(kicad_pcb
	(version 20260206)
	(generator "pcbnew")
	(generator_version "10.0")
	(general
		(thickness 1.6)
		(legacy_teardrops no)
	)
	(paper "A4")
	(layers
		(0 "F.Cu" signal "TOP")
		(4 "In1.Cu" signal "GND")
		(6 "In2.Cu" signal "GND1")
		(2 "B.Cu" signal "BOTTOM")
		(9 "F.Adhes" user "F.Adhesive")
		(11 "B.Adhes" user "B.Adhesive")
		(13 "F.Paste" user "Package Geometry/Pastemask Top")
		(15 "B.Paste" user "Package Geometry/Pastemask Bottom")
		(5 "F.SilkS" user "Ref Des/Silkscreen Top")
		(7 "B.SilkS" user "Ref Des/Silkscreen Bottom")
		(1 "F.Mask" user "Board Geometry/Soldermask Top")
		(3 "B.Mask" user "Board Geometry/Soldermask Bottom")
		(17 "Dwgs.User" user "User.Drawings")
		(19 "Cmts.User" user "User.Comments")
		(21 "Eco1.User" user "User.Eco1")
		(23 "Eco2.User" user "User.Eco2")
		(25 "Edge.Cuts" user "Board Geometry/Outline")
		(27 "Margin" user)
		(31 "F.CrtYd" user "Package Geometry/Place Bound Top")
		(29 "B.CrtYd" user "Package Geometry/Place Bound Bottom")
		(35 "F.Fab" user "Ref Des/Assembly Top")
		(33 "B.Fab" user "Ref Des/Assembly Bottom")
	)
	(setup
		(pad_to_mask_clearance 0)
		(allow_soldermask_bridges_in_footprints no)
		(tenting
			(front yes)
			(back yes)
		)
		(covering
			(front no)
			(back no)
		)
		(plugging
			(front no)
			(back no)
		)
		(capping no)
		(filling no)
		(pcbplotparams
			(layerselection 0x00000000_00000000_55555555_5755f5ff)
			(plot_on_all_layers_selection 0x00000000_00000000_00000000_00000000)
			(disableapertmacros no)
			(usegerberextensions no)
			(usegerberattributes yes)
			(usegerberadvancedattributes yes)
			(creategerberjobfile yes)
			(dashed_line_dash_ratio 12)
			(dashed_line_gap_ratio 3)
			(svgprecision 4)
			(plotframeref no)
			(mode 1)
			(useauxorigin no)
			(pdf_front_fp_property_popups yes)
			(pdf_back_fp_property_popups yes)
			(pdf_metadata yes)
			(pdf_single_document no)
			(dxfpolygonmode yes)
			(dxfimperialunits yes)
			(dxfusepcbnewfont yes)
			(psnegative no)
			(psa4output no)
			(plot_black_and_white yes)
			(sketchpadsonfab no)
			(plotpadnumbers no)
			(hidednponfab no)
			(sketchdnponfab yes)
			(crossoutdnponfab yes)
			(subtractmaskfromsilk no)
			(outputformat 1)
			(mirror no)
			(drillshape 1)
			(scaleselection 1)
			(outputdirectory "")
		)
	)
	(footprint ""
		(layer "F.Cu")
		(at 32.004 -29.591)
		(property "Reference" "U7"
			(at -3.302 0.02667 0)
			(unlocked yes)
			(layer "F.SilkS")
			(effects
				(font
					(size 0.7874 0.5842)
					(thickness 0.1524)
				)
				(justify left)
			)
		)
		(property "Value" ""
			(at 0 0 0)
			(layer "F.Fab")
			(effects
				(font
					(size 1.27 1.27)
				)
			)
		)
		(duplicate_pad_numbers_are_jumpers no)
		(fp_line
			(start -1.738884 -1.549908)
			(end -1.738884 1.549908)
			(stroke
				(width 0.1524)
				(type default)
			)
			(layer "F.SilkS")
		)
		(fp_line
			(start -1.738884 1.549908)
			(end 1.738884 1.549908)
			(stroke
				(width 0.1524)
				(type default)
			)
			(layer "F.SilkS")
		)
		(fp_line
			(start -0.635508 -1.549908)
			(end -1.738884 -1.549908)
			(stroke
				(width 0.1524)
				(type default)
			)
			(layer "F.SilkS")
		)
		(fp_line
			(start 0 -0.9144)
			(end -0.635508 -1.549908)
			(stroke
				(width 0.1524)
				(type default)
			)
			(layer "F.SilkS")
		)
		(fp_line
			(start 0.635508 -1.549908)
			(end 0 -0.9144)
			(stroke
				(width 0.1524)
				(type default)
			)
			(layer "F.SilkS")
		)
		(fp_line
			(start 1.738884 -1.549908)
			(end 0.635508 -1.549908)
			(stroke
				(width 0.1524)
				(type default)
			)
			(layer "F.SilkS")
		)
		(fp_line
			(start 1.738884 1.549908)
			(end 1.738884 -1.549908)
			(stroke
				(width 0.1524)
				(type default)
			)
			(layer "F.SilkS")
		)
		(fp_poly
			(pts
				(xy -2.445766 -1.211326) (xy -1.923034 -0.94996) (xy -2.445766 -0.688594)
			)
			(stroke
				(width 0)
				(type default)
			)
			(fill yes)
			(layer "F.SilkS")
		)
		(fp_line
			(start -0.849884 -1.549908)
			(end -0.849884 1.549908)
			(stroke
				(width 0.1)
				(type default)
			)
			(layer "F.Fab")
		)
		(fp_line
			(start -0.849884 1.549908)
			(end 0.849884 1.549908)
			(stroke
				(width 0.1)
				(type default)
			)
			(layer "F.Fab")
		)
		(fp_line
			(start 0.849884 -1.549908)
			(end -0.849884 -1.549908)
			(stroke
				(width 0.1)
				(type default)
			)
			(layer "F.Fab")
		)
		(fp_line
			(start 0.849884 1.549908)
			(end 0.849884 -1.549908)
			(stroke
				(width 0.1)
				(type default)
			)
			(layer "F.Fab")
		)
		(fp_poly
			(pts
				(xy -2.445766 -1.211326) (xy -1.923034 -0.94996) (xy -2.445766 -0.688594)
			)
			(stroke
				(width 0)
				(type default)
			)
			(fill yes)
			(layer "F.Fab")
		)
		(pad "1" smd rect
			(at -1.124966 -0.94996 90)
			(size 0.6096 0.9652)
			(layers "F.Cu" "F.Mask" "F.Paste")
			(net "P5V_STBY")
		)
		(pad "2" smd rect
			(at -1.124966 0 90)
			(size 0.6096 0.9652)
			(layers "F.Cu" "F.Mask" "F.Paste")
			(net "GND")
		)
		(pad "3" smd rect
			(at -1.124966 0.94996 90)
			(size 0.6096 0.9652)
			(layers "F.Cu" "F.Mask" "F.Paste")
			(net "NCO380_EN")
		)
		(pad "4" smd rect
			(at 1.124966 0.94996 90)
			(size 0.6096 0.9652)
			(layers "F.Cu" "F.Mask" "F.Paste")
			(net "NCP380_FLT_N")
		)
		(pad "5" smd rect
			(at 1.124966 0 90)
			(size 0.6096 0.9652)
			(layers "F.Cu" "F.Mask" "F.Paste")
			(net "NCP380_ILIM")
		)
		(pad "6" smd rect
			(at 1.124966 -0.94996 90)
			(size 0.6096 0.9652)
			(layers "F.Cu" "F.Mask" "F.Paste")
			(net "P5V_STBY_DEBUG")
		)
	)
	(footprint ""
		(layer "F.Cu")
		(at 24.100028 -20.830032)
		(property "Reference" "J2"
			(at -2.8956 -5.02793 0)
			(unlocked yes)
			(layer "F.SilkS")
			(effects
				(font
					(size 0.7874 0.5842)
					(thickness 0.1524)
				)
				(justify left)
			)
		)
		(property "Value" ""
			(at 0 0 0)
			(layer "F.Fab")
			(effects
				(font
					(size 1.27 1.27)
				)
			)
		)
		(duplicate_pad_numbers_are_jumpers no)
		(fp_line
			(start -2.810002 -4.219956)
			(end -2.810002 22.029928)
			(stroke
				(width 0.1524)
				(type default)
			)
			(layer "F.SilkS")
		)
		(fp_line
			(start -2.810002 22.029928)
			(end -2.659888 22.029928)
			(stroke
				(width 0.1524)
				(type default)
			)
			(layer "F.SilkS")
		)
		(fp_line
			(start -2.659888 -3.720084)
			(end 4.459986 -3.720084)
			(stroke
				(width 0.1524)
				(type default)
			)
			(layer "F.SilkS")
		)
		(fp_line
			(start -2.659888 21.480018)
			(end 4.459986 21.480018)
			(stroke
				(width 0.1524)
				(type default)
			)
			(layer "F.SilkS")
		)
		(fp_line
			(start -2.659888 22.029928)
			(end -2.659888 -3.720084)
			(stroke
				(width 0.1524)
				(type default)
			)
			(layer "F.SilkS")
		)
		(fp_line
			(start 4.459986 -3.720084)
			(end 4.459986 22.029928)
			(stroke
				(width 0.1524)
				(type default)
			)
			(layer "F.SilkS")
		)
		(fp_line
			(start 4.459986 22.029928)
			(end -2.659888 22.029928)
			(stroke
				(width 0.1524)
				(type default)
			)
			(layer "F.SilkS")
		)
		(fp_line
			(start 4.459986 22.029928)
			(end 4.6101 22.029928)
			(stroke
				(width 0.1524)
				(type default)
			)
			(layer "F.SilkS")
		)
		(fp_line
			(start 4.6101 -4.219956)
			(end -2.810002 -4.219956)
			(stroke
				(width 0.1524)
				(type default)
			)
			(layer "F.SilkS")
		)
		(fp_line
			(start 4.6101 22.029928)
			(end 4.6101 -4.219956)
			(stroke
				(width 0.1524)
				(type default)
			)
			(layer "F.SilkS")
		)
		(fp_poly
			(pts
				(xy 0.413004 -5.377942) (xy -0.602996 -5.377942) (xy -0.094996 -4.361942)
			)
			(stroke
				(width 0)
				(type default)
			)
			(fill yes)
			(layer "F.SilkS")
		)
		(fp_line
			(start -2.659888 -3.720084)
			(end -2.659888 22.029928)
			(stroke
				(width 0.1)
				(type default)
			)
			(layer "F.Fab")
		)
		(fp_line
			(start -2.659888 22.029928)
			(end 4.459986 22.029928)
			(stroke
				(width 0.1)
				(type default)
			)
			(layer "F.Fab")
		)
		(fp_line
			(start 4.459986 -3.720084)
			(end -2.659888 -3.720084)
			(stroke
				(width 0.1)
				(type default)
			)
			(layer "F.Fab")
		)
		(fp_line
			(start 4.459986 22.029928)
			(end 4.459986 -3.720084)
			(stroke
				(width 0.1)
				(type default)
			)
			(layer "F.Fab")
		)
		(fp_poly
			(pts
				(xy -3.953002 -0.508) (xy -3.953002 0.508) (xy -2.937002 0)
			)
			(stroke
				(width 0)
				(type default)
			)
			(fill yes)
			(layer "F.Fab")
		)
		(pad "1" thru_hole rect
			(at 0 0)
			(size 1.1176 1.1176)
			(drill 0.7112)
			(layers "*.Cu" "*.Mask")
			(remove_unused_layers no)
			(net "P5V_STBY_DEBUG")
			(clearance 0.0508)
			(thermal_gap 0.0508)
			(padstack
				(mode front_inner_back)
				(layer "Inner"
					(shape circle)
					(size 1.1176 1.1176)
					(clearance 0.0508)
				)
				(layer "B.Cu"
					(shape rect)
					(size 1.1176 1.1176)
					(clearance 0.0508)
				)
			)
		)
		(pad "2" thru_hole circle
			(at 0 2.500122)
			(size 1.1176 1.1176)
			(drill 0.7112)
			(layers "*.Cu" "*.Mask")
			(remove_unused_layers no)
			(net "USB2_DEBUG_DN")
			(clearance 0.0508)
			(thermal_gap 0.0508)
		)
		(pad "3" thru_hole circle
			(at 0 4.500118)
			(size 1.1176 1.1176)
			(drill 0.7112)
			(layers "*.Cu" "*.Mask")
			(remove_unused_layers no)
			(net "USB2_DEBUG_DP")
			(clearance 0.0508)
			(thermal_gap 0.0508)
		)
		(pad "4" thru_hole circle
			(at 0 6.999986)
			(size 1.1176 1.1176)
			(drill 0.7112)
			(layers "*.Cu" "*.Mask")
			(remove_unused_layers no)
			(net "GND")
			(clearance 0.0508)
			(thermal_gap 0.0508)
		)
		(pad "5" thru_hole circle
			(at 1.800098 7.500112)
			(size 1.1176 1.1176)
			(drill 0.7112)
			(layers "*.Cu" "*.Mask")
			(remove_unused_layers no)
			(net "SMB_IO_DEBUG_CARD_SCL")
			(clearance 0.0508)
			(thermal_gap 0.0508)
		)
		(pad "6" thru_hole circle
			(at 1.800098 5.500116)
			(size 1.1176 1.1176)
			(drill 0.7112)
			(layers "*.Cu" "*.Mask")
			(remove_unused_layers no)
			(net "SMB_IO_DEBUG_CARD_SDA")
			(clearance 0.0508)
			(thermal_gap 0.0508)
		)
		(pad "7" thru_hole circle
			(at 1.800098 3.50012)
			(size 1.1176 1.1176)
			(drill 0.7112)
			(layers "*.Cu" "*.Mask")
			(remove_unused_layers no)
			(net "PRSNT_DBV2_USB")
			(clearance 0.0508)
			(thermal_gap 0.0508)
		)
		(pad "8" thru_hole circle
			(at 1.800098 1.500124)
			(size 1.1176 1.1176)
			(drill 0.7112)
			(layers "*.Cu" "*.Mask")
			(remove_unused_layers no)
			(net "UART_DEBUG_R_TX")
			(clearance 0.0508)
			(thermal_gap 0.0508)
		)
		(pad "9" thru_hole circle
			(at 1.800098 -0.499872)
			(size 1.1176 1.1176)
			(drill 0.7112)
			(layers "*.Cu" "*.Mask")
			(remove_unused_layers no)
			(net "UART_DEBUG_R_RX")
			(clearance 0.0508)
			(thermal_gap 0.0508)
		)
		(pad "G1" thru_hole oval
			(at -1.810004 8.830056)
			(size 1.3208 2.6162)
			(drill oval 0.8128 2.1082)
			(layers "*.Cu" "*.Mask")
			(remove_unused_layers no)
			(net "GND")
			(clearance 0.127)
			(thermal_gap 0.127)
		)
		(pad "G2" thru_hole oval
			(at 3.610102 8.830056)
			(size 1.3208 1.905)
			(drill oval 0.8128 1.4224)
			(layers "*.Cu" "*.Mask")
			(remove_unused_layers no)
			(net "GND")
			(clearance 0.127)
			(thermal_gap 0.127)
		)
		(pad "G3" thru_hole oval
			(at -1.810004 -1.869948)
			(size 1.3208 1.905)
			(drill oval 0.8128 1.4224)
			(layers "*.Cu" "*.Mask")
			(remove_unused_layers no)
			(net "GND")
			(clearance 0.127)
			(thermal_gap 0.127)
		)
		(pad "G4" thru_hole oval
			(at 3.610102 -1.869948)
			(size 1.3208 2.6162)
			(drill oval 0.8128 2.1082)
			(layers "*.Cu" "*.Mask")
			(remove_unused_layers no)
			(net "GND")
			(clearance 0.127)
			(thermal_gap 0.127)
		)
	)
	(footprint ""
		(layer "F.Cu")
		(at 1.397 -32.385)
		(property "Reference" "ME1"
			(at 0 0 0)
			(layer "F.SilkS")
			(hide yes)
			(effects
				(font
					(size 1.27 1.27)
				)
			)
		)
		(property "Value" ""
			(at 0 0 0)
			(layer "F.Fab")
			(effects
				(font
					(size 1.27 1.27)
				)
			)
		)
		(duplicate_pad_numbers_are_jumpers no)
		(fp_poly
			(pts
				(xy 2.034794 -0.209296) (xy 2.03327 -0.20955) (xy 2.023872 -0.20955) (xy 2.021332 -0.209804) (xy 2.020316 -0.209804)
				(xy 2.013204 -0.210312) (xy 2.011172 -0.210312) (xy 2.01041 -0.210312) (xy 2.008124 -0.210566) (xy 2.002028 -0.21082)
				(xy 2.001012 -0.21082) (xy 1.99898 -0.211074) (xy 1.9812 -0.21209) (xy 1.96469 -0.214884) (xy 1.903984 -0.225298)
				(xy 1.876298 -0.235458) (xy 1.839976 -0.248666) (xy 1.837944 -0.249428) (xy 1.813814 -0.264414)
				(xy 1.800606 -0.272796) (xy 1.79959 -0.273304) (xy 1.79832 -0.27432) (xy 1.795526 -0.275844) (xy 1.791462 -0.278384)
				(xy 1.786382 -0.281686) (xy 1.782572 -0.283972) (xy 1.780286 -0.286258) (xy 1.765808 -0.300736)
				(xy 1.749044 -0.317246) (xy 1.737614 -0.328676) (xy 1.714754 -0.364744) (xy 1.70307 -0.382778) (xy 1.69926 -0.392684)
				(xy 1.686814 -0.424688) (xy 1.681988 -0.437134) (xy 1.678432 -0.446278) (xy 1.678432 -0.446532)
				(xy 1.676146 -0.457708) (xy 1.675384 -0.461518) (xy 1.6637 -0.518414) (xy 1.662176 -0.538734) (xy 1.658366 -0.599186)
				(xy 1.662176 -0.687578) (xy 1.6637 -0.69723) (xy 1.675384 -0.783336) (xy 1.676146 -0.787908) (xy 1.678432 -0.800862)
				(xy 1.678432 -0.80137) (xy 1.681988 -0.821436) (xy 1.686814 -0.848868) (xy 1.69926 -0.919988) (xy 1.70307 -0.941578)
				(xy 1.714754 -1.007618) (xy 1.737614 -1.138682) (xy 1.749044 -1.203452) (xy 1.765808 -1.29794) (xy 1.780286 -1.380998)
				(xy 1.782572 -1.394206) (xy 1.786382 -1.415796) (xy 1.791462 -1.445006) (xy 1.795526 -1.46812) (xy 1.79832 -1.483614)
				(xy 1.79959 -1.49098) (xy 1.800606 -1.491488) (xy 2.12852 -1.491488) (xy 2.129536 -1.49098) (xy 2.12852 -1.486154)
				(xy 2.128266 -1.483868) (xy 2.125726 -1.468882) (xy 2.121662 -1.447038) (xy 2.116836 -1.418844)
				(xy 2.115312 -1.410716) (xy 2.113534 -1.40081) (xy 2.110994 -1.385316) (xy 2.097024 -1.305814) (xy 2.08915 -1.26111)
				(xy 2.087118 -1.24968) (xy 2.083816 -1.230884) (xy 2.081022 -1.215136) (xy 2.058162 -1.085088) (xy 2.053082 -1.055624)
				(xy 2.050796 -1.043178) (xy 2.048002 -1.027176) (xy 2.041652 -0.990854) (xy 2.03708 -0.96393) (xy 2.034794 -0.951992)
				(xy 2.03327 -0.943102) (xy 2.023872 -0.888492) (xy 2.021332 -0.874776) (xy 2.020316 -0.86868) (xy 2.01676 -0.848868)
				(xy 2.013204 -0.829056) (xy 2.011172 -0.81661) (xy 2.01041 -0.812292) (xy 2.008124 -0.797306) (xy 2.002028 -0.75311)
				(xy 2.001012 -0.738124) (xy 1.99898 -0.701802) (xy 2.001012 -0.658114) (xy 2.002028 -0.653288) (xy 2.008124 -0.621284)
				(xy 2.01041 -0.615696) (xy 2.011172 -0.613918) (xy 2.013204 -0.60833) (xy 2.01676 -0.599694) (xy 2.020316 -0.590804)
				(xy 2.021332 -0.58928) (xy 2.023872 -0.585724) (xy 2.03327 -0.571754) (xy 2.034794 -0.569722) (xy 2.03708 -0.566674)
				(xy 2.041652 -0.562356) (xy 2.048002 -0.556768) (xy 2.050796 -0.554228) (xy 2.053082 -0.55245) (xy 2.058162 -0.547878)
				(xy 2.081022 -0.53594) (xy 2.083816 -0.534416) (xy 2.087118 -0.5334) (xy 2.08915 -0.532892) (xy 2.097024 -0.530606)
				(xy 2.110994 -0.526542) (xy 2.113534 -0.52578) (xy 2.115312 -0.525526) (xy 2.116836 -0.525272) (xy 2.121662 -0.524764)
				(xy 2.125726 -0.524256) (xy 2.128266 -0.523748) (xy 2.12852 -0.523748) (xy 2.129536 -0.523748) (xy 2.14757 -0.521208)
				(xy 2.155952 -0.521716) (xy 2.219198 -0.523748) (xy 2.22123 -0.523748) (xy 2.255012 -0.531114) (xy 2.27584 -0.538734)
				(xy 2.286508 -0.542798) (xy 2.31521 -0.559308) (xy 2.324608 -0.566928) (xy 2.337562 -0.57785) (xy 2.338832 -0.578866)
				(xy 2.341626 -0.581152) (xy 2.342134 -0.581914) (xy 2.345436 -0.585724) (xy 2.34569 -0.585978) (xy 2.349754 -0.590804)
				(xy 2.350516 -0.591566) (xy 2.351786 -0.59309) (xy 2.35204 -0.593344) (xy 2.365248 -0.608838) (xy 2.367788 -0.613156)
				(xy 2.38633 -0.64262) (xy 2.401062 -0.674878) (xy 2.404872 -0.683006) (xy 2.42062 -0.73025) (xy 2.433574 -0.78486)
				(xy 2.436622 -0.799846) (xy 2.437384 -0.804926) (xy 2.437384 -0.80518) (xy 2.438654 -0.812546) (xy 2.441448 -0.827786)
				(xy 2.441956 -0.83058) (xy 2.445258 -0.849884) (xy 2.450338 -0.878332) (xy 2.45618 -0.912114) (xy 2.470404 -0.992378)
				(xy 2.486406 -1.084072) (xy 2.51968 -1.274318) (xy 2.533142 -1.35128) (xy 2.534666 -1.359154) (xy 2.546604 -1.428242)
				(xy 2.551176 -1.454658) (xy 2.554732 -1.474724) (xy 2.557018 -1.48717) (xy 2.55778 -1.491488) (xy 2.887726 -1.491488)
				(xy 2.887472 -1.487932) (xy 2.884424 -1.470406) (xy 2.88417 -1.469644) (xy 2.878582 -1.43764) (xy 2.870708 -1.392936)
				(xy 2.86639 -1.368298) (xy 2.861056 -1.337564) (xy 2.849626 -1.272794) (xy 2.836926 -1.200404) (xy 2.836418 -1.197864)
				(xy 2.808478 -1.038098) (xy 2.79781 -0.9779) (xy 2.777744 -0.8636) (xy 2.753614 -0.726694) (xy 2.74701 -0.689102)
				(xy 2.718562 -0.52705) (xy 2.705862 -0.454406) (xy 2.694432 -0.389636) (xy 2.68478 -0.334264) (xy 2.676906 -0.289814)
				(xy 2.671318 -0.257556) (xy 2.668016 -0.239268) (xy 2.667254 -0.235712) (xy 2.337562 -0.235712)
				(xy 2.338832 -0.243332) (xy 2.341626 -0.25908) (xy 2.342134 -0.262128) (xy 2.345436 -0.282194) (xy 2.34569 -0.282702)
				(xy 2.349754 -0.306324) (xy 2.350516 -0.310388) (xy 2.351786 -0.318516) (xy 2.35204 -0.319278) (xy 2.351786 -0.319278)
				(xy 2.350516 -0.318008) (xy 2.349754 -0.3175) (xy 2.34569 -0.313944) (xy 2.345436 -0.313944) (xy 2.342134 -0.31115)
				(xy 2.341626 -0.310896) (xy 2.338832 -0.30861) (xy 2.337562 -0.307594) (xy 2.324608 -0.297688) (xy 2.31521 -0.291846)
				(xy 2.286508 -0.274066) (xy 2.27584 -0.267462) (xy 2.255012 -0.258064) (xy 2.22123 -0.242824) (xy 2.219198 -0.242062)
				(xy 2.155952 -0.223012) (xy 2.14757 -0.221488) (xy 2.129536 -0.218694) (xy 2.12852 -0.21844) (xy 2.128266 -0.21844)
				(xy 2.125726 -0.217932) (xy 2.121662 -0.217424) (xy 2.116836 -0.216408) (xy 2.115312 -0.216408)
				(xy 2.113534 -0.2159) (xy 2.110994 -0.215646) (xy 2.097024 -0.21336) (xy 2.08915 -0.21209) (xy 2.087118 -0.211582)
				(xy 2.083816 -0.211582) (xy 2.081022 -0.211328) (xy 2.058162 -0.210058) (xy 2.053082 -0.209804)
				(xy 2.050796 -0.20955) (xy 2.048002 -0.20955) (xy 2.041652 -0.209296)
			)
			(stroke
				(width 0)
				(type default)
			)
			(fill yes)
			(layer "F.SilkS")
		)
		(fp_poly
			(pts
				(xy 4.131818 -0.235712) (xy 4.130802 -0.236728) (xy 4.131818 -0.241046) (xy 4.133088 -0.249682)
				(xy 4.138168 -0.277622) (xy 4.145026 -0.316484) (xy 4.14528 -0.318008) (xy 4.154424 -0.370078) (xy 4.165092 -0.4318)
				(xy 4.171188 -0.466344) (xy 4.177538 -0.501904) (xy 4.191 -0.578866) (xy 4.207256 -0.672084) (xy 4.220464 -0.746506)
				(xy 4.281424 -1.094232) (xy 4.295394 -1.174496) (xy 4.295902 -1.176274) (xy 4.308602 -1.249426)
				(xy 4.32054 -1.31699) (xy 4.3307 -1.375664) (xy 4.339082 -1.423924) (xy 4.345686 -1.4605) (xy 4.34975 -1.483614)
				(xy 4.35102 -1.491488) (xy 4.677918 -1.491488) (xy 4.679696 -1.491488) (xy 4.680712 -1.491234) (xy 4.68122 -1.491234)
				(xy 4.680712 -1.487932) (xy 4.679696 -1.483106) (xy 4.677918 -1.472184) (xy 4.67741 -1.470406) (xy 4.673854 -1.449578)
				(xy 4.66979 -1.427226) (xy 4.66979 -1.425956) (xy 4.668774 -1.421384) (xy 4.666996 -1.411478) (xy 4.666488 -1.407922)
				(xy 4.666996 -1.408176) (xy 4.668774 -1.409954) (xy 4.66979 -1.410716) (xy 4.673854 -1.414018) (xy 4.67741 -1.417066)
				(xy 4.677918 -1.41732) (xy 4.679696 -1.418844) (xy 4.680712 -1.419606) (xy 4.68122 -1.41986) (xy 4.694428 -1.42875)
				(xy 4.722368 -1.448054) (xy 4.72567 -1.450086) (xy 4.752848 -1.463802) (xy 4.779772 -1.477518) (xy 4.821428 -1.491996)
				(xy 4.840986 -1.4986) (xy 4.888738 -1.50876) (xy 4.8895 -1.509014) (xy 4.891532 -1.509268) (xy 4.894326 -1.509776)
				(xy 4.895088 -1.51003) (xy 4.896866 -1.510284) (xy 4.89966 -1.511046) (xy 4.908042 -1.512824) (xy 4.911598 -1.513078)
				(xy 4.919218 -1.513586) (xy 4.925314 -1.514094) (xy 4.926584 -1.514094) (xy 4.952492 -1.515872)
				(xy 4.959604 -1.51638) (xy 4.975098 -1.517396) (xy 4.975606 -1.517396) (xy 4.979924 -1.517904) (xy 4.989576 -1.517142)
				(xy 4.993132 -1.516888) (xy 4.993386 -1.516888) (xy 4.995418 -1.516634) (xy 5.000244 -1.51638) (xy 5.004308 -1.516126)
				(xy 5.006848 -1.515872) (xy 5.008118 -1.515872) (xy 5.00888 -1.515872) (xy 5.01142 -1.515618) (xy 5.015484 -1.515364)
				(xy 5.018024 -1.51511) (xy 5.019294 -1.51511) (xy 5.064506 -1.512062) (xy 5.084826 -1.50749) (xy 5.128768 -1.497076)
				(xy 5.137912 -1.495044) (xy 5.167376 -1.48209) (xy 5.197348 -1.468882) (xy 5.200396 -1.467612) (xy 5.215382 -1.456436)
				(xy 5.219446 -1.453388) (xy 5.221224 -1.452118) (xy 5.224526 -1.449832) (xy 5.228844 -1.44653) (xy 5.234178 -1.44272)
				(xy 5.247894 -1.43256) (xy 5.252212 -1.429512) (xy 5.263896 -1.415796) (xy 5.281168 -1.395984) (xy 5.293614 -1.381506)
				(xy 5.29844 -1.372616) (xy 5.314442 -1.343406) (xy 5.324856 -1.324102) (xy 5.327904 -1.314196) (xy 5.333492 -1.297178)
				(xy 5.33781 -1.283462) (xy 5.341112 -1.273556) (xy 5.34289 -1.267968) (xy 5.343144 -1.266952) (xy 5.343398 -1.266952)
				(xy 5.343906 -1.264666) (xy 5.346192 -1.258316) (xy 5.346192 -1.257808) (xy 5.35305 -1.21412) (xy 5.357876 -1.182624)
				(xy 5.359908 -1.099566) (xy 5.357876 -1.071372) (xy 5.35305 -1.00838) (xy 5.346192 -0.960882) (xy 5.346192 -0.96012)
				(xy 5.343906 -0.947928) (xy 5.343398 -0.94361) (xy 5.343144 -0.94361) (xy 5.34289 -0.941578) (xy 5.341112 -0.931418)
				(xy 5.33781 -0.91313) (xy 5.333492 -0.887984) (xy 5.327904 -0.856742) (xy 5.324856 -0.838708) (xy 5.314442 -0.779272)
				(xy 5.29844 -0.688086) (xy 5.293614 -0.6604) (xy 5.281168 -0.589788) (xy 5.263896 -0.491236) (xy 5.252212 -0.424434)
				(xy 5.247894 -0.399796) (xy 5.234178 -0.32258) (xy 5.228844 -0.291338) (xy 5.224526 -0.266192) (xy 5.221224 -0.247904)
				(xy 5.219446 -0.237744) (xy 5.215382 -0.235712) (xy 4.888738 -0.235712) (xy 4.8895 -0.24003) (xy 4.891532 -0.252476)
				(xy 4.894326 -0.267208) (xy 4.895088 -0.272288) (xy 4.896866 -0.282194) (xy 4.89966 -0.29845) (xy 4.908042 -0.345694)
				(xy 4.911598 -0.366776) (xy 4.919218 -0.40894) (xy 4.925314 -0.444246) (xy 4.926584 -0.450596) (xy 4.952492 -0.597916)
				(xy 4.959604 -0.63881) (xy 4.975098 -0.726948) (xy 4.975606 -0.729234) (xy 4.979924 -0.755142) (xy 4.989576 -0.808736)
				(xy 4.993132 -0.830072) (xy 4.993386 -0.830326) (xy 4.995418 -0.842264) (xy 5.000244 -0.870458)
				(xy 5.004308 -0.892302) (xy 5.006848 -0.907288) (xy 5.006848 -0.907542) (xy 5.008118 -0.9144) (xy 5.008118 -0.914908)
				(xy 5.00888 -0.920242) (xy 5.01142 -0.935482) (xy 5.015484 -0.970534) (xy 5.018024 -0.992124) (xy 5.019294 -1.040892)
				(xy 5.018024 -1.055116) (xy 5.015484 -1.082294) (xy 5.01142 -1.09855) (xy 5.00888 -1.108202) (xy 5.008118 -1.112012)
				(xy 5.008118 -1.112266) (xy 5.006848 -1.117092) (xy 5.004308 -1.12268) (xy 5.000244 -1.130808) (xy 4.995418 -1.140968)
				(xy 4.993386 -1.145286) (xy 4.993132 -1.145286) (xy 4.989576 -1.150112) (xy 4.979924 -1.161542)
				(xy 4.975606 -1.16713) (xy 4.975098 -1.167638) (xy 4.959604 -1.179322) (xy 4.952492 -1.184402) (xy 4.926584 -1.195832)
				(xy 4.925314 -1.19634) (xy 4.919218 -1.197864) (xy 4.911598 -1.199642) (xy 4.908042 -1.200404) (xy 4.89966 -1.202436)
				(xy 4.896866 -1.202944) (xy 4.895088 -1.203452) (xy 4.894326 -1.203706) (xy 4.891532 -1.203706)
				(xy 4.8895 -1.203706) (xy 4.888738 -1.203706) (xy 4.840986 -1.205484) (xy 4.821428 -1.206246) (xy 4.779772 -1.198118)
				(xy 4.752848 -1.193038) (xy 4.72567 -1.1811) (xy 4.722368 -1.17983) (xy 4.694428 -1.161288) (xy 4.68122 -1.149096)
				(xy 4.680712 -1.148588) (xy 4.679696 -1.147826) (xy 4.677918 -1.146048) (xy 4.67741 -1.145794) (xy 4.673854 -1.142238)
				(xy 4.66979 -1.138682) (xy 4.66979 -1.138428) (xy 4.668774 -1.137666) (xy 4.666996 -1.13538) (xy 4.666488 -1.134618)
				(xy 4.659376 -1.125728) (xy 4.645914 -1.107948) (xy 4.629658 -1.078738) (xy 4.625848 -1.07188) (xy 4.608322 -1.029208)
				(xy 4.59359 -0.979424) (xy 4.59105 -0.967486) (xy 4.581398 -0.922274) (xy 4.580636 -0.917702) (xy 4.578604 -0.905256)
				(xy 4.575048 -0.88519) (xy 4.570476 -0.859028) (xy 4.558284 -0.789686) (xy 4.546854 -0.725678) (xy 4.543298 -0.705104)
				(xy 4.510024 -0.514858) (xy 4.493768 -0.423418) (xy 4.479798 -0.3429) (xy 4.473702 -0.309118) (xy 4.468622 -0.28067)
				(xy 4.464812 -0.258572) (xy 4.462272 -0.243332) (xy 4.461002 -0.23622) (xy 4.459986 -0.235712)
			)
			(stroke
				(width 0)
				(type default)
			)
			(fill yes)
			(layer "F.SilkS")
		)
		(fp_poly
			(pts
				(xy 5.909056 -0.209296) (xy 5.870702 -0.21336) (xy 5.859526 -0.214376) (xy 5.855462 -0.214884) (xy 5.852922 -0.215138)
				(xy 5.846572 -0.215646) (xy 5.837428 -0.216662) (xy 5.827014 -0.220218) (xy 5.8166 -0.223774) (xy 5.80771 -0.226822)
				(xy 5.801106 -0.228854) (xy 5.79882 -0.22987) (xy 5.789676 -0.232918) (xy 5.775706 -0.23749) (xy 5.7658 -0.244094)
				(xy 5.74421 -0.258064) (xy 5.743194 -0.258826) (xy 5.739892 -0.261112) (xy 5.73532 -0.263906) (xy 5.734558 -0.264414)
				(xy 5.727954 -0.268732) (xy 5.724398 -0.271018) (xy 5.711444 -0.285496) (xy 5.71119 -0.285496) (xy 5.693664 -0.305054)
				(xy 5.69214 -0.306578) (xy 5.684012 -0.315976) (xy 5.67309 -0.336296) (xy 5.656326 -0.367792) (xy 5.654802 -0.371094)
				(xy 5.649722 -0.389382) (xy 5.644642 -0.408432) (xy 5.64134 -0.420624) (xy 5.64007 -0.424942) (xy 5.639054 -0.42926)
				(xy 5.637276 -0.43561) (xy 5.632196 -0.508) (xy 5.637276 -0.5588) (xy 5.639054 -0.576072) (xy 5.64007 -0.587502)
				(xy 5.64134 -0.594106) (xy 5.644642 -0.612902) (xy 5.649722 -0.642112) (xy 5.654802 -0.670306) (xy 5.656326 -0.680212)
				(xy 5.67309 -0.775208) (xy 5.684012 -0.836676) (xy 5.69214 -0.88392) (xy 5.693664 -0.891794) (xy 5.71119 -0.992886)
				(xy 5.711444 -0.99314) (xy 5.724398 -1.067308) (xy 5.727954 -1.087882) (xy 5.734558 -1.125728) (xy 5.73532 -1.12903)
				(xy 5.739892 -1.154938) (xy 5.743194 -1.173988) (xy 5.74421 -1.180592) (xy 5.533644 -1.180592) (xy 5.536184 -1.1938)
				(xy 5.54228 -1.229106) (xy 5.542788 -1.2319) (xy 5.550916 -1.27889) (xy 5.561076 -1.33604) (xy 5.566664 -1.367536)
				(xy 5.570982 -1.39319) (xy 5.579872 -1.442974) (xy 5.586222 -1.47828) (xy 5.588508 -1.491488) (xy 5.79882 -1.491488)
				(xy 5.801106 -1.505458) (xy 5.80771 -1.542034) (xy 5.8166 -1.593596) (xy 5.827014 -1.652778) (xy 5.837428 -1.712214)
				(xy 5.846572 -1.763776) (xy 5.852922 -1.800606) (xy 5.855462 -1.814322) (xy 5.859526 -1.8161) (xy 5.870702 -1.821434)
				(xy 5.909056 -1.83896) (xy 5.911596 -1.84023) (xy 5.969 -1.866646) (xy 5.980684 -1.87198) (xy 5.98551 -1.874266)
				(xy 5.986018 -1.874266) (xy 5.986018 -1.87452) (xy 5.98678 -1.874774) (xy 5.989828 -1.876044) (xy 5.993892 -1.878076)
				(xy 5.996178 -1.879092) (xy 5.999734 -1.880616) (xy 6.013958 -1.88722) (xy 6.030214 -1.894586) (xy 6.03504 -1.896872)
				(xy 6.04647 -1.902206) (xy 6.058662 -1.907794) (xy 6.060694 -1.90881) (xy 6.066282 -1.91135) (xy 6.0706 -1.913382)
				(xy 6.073394 -1.914652) (xy 6.07441 -1.91516) (xy 6.081522 -1.918208) (xy 6.087364 -1.921002) (xy 6.10108 -1.927098)
				(xy 6.121654 -1.93675) (xy 6.124194 -1.93802) (xy 6.12521 -1.938528) (xy 6.12902 -1.940052) (xy 6.129782 -1.94056)
				(xy 6.132576 -1.94183) (xy 6.136894 -1.943608) (xy 6.141974 -1.946148) (xy 6.142228 -1.946402) (xy 6.156198 -1.952498)
				(xy 6.158484 -1.953768) (xy 6.170422 -1.959102) (xy 6.171692 -1.959864) (xy 6.17601 -1.961642) (xy 6.178042 -1.962658)
				(xy 6.179312 -1.963166) (xy 6.182614 -1.96469) (xy 6.18744 -1.966976) (xy 6.194806 -1.970278) (xy 6.199124 -1.97231)
				(xy 6.20141 -1.973326) (xy 6.206744 -1.975866) (xy 6.210554 -1.977644) (xy 6.211062 -1.977898) (xy 6.211824 -1.978152)
				(xy 6.213602 -1.979168) (xy 6.214618 -1.979422) (xy 6.213602 -1.974088) (xy 6.211824 -1.96342) (xy 6.211062 -1.958594)
				(xy 6.210554 -1.956562) (xy 6.206744 -1.934464) (xy 6.20141 -1.903222) (xy 6.199124 -1.891538) (xy 6.194806 -1.866138)
				(xy 6.18744 -1.82499) (xy 6.182614 -1.797558) (xy 6.179312 -1.778254) (xy 6.178042 -1.771396) (xy 6.17601 -1.759712)
				(xy 6.171692 -1.735582) (xy 6.170422 -1.727708) (xy 6.158484 -1.65989) (xy 6.156198 -1.64592) (xy 6.142228 -1.567688)
				(xy 6.141974 -1.565402) (xy 6.136894 -1.5367) (xy 6.132576 -1.51257) (xy 6.129782 -1.497076) (xy 6.12902 -1.491488)
				(xy 6.430264 -1.491488) (xy 6.427978 -1.47828) (xy 6.421882 -1.442974) (xy 6.41731 -1.417574) (xy 6.412992 -1.39319)
				(xy 6.403086 -1.33604) (xy 6.392926 -1.27889) (xy 6.38429 -1.229106) (xy 6.383274 -1.222756) (xy 6.378194 -1.1938)
				(xy 6.375908 -1.180592) (xy 6.07441 -1.180592) (xy 6.073394 -1.175004) (xy 6.0706 -1.158748) (xy 6.066282 -1.13411)
				(xy 6.060694 -1.101598) (xy 6.058662 -1.090422) (xy 6.04647 -1.020826) (xy 6.03504 -0.955802) (xy 6.030214 -0.928624)
				(xy 6.030214 -0.928116) (xy 6.013958 -0.83566) (xy 5.999734 -0.754888) (xy 5.996178 -0.734568) (xy 5.993892 -0.722376)
				(xy 5.989828 -0.697484) (xy 5.98678 -0.681482) (xy 5.986018 -0.67691) (xy 5.986018 -0.675894) (xy 5.98551 -0.674116)
				(xy 5.980684 -0.636016) (xy 5.980684 -0.635) (xy 5.980684 -0.601726) (xy 5.98551 -0.577596) (xy 5.986018 -0.576326)
				(xy 5.986018 -0.575564) (xy 5.98678 -0.573786) (xy 5.989828 -0.568452) (xy 5.993892 -0.559816) (xy 5.996178 -0.555498)
				(xy 5.999734 -0.553212) (xy 6.013958 -0.543306) (xy 6.030214 -0.531876) (xy 6.03504 -0.531368) (xy 6.04647 -0.529844)
				(xy 6.058662 -0.52832) (xy 6.060694 -0.527812) (xy 6.066282 -0.52705) (xy 6.0706 -0.526542) (xy 6.073394 -0.526288)
				(xy 6.07441 -0.526034) (xy 6.081522 -0.525272) (xy 6.087364 -0.52578) (xy 6.10108 -0.527558) (xy 6.121654 -0.529844)
				(xy 6.124194 -0.530098) (xy 6.12521 -0.530352) (xy 6.12902 -0.531622) (xy 6.129782 -0.53213) (xy 6.132576 -0.533146)
				(xy 6.136894 -0.53467) (xy 6.141974 -0.536448) (xy 6.142228 -0.536702) (xy 6.156198 -0.541782) (xy 6.158484 -0.542544)
				(xy 6.170422 -0.546862) (xy 6.171692 -0.547624) (xy 6.17601 -0.550164) (xy 6.178042 -0.551434) (xy 6.179312 -0.552196)
				(xy 6.182614 -0.553974) (xy 6.18744 -0.556768) (xy 6.194806 -0.561086) (xy 6.199124 -0.563372) (xy 6.20141 -0.564642)
				(xy 6.206744 -0.567944) (xy 6.210554 -0.569976) (xy 6.211062 -0.57023) (xy 6.211824 -0.570738) (xy 6.213602 -0.572008)
				(xy 6.214618 -0.572516) (xy 6.221984 -0.57658) (xy 6.225286 -0.578866) (xy 6.231382 -0.583184) (xy 6.25094 -0.597154)
				(xy 6.267958 -0.609092) (xy 6.279642 -0.617474) (xy 6.28015 -0.617728) (xy 6.283452 -0.620014) (xy 6.284722 -0.62103)
				(xy 6.283452 -0.61722) (xy 6.28015 -0.606552) (xy 6.279642 -0.605028) (xy 6.267958 -0.568706) (xy 6.25094 -0.515112)
				(xy 6.231382 -0.45339) (xy 6.225286 -0.433832) (xy 6.221984 -0.423672) (xy 6.214618 -0.400812) (xy 6.213602 -0.397764)
				(xy 6.211824 -0.391922) (xy 6.211062 -0.389128) (xy 6.210554 -0.388112) (xy 6.206744 -0.37592) (xy 6.20141 -0.358648)
				(xy 6.199124 -0.352298) (xy 6.194806 -0.338328) (xy 6.18744 -0.315722) (xy 6.182614 -0.300228) (xy 6.179312 -0.289814)
				(xy 6.178042 -0.286004) (xy 6.17601 -0.284734) (xy 6.171692 -0.282448) (xy 6.170422 -0.281686) (xy 6.158484 -0.275082)
				(xy 6.156198 -0.273558) (xy 6.142228 -0.265938) (xy 6.141974 -0.265684) (xy 6.136894 -0.26289) (xy 6.132576 -0.260604)
				(xy 6.129782 -0.25908) (xy 6.12902 -0.258572) (xy 6.12521 -0.256286) (xy 6.124194 -0.255778) (xy 6.121654 -0.255016)
				(xy 6.10108 -0.247142) (xy 6.087364 -0.242316) (xy 6.081522 -0.24003) (xy 6.07441 -0.23749) (xy 6.073394 -0.236982)
				(xy 6.0706 -0.235966) (xy 6.066282 -0.234442) (xy 6.060694 -0.23241) (xy 6.058662 -0.231394) (xy 6.04647 -0.228854)
				(xy 6.03504 -0.226314) (xy 6.030214 -0.225298) (xy 6.013958 -0.221488) (xy 5.999734 -0.21844) (xy 5.996178 -0.217678)
				(xy 5.993892 -0.21717) (xy 5.989828 -0.216154) (xy 5.98678 -0.215646) (xy 5.986018 -0.215392) (xy 5.98551 -0.215392)
				(xy 5.980684 -0.214884) (xy 5.969 -0.214122) (xy 5.911596 -0.20955)
			)
			(stroke
				(width 0)
				(type default)
			)
			(fill yes)
			(layer "F.SilkS")
		)
		(fp_poly
			(pts
				(xy 1.328166 0) (xy 1.325626 -0.000508) (xy 1.31318 -0.005588) (xy 1.30302 -0.009652) (xy 1.290828 -0.014478)
				(xy 1.274064 -0.021082) (xy 1.260348 -0.026416) (xy 1.25222 -0.029718) (xy 1.246886 -0.03175) (xy 1.207262 -0.047244)
				(xy 1.196086 -0.051816) (xy 1.192276 -0.053086) (xy 1.185418 -0.05588) (xy 1.1811 -0.057658) (xy 1.130554 -0.077216)
				(xy 1.128776 -0.077724) (xy 1.128522 -0.077978) (xy 1.123442 -0.08001) (xy 1.12268 -0.08001) (xy 1.114806 -0.083312)
				(xy 1.114552 -0.083312) (xy 1.113282 -0.08382) (xy 1.102614 -0.087884) (xy 1.100328 -0.0889) (xy 1.089152 -0.093218)
				(xy 1.087628 -0.093726) (xy 1.084072 -0.094996) (xy 1.064768 -0.102362) (xy 1.048258 -0.108712)
				(xy 1.04267 -0.110744) (xy 1.039368 -0.112014) (xy 1.024382 -0.117602) (xy 1.017778 -0.119888) (xy 0.998474 -0.127254)
				(xy 0.997712 -0.127508) (xy 0.9906 -0.130302) (xy 0.968502 -0.138176) (xy 0.960882 -0.140716) (xy 0.960374 -0.14097)
				(xy 0.937006 -0.149352) (xy 0.928878 -0.152146) (xy 0.922528 -0.154686) (xy 0.903224 -0.161036)
				(xy 0.89535 -0.163576) (xy 0.894334 -0.16383) (xy 0.877062 -0.168656) (xy 0.874776 -0.169418) (xy 0.868934 -0.17018)
				(xy 0.862076 -0.17018) (xy 0.860044 -0.170434) (xy 0.845312 -0.170434) (xy 0.828802 -0.170942) (xy 0.82296 -0.170942)
				(xy 0.78994 -0.171958) (xy 0.788924 -0.171958) (xy 0.78486 -0.171958) (xy 0.77978 -0.172212) (xy 0.767588 -0.173228)
				(xy 0.751078 -0.174498) (xy 0.747014 -0.174752) (xy 0.745236 -0.175006) (xy 0.725424 -0.17653) (xy 0.710692 -0.1778)
				(xy 0.70612 -0.178054) (xy 0.675894 -0.180594) (xy 0.667004 -0.181356) (xy 0.65786 -0.182118) (xy 0.641604 -0.184912)
				(xy 0.629412 -0.18669) (xy 0.62611 -0.187452) (xy 0.607822 -0.1905) (xy 0.593598 -0.192786) (xy 0.57531 -0.196088)
				(xy 0.559562 -0.198628) (xy 0.547116 -0.200914) (xy 0.543814 -0.201676) (xy 0.534162 -0.20447) (xy 0.527812 -0.206248)
				(xy 0.514096 -0.210058) (xy 0.485902 -0.217932) (xy 0.471424 -0.22225) (xy 0.460248 -0.225298) (xy 0.449072 -0.228346)
				(xy 0.446786 -0.229108) (xy 0.446532 -0.229108) (xy 0.436626 -0.233172) (xy 0.425196 -0.237998)
				(xy 0.416052 -0.242062) (xy 0.406654 -0.245872) (xy 0.398272 -0.249682) (xy 0.39116 -0.252476) (xy 0.383794 -0.255778)
				(xy 0.378714 -0.25781) (xy 0.373126 -0.260096) (xy 0.371348 -0.261112) (xy 0.370078 -0.26162) (xy 0.366014 -0.263144)
				(xy 0.364744 -0.263652) (xy 0.36322 -0.264414) (xy 0.356108 -0.267462) (xy 0.300736 -0.300482) (xy 0.274828 -0.31623)
				(xy 0.23749 -0.34671) (xy 0.201676 -0.37592) (xy 0.18161 -0.398272) (xy 0.136398 -0.448564) (xy 0.133096 -0.454406)
				(xy 0.091948 -0.5207) (xy 0.085598 -0.530606) (xy 0.05842 -0.594868) (xy 0.049276 -0.615696) (xy 0.032258 -0.674878)
				(xy 0.024892 -0.69977) (xy 0.013716 -0.759206) (xy 0.010414 -0.777748) (xy 0.003048 -0.84328) (xy 0.002794 -0.845312)
				(xy 0.000508 -0.890778) (xy 0.000254 -0.897636) (xy 0 -0.911098) (xy 0 -0.916686) (xy 0 -0.928878)
				(xy 0.000254 -0.934974) (xy 0.000508 -0.94742) (xy 0.002794 -0.981202) (xy 0.003048 -0.98425) (xy 0.010414 -1.03378)
				(xy 0.013716 -1.057402) (xy 0.024892 -1.101344) (xy 0.032258 -1.129538) (xy 0.049276 -1.175766)
				(xy 0.05842 -1.199896) (xy 0.085598 -1.25476) (xy 0.091948 -1.267206) (xy 0.133096 -1.33096) (xy 0.136398 -1.335278)
				(xy 0.18161 -1.39065) (xy 0.201676 -1.410462) (xy 0.23749 -1.44526) (xy 0.274828 -1.474216) (xy 0.300736 -1.494028)
				(xy 0.356108 -1.527302) (xy 0.36322 -1.53162) (xy 0.364744 -1.532382) (xy 0.366014 -1.533398) (xy 0.370078 -1.535684)
				(xy 0.371348 -1.536446) (xy 0.373126 -1.537208) (xy 0.378714 -1.539748) (xy 0.383794 -1.542034)
				(xy 0.39116 -1.545336) (xy 0.398272 -1.548638) (xy 0.406654 -1.552194) (xy 0.416052 -1.556512) (xy 0.425196 -1.560576)
				(xy 0.436626 -1.56591) (xy 0.446532 -1.570228) (xy 0.446786 -1.570482) (xy 0.449072 -1.571498) (xy 0.460248 -1.5748)
				(xy 0.471424 -1.57861) (xy 0.485902 -1.583182) (xy 0.498348 -1.586992) (xy 0.514096 -1.592072) (xy 0.527812 -1.59639)
				(xy 0.534162 -1.598422) (xy 0.543814 -1.6002) (xy 0.547116 -1.600962) (xy 0.559562 -1.603502) (xy 0.57531 -1.60655)
				(xy 0.593598 -1.610106) (xy 0.607822 -1.6129) (xy 0.62611 -1.616456) (xy 0.629412 -1.61671) (xy 0.641604 -1.617726)
				(xy 0.65786 -1.61925) (xy 0.667004 -1.620012) (xy 0.675894 -1.620774) (xy 0.70612 -1.623314) (xy 0.710692 -1.623822)
				(xy 0.725424 -1.625092) (xy 0.745236 -1.625346) (xy 0.747014 -1.6256) (xy 0.751078 -1.6256) (xy 0.767588 -1.6256)
				(xy 0.77978 -1.625346) (xy 0.78486 -1.625346) (xy 0.788924 -1.625092) (xy 0.78994 -1.625092) (xy 0.82296 -1.622806)
				(xy 0.828802 -1.622298) (xy 0.845312 -1.621028) (xy 0.860044 -1.620012) (xy 0.862076 -1.619758)
				(xy 0.866902 -1.619504) (xy 0.868934 -1.61925) (xy 0.874776 -1.618742) (xy 0.877062 -1.618488) (xy 0.894334 -1.615694)
				(xy 0.89535 -1.61544) (xy 0.903224 -1.61417) (xy 0.922528 -1.610614) (xy 0.928878 -1.609598) (xy 0.937006 -1.608328)
				(xy 0.960374 -1.604264) (xy 0.960882 -1.60401) (xy 0.968502 -1.601724) (xy 0.9906 -1.595628) (xy 0.997712 -1.593596)
				(xy 0.998474 -1.593342) (xy 1.017778 -1.587754) (xy 1.024382 -1.585976) (xy 1.039368 -1.581658)
				(xy 1.04267 -1.580388) (xy 1.048258 -1.578102) (xy 1.064768 -1.571244) (xy 1.06934 -1.569466) (xy 1.084072 -1.56337)
				(xy 1.087628 -1.5621) (xy 1.089152 -1.561338) (xy 1.100328 -1.556766) (xy 1.102614 -1.556004) (xy 1.113282 -1.551686)
				(xy 1.114552 -1.550924) (xy 1.114806 -1.550924) (xy 1.12268 -1.546606) (xy 1.123442 -1.546098) (xy 1.128522 -1.543304)
				(xy 1.128776 -1.543304) (xy 1.130554 -1.542288) (xy 1.1811 -1.514602) (xy 1.185418 -1.512316) (xy 1.192276 -1.50749)
				(xy 1.196086 -1.504696) (xy 1.207262 -1.496822) (xy 1.246886 -1.468882) (xy 1.25222 -1.465072) (xy 1.260348 -1.45796)
				(xy 1.274064 -1.445768) (xy 1.290828 -1.430528) (xy 1.30302 -1.41986) (xy 1.31318 -1.410716) (xy 1.317498 -1.406906)
				(xy 1.325626 -1.397) (xy 1.328166 -1.393952) (xy 1.342644 -1.375918) (xy 1.343914 -1.374394) (xy 1.36779 -1.345184)
				(xy 1.376172 -1.335024) (xy 1.37922 -1.331214) (xy 1.398524 -1.297432) (xy 1.425448 -1.250696) (xy 1.433322 -1.231392)
				(xy 1.441958 -1.209802) (xy 1.458214 -1.170178) (xy 1.461516 -1.157986) (xy 1.472946 -1.116838)
				(xy 1.47955 -1.09347) (xy 1.491234 -1.029462) (xy 1.491996 -1.025906) (xy 1.491996 -1.02489) (xy 1.497838 -0.96901)
				(xy 1.498854 -0.946912) (xy 1.499108 -0.940054) (xy 1.499108 -0.937768) (xy 1.499108 -0.92837) (xy 1.499108 -0.918972)
				(xy 1.498854 -0.916432) (xy 1.497838 -0.898652) (xy 1.491996 -0.8001) (xy 1.491996 -0.797814) (xy 1.491234 -0.79375)
				(xy 1.47955 -0.726186) (xy 1.472946 -0.688086) (xy 1.461516 -0.65151) (xy 1.458214 -0.640588) (xy 1.441958 -0.589534)
				(xy 1.433322 -0.572008) (xy 1.425448 -0.556006) (xy 1.398524 -0.50165) (xy 1.37922 -0.474726) (xy 1.376172 -0.470408)
				(xy 1.36779 -0.458978) (xy 1.343914 -0.425704) (xy 1.342644 -0.423926) (xy 1.328166 -0.409702) (xy 1.325626 -0.407162)
				(xy 1.317498 -0.399288) (xy 1.31318 -0.39497) (xy 1.30302 -0.38481) (xy 1.290828 -0.372872) (xy 1.274064 -0.356108)
				(xy 1.260348 -0.346456) (xy 1.25222 -0.340614) (xy 1.246886 -0.336804) (xy 1.207262 -0.30861) (xy 1.196086 -0.300482)
				(xy 1.192276 -0.297688) (xy 1.196086 -0.294894) (xy 1.207262 -0.28702) (xy 1.246886 -0.25908) (xy 1.25222 -0.255016)
				(xy 1.260348 -0.249428) (xy 1.274064 -0.239776) (xy 1.290828 -0.227584) (xy 1.30302 -0.219202) (xy 1.31318 -0.211836)
				(xy 1.317498 -0.208788) (xy 1.325626 -0.2032) (xy 1.328166 -0.201422) (xy 1.342644 -0.191008) (xy 1.343914 -0.189992)
				(xy 1.36779 -0.173228) (xy 1.376172 -0.167386) (xy 1.37922 -0.1651) (xy 1.398524 -0.151384) (xy 1.425448 -0.132334)
				(xy 1.433322 -0.126746) (xy 1.441958 -0.12065) (xy 1.458214 -0.10922) (xy 1.461516 -0.106934) (xy 1.472946 -0.098806)
				(xy 1.47955 -0.09398) (xy 1.491234 -0.085852) (xy 1.491996 -0.085344) (xy 1.491996 -0.08509) (xy 1.497838 -0.08128)
				(xy 1.498854 -0.080518) (xy 1.499108 -0.080264) (xy 1.500632 -0.079248) (xy 1.528318 -0.05969) (xy 1.533906 -0.05588)
				(xy 1.53543 -0.05461) (xy 1.536954 -0.05334) (xy 1.53543 -0.053086) (xy 1.533906 -0.052578) (xy 1.528318 -0.051054)
				(xy 1.500632 -0.044196) (xy 1.499108 -0.043688) (xy 1.498854 -0.043688) (xy 1.497838 -0.043434)
				(xy 1.491996 -0.04191) (xy 1.491234 -0.041656) (xy 1.47955 -0.038608) (xy 1.472946 -0.037084) (xy 1.461516 -0.034036)
				(xy 1.458214 -0.033274) (xy 1.441958 -0.02921) (xy 1.433322 -0.026924) (xy 1.425448 -0.024892) (xy 1.398524 -0.018034)
				(xy 1.37922 -0.013208) (xy 1.376172 -0.012192) (xy 1.36779 -0.01016) (xy 1.343914 -0.004064) (xy 1.342644 -0.00381)
			)
			(stroke
				(width 0)
				(type default)
			)
			(fill yes)
			(layer "F.SilkS")
		)
		(fp_poly
			(pts
				(xy 3.297936 -0.209296) (xy 3.295904 -0.20955) (xy 3.29311 -0.20955) (xy 3.283204 -0.209804) (xy 3.280156 -0.209804)
				(xy 3.277108 -0.210312) (xy 3.270504 -0.21082) (xy 3.2639 -0.211582) (xy 3.259836 -0.21209) (xy 3.25628 -0.212344)
				(xy 3.25374 -0.212598) (xy 3.2512 -0.212852) (xy 3.246374 -0.21336) (xy 3.244596 -0.213614) (xy 3.241294 -0.213868)
				(xy 3.240532 -0.214122) (xy 3.239008 -0.214122) (xy 3.2385 -0.214122) (xy 3.237738 -0.214122) (xy 3.228086 -0.215138)
				(xy 3.227324 -0.215392) (xy 3.223768 -0.215646) (xy 3.219958 -0.216154) (xy 3.216148 -0.216408)
				(xy 3.21056 -0.21717) (xy 3.207258 -0.217932) (xy 3.205734 -0.218186) (xy 3.18008 -0.224536) (xy 3.15976 -0.229616)
				(xy 3.156204 -0.230378) (xy 3.1496 -0.231902) (xy 3.147568 -0.23241) (xy 3.147314 -0.232664) (xy 3.14452 -0.233172)
				(xy 3.14198 -0.234188) (xy 3.141472 -0.234442) (xy 3.141218 -0.234696) (xy 3.0861 -0.257556) (xy 3.083306 -0.258572)
				(xy 3.03022 -0.2921) (xy 3.028696 -0.293116) (xy 2.98323 -0.336042) (xy 2.982214 -0.337058) (xy 2.946146 -0.38862)
				(xy 2.944876 -0.390398) (xy 2.919984 -0.450596) (xy 2.918714 -0.45339) (xy 2.905252 -0.52451) (xy 2.904998 -0.52578)
				(xy 2.905252 -0.60833) (xy 2.918714 -0.688086) (xy 2.919984 -0.69469) (xy 2.944876 -0.767588) (xy 2.946146 -0.771144)
				(xy 2.982214 -0.836676) (xy 2.98323 -0.838708) (xy 3.028696 -0.896112) (xy 3.03022 -0.89789) (xy 3.083306 -0.945896)
				(xy 3.0861 -0.948436) (xy 3.141218 -0.984758) (xy 3.141472 -0.985012) (xy 3.14198 -0.98552) (xy 3.14452 -0.987044)
				(xy 3.147314 -0.988822) (xy 3.147568 -0.989076) (xy 3.1496 -0.990346) (xy 3.156204 -0.993394) (xy 3.15976 -0.995172)
				(xy 3.18008 -1.004824) (xy 3.205734 -1.017016) (xy 3.207258 -1.017778) (xy 3.21056 -1.019302) (xy 3.216148 -1.022096)
				(xy 3.219958 -1.023874) (xy 3.223768 -1.02489) (xy 3.227324 -1.02616) (xy 3.228086 -1.026414) (xy 3.237738 -1.029716)
				(xy 3.2385 -1.02997) (xy 3.239008 -1.02997) (xy 3.240532 -1.030478) (xy 3.244596 -1.032002) (xy 3.246374 -1.03251)
				(xy 3.2512 -1.034034) (xy 3.25374 -1.034796) (xy 3.25628 -1.035558) (xy 3.259836 -1.036828) (xy 3.2639 -1.038098)
				(xy 3.270504 -1.040384) (xy 3.277108 -1.042416) (xy 3.280156 -1.043432) (xy 3.283204 -1.044448)
				(xy 3.29311 -1.04775) (xy 3.295904 -1.048512) (xy 3.297936 -1.04902) (xy 3.29819 -1.04902) (xy 3.299714 -1.049274)
				(xy 3.308858 -1.051306) (xy 3.312414 -1.051814) (xy 3.314954 -1.052322) (xy 3.325876 -1.054608)
				(xy 3.326638 -1.054608) (xy 3.333496 -1.056132) (xy 3.33502 -1.056386) (xy 3.354324 -1.060196) (xy 3.361182 -1.06172)
				(xy 3.361944 -1.06172) (xy 3.376676 -1.064768) (xy 3.3909 -1.066038) (xy 3.392424 -1.066292) (xy 3.393694 -1.066292)
				(xy 3.40106 -1.0668) (xy 3.406394 -1.067308) (xy 3.41884 -1.068578) (xy 3.427222 -1.06934) (xy 3.430524 -1.069594)
				(xy 3.443478 -1.070864) (xy 3.454908 -1.07188) (xy 3.461004 -1.072388) (xy 3.46202 -1.072388) (xy 3.482086 -1.072896)
				(xy 3.482594 -1.072896) (xy 3.490976 -1.072896) (xy 3.498088 -1.072896) (xy 3.506724 -1.072896)
				(xy 3.515106 -1.072642) (xy 3.529076 -1.071626) (xy 3.535172 -1.071372) (xy 3.53949 -1.071118) (xy 3.551428 -1.070102)
				(xy 3.5687 -1.068832) (xy 3.57505 -1.068324) (xy 3.576574 -1.068324) (xy 3.583178 -1.067308) (xy 3.588766 -1.066292)
				(xy 3.59029 -1.066038) (xy 3.5941 -1.065276) (xy 3.598418 -1.064514) (xy 3.600196 -1.06426) (xy 3.602228 -1.064006)
				(xy 3.603244 -1.063752) (xy 3.603498 -1.063752) (xy 3.606292 -1.063244) (xy 3.610102 -1.062482)
				(xy 3.618484 -1.061212) (xy 3.624072 -1.060196) (xy 3.62839 -1.059434) (xy 3.631184 -1.058672) (xy 3.638296 -1.05664)
				(xy 3.639312 -1.056386) (xy 3.648456 -1.053592) (xy 3.651504 -1.05283) (xy 3.653536 -1.052322) (xy 3.65379 -1.052322)
				(xy 3.65506 -1.051814) (xy 3.657092 -1.051306) (xy 3.659378 -1.050544) (xy 3.662172 -1.049782) (xy 3.662426 -1.049782)
				(xy 3.668776 -1.048004) (xy 3.671824 -1.046988) (xy 3.674364 -1.045972) (xy 3.674872 -1.045972)
				(xy 3.677412 -1.044702) (xy 3.679444 -1.04394) (xy 3.680714 -1.043432) (xy 3.681222 -1.043178) (xy 3.683254 -1.042416)
				(xy 3.6957 -1.037336) (xy 3.707892 -1.03251) (xy 3.712972 -1.02997) (xy 3.72364 -1.024382) (xy 3.726942 -1.022858)
				(xy 3.727196 -1.023874) (xy 3.729228 -1.034796) (xy 3.734816 -1.068324) (xy 3.735324 -1.07061) (xy 3.73761 -1.082802)
				(xy 3.737864 -1.085088) (xy 3.740658 -1.109218) (xy 3.737864 -1.13284) (xy 3.73761 -1.135888) (xy 3.735324 -1.15443)
				(xy 3.734816 -1.157732) (xy 3.729228 -1.168654) (xy 3.727196 -1.17221) (xy 3.726942 -1.172464) (xy 3.72364 -1.178814)
				(xy 3.712972 -1.198118) (xy 3.707892 -1.202944) (xy 3.6957 -1.214374) (xy 3.683254 -1.221994) (xy 3.681222 -1.223264)
				(xy 3.680714 -1.223518) (xy 3.679444 -1.22428) (xy 3.677412 -1.22555) (xy 3.674872 -1.227328) (xy 3.674364 -1.227582)
				(xy 3.671824 -1.228598) (xy 3.668776 -1.229614) (xy 3.662426 -1.232154) (xy 3.662172 -1.232154)
				(xy 3.659378 -1.23317) (xy 3.657092 -1.234186) (xy 3.65506 -1.234694) (xy 3.65379 -1.235202) (xy 3.653536 -1.235456)
				(xy 3.651504 -1.236218) (xy 3.648456 -1.237234) (xy 3.639312 -1.239012) (xy 3.638296 -1.23952) (xy 3.631184 -1.24079)
				(xy 3.62839 -1.241298) (xy 3.624072 -1.24206) (xy 3.618484 -1.24333) (xy 3.610102 -1.243584) (xy 3.606292 -1.243838)
				(xy 3.603498 -1.244092) (xy 3.602228 -1.244092) (xy 3.600196 -1.244092) (xy 3.598418 -1.244346)
				(xy 3.5941 -1.2446) (xy 3.59029 -1.2446) (xy 3.588766 -1.244854) (xy 3.583178 -1.245108) (xy 3.576574 -1.245108)
				(xy 3.57505 -1.245108) (xy 3.5687 -1.244854) (xy 3.551428 -1.2446) (xy 3.53949 -1.244346) (xy 3.535172 -1.244092)
				(xy 3.529076 -1.243584) (xy 3.515106 -1.242314) (xy 3.506724 -1.241806) (xy 3.498088 -1.241044)
				(xy 3.494278 -1.24079) (xy 3.494024 -1.24079) (xy 3.493262 -1.24079) (xy 3.490976 -1.240536) (xy 3.482594 -1.240028)
				(xy 3.482086 -1.239774) (xy 3.46202 -1.23825) (xy 3.461004 -1.237996) (xy 3.454908 -1.23698) (xy 3.443478 -1.234694)
				(xy 3.430524 -1.232408) (xy 3.427222 -1.2319) (xy 3.41884 -1.230376) (xy 3.406394 -1.227836) (xy 3.40106 -1.22682)
				(xy 3.393694 -1.22555) (xy 3.392424 -1.225296) (xy 3.3909 -1.224788) (xy 3.376676 -1.22047) (xy 3.361944 -1.215898)
				(xy 3.361182 -1.215644) (xy 3.354324 -1.213612) (xy 3.33502 -1.207516) (xy 3.333496 -1.207008) (xy 3.326638 -1.204976)
				(xy 3.325876 -1.204722) (xy 3.314954 -1.199896) (xy 3.312414 -1.19888) (xy 3.308858 -1.19761) (xy 3.299714 -1.1938)
				(xy 3.29819 -1.192784) (xy 3.297936 -1.192784) (xy 3.295904 -1.192022) (xy 3.29311 -1.191006) (xy 3.283204 -1.186688)
				(xy 3.280156 -1.185418) (xy 3.277108 -1.184148) (xy 3.270504 -1.181354) (xy 3.2639 -1.17856) (xy 3.259836 -1.176782)
				(xy 3.25628 -1.175258) (xy 3.25374 -1.173988) (xy 3.2512 -1.172718) (xy 3.246374 -1.170432) (xy 3.244596 -1.16967)
				(xy 3.241294 -1.168146) (xy 3.240532 -1.167638) (xy 3.239008 -1.166876) (xy 3.2385 -1.166876) (xy 3.237738 -1.166368)
				(xy 3.228086 -1.161796) (xy 3.227324 -1.161796) (xy 3.223768 -1.171194) (xy 3.219958 -1.181608)
				(xy 3.216148 -1.191514) (xy 3.21056 -1.2065) (xy 3.207258 -1.21539) (xy 3.205734 -1.2192) (xy 3.18008 -1.287018)
				(xy 3.15976 -1.341374) (xy 3.156204 -1.351026) (xy 3.1496 -1.368298) (xy 3.147568 -1.373378) (xy 3.147314 -1.374394)
				(xy 3.14452 -1.382014) (xy 3.14198 -1.388364) (xy 3.141472 -1.389634) (xy 3.141218 -1.390904) (xy 3.141472 -1.391158)
				(xy 3.14198 -1.391412) (xy 3.14452 -1.392682) (xy 3.147314 -1.394206) (xy 3.147568 -1.39446) (xy 3.1496 -1.395476)
				(xy 3.156204 -1.398778) (xy 3.15976 -1.400556) (xy 3.18008 -1.410716) (xy 3.205734 -1.423162) (xy 3.207258 -1.423924)
				(xy 3.21056 -1.425194) (xy 3.216148 -1.427734) (xy 3.219958 -1.429258) (xy 3.223768 -1.430782) (xy 3.227324 -1.432306)
				(xy 3.228086 -1.432814) (xy 3.237738 -1.436624) (xy 3.2385 -1.437132) (xy 3.239008 -1.437132) (xy 3.240532 -1.437894)
				(xy 3.241294 -1.438402) (xy 3.244596 -1.439672) (xy 3.246374 -1.440434) (xy 3.2512 -1.442466) (xy 3.25374 -1.443482)
				(xy 3.25628 -1.444498) (xy 3.259836 -1.446022) (xy 3.2639 -1.4478) (xy 3.270504 -1.450594) (xy 3.277108 -1.453388)
				(xy 3.280156 -1.454658) (xy 3.283204 -1.455928) (xy 3.29311 -1.459992) (xy 3.295904 -1.461262) (xy 3.297936 -1.462024)
				(xy 3.29819 -1.462024) (xy 3.299714 -1.462786) (xy 3.308858 -1.46558) (xy 3.312414 -1.466596) (xy 3.314954 -1.467358)
				(xy 3.325876 -1.470914) (xy 3.326638 -1.471168) (xy 3.333496 -1.4732) (xy 3.33502 -1.473708) (xy 3.354324 -1.479296)
				(xy 3.361182 -1.481582) (xy 3.361944 -1.481836) (xy 3.376676 -1.486408) (xy 3.3909 -1.490472) (xy 3.392424 -1.49098)
				(xy 3.393694 -1.491488) (xy 3.40106 -1.492758) (xy 3.406394 -1.493774) (xy 3.41884 -1.49606) (xy 3.427222 -1.497584)
				(xy 3.430524 -1.498092) (xy 3.443478 -1.500632) (xy 3.454908 -1.502664) (xy 3.461004 -1.50368) (xy 3.46202 -1.503934)
				(xy 3.482086 -1.50749) (xy 3.482594 -1.50749) (xy 3.490976 -1.509268) (xy 3.493262 -1.509522) (xy 3.494024 -1.509776)
				(xy 3.494278 -1.509776) (xy 3.498088 -1.51003) (xy 3.506724 -1.510538) (xy 3.515106 -1.5113) (xy 3.529076 -1.512316)
				(xy 3.535172 -1.51257) (xy 3.53949 -1.512824) (xy 3.551428 -1.513586) (xy 3.5687 -1.514856) (xy 3.57505 -1.515364)
				(xy 3.576574 -1.515364) (xy 3.583178 -1.515872) (xy 3.588766 -1.51638) (xy 3.59029 -1.51638) (xy 3.5941 -1.516634)
				(xy 3.598418 -1.516888) (xy 3.600196 -1.517142) (xy 3.602228 -1.517142) (xy 3.603244 -1.517396)
				(xy 3.603498 -1.517396) (xy 3.606292 -1.517396) (xy 3.610102 -1.517396) (xy 3.618484 -1.51765) (xy 3.624072 -1.51765)
				(xy 3.62839 -1.51765) (xy 3.631184 -1.51765) (xy 3.638296 -1.517904) (xy 3.639312 -1.51765) (xy 3.648456 -1.517396)
				(xy 3.651504 -1.517396) (xy 3.653536 -1.517396) (xy 3.65379 -1.517396) (xy 3.65506 -1.517142) (xy 3.657092 -1.517142)
				(xy 3.659378 -1.517142) (xy 3.662172 -1.516888) (xy 3.662426 -1.516888) (xy 3.668776 -1.516888)
				(xy 3.671824 -1.516634) (xy 3.674364 -1.516634) (xy 3.674872 -1.516634) (xy 3.677412 -1.51638) (xy 3.679444 -1.51638)
				(xy 3.680714 -1.51638) (xy 3.683254 -1.51638) (xy 3.6957 -1.514856) (xy 3.707892 -1.513332) (xy 3.712972 -1.512824)
				(xy 3.72364 -1.511554) (xy 3.726942 -1.511046) (xy 3.727196 -1.511046) (xy 3.729228 -1.510792) (xy 3.734816 -1.510284)
				(xy 3.735324 -1.510284) (xy 3.73761 -1.509776) (xy 3.737864 -1.509776) (xy 3.740658 -1.509522) (xy 3.767328 -1.50622)
				(xy 3.807206 -1.49606) (xy 3.842512 -1.486916) (xy 3.852164 -1.482598) (xy 3.888486 -1.46685) (xy 3.908552 -1.458214)
				(xy 3.912108 -1.455674) (xy 3.91922 -1.451102) (xy 3.920998 -1.449832) (xy 3.924808 -1.447292) (xy 3.930142 -1.443482)
				(xy 3.937254 -1.43891) (xy 3.945382 -1.433322) (xy 3.95478 -1.426972) (xy 3.964432 -1.420368) (xy 3.975608 -1.408684)
				(xy 4.009644 -1.373886) (xy 4.020058 -1.357122) (xy 4.039616 -1.325118) (xy 4.043426 -1.318768)
				(xy 4.047998 -1.305814) (xy 4.05511 -1.284986) (xy 4.060698 -1.26873) (xy 4.064508 -1.257554) (xy 4.065524 -1.255268)
				(xy 4.06654 -1.246378) (xy 4.066794 -1.245362) (xy 4.067556 -1.238504) (xy 4.070604 -1.214374) (xy 4.074668 -1.183386)
				(xy 4.070604 -1.103884) (xy 4.067556 -1.082802) (xy 4.066794 -1.077722) (xy 4.06654 -1.076706) (xy 4.065524 -1.070356)
				(xy 4.064508 -1.065784) (xy 4.060698 -1.043686) (xy 4.05511 -1.011682) (xy 4.047998 -0.971042) (xy 4.043426 -0.945388)
				(xy 4.039616 -0.92329) (xy 4.020058 -0.811276) (xy 4.009644 -0.752348) (xy 3.975608 -0.5588) (xy 3.964432 -0.494538)
				(xy 3.95478 -0.43942) (xy 3.945382 -0.38608) (xy 3.937254 -0.33909) (xy 3.930142 -0.298958) (xy 3.924808 -0.267716)
				(xy 3.920998 -0.24638) (xy 3.91922 -0.23622) (xy 3.912108 -0.235712) (xy 3.588766 -0.235712) (xy 3.59029 -0.244602)
				(xy 3.5941 -0.265938) (xy 3.598418 -0.289814) (xy 3.600196 -0.300482) (xy 3.602228 -0.311912) (xy 3.603244 -0.317754)
				(xy 3.603498 -0.319278) (xy 3.603244 -0.319278) (xy 3.602228 -0.318262) (xy 3.600196 -0.316484)
				(xy 3.598418 -0.315214) (xy 3.5941 -0.312166) (xy 3.59029 -0.309372) (xy 3.588766 -0.308356) (xy 3.583178 -0.304292)
				(xy 3.576574 -0.299466) (xy 3.57505 -0.298196) (xy 3.5687 -0.293624) (xy 3.551428 -0.281178) (xy 3.53949 -0.274828)
				(xy 3.535172 -0.272542) (xy 3.529076 -0.26924) (xy 3.515106 -0.261874) (xy 3.506724 -0.257302) (xy 3.498088 -0.252984)
				(xy 3.494278 -0.250952) (xy 3.494024 -0.250952) (xy 3.493262 -0.250698) (xy 3.490976 -0.249682)
				(xy 3.482594 -0.246634) (xy 3.482086 -0.24638) (xy 3.46202 -0.239268) (xy 3.461004 -0.239014) (xy 3.454908 -0.236728)
				(xy 3.443478 -0.232664) (xy 3.430524 -0.227838) (xy 3.427222 -0.227076) (xy 3.41884 -0.225298) (xy 3.406394 -0.222758)
				(xy 3.40106 -0.221742) (xy 3.393694 -0.220218) (xy 3.392424 -0.219964) (xy 3.3909 -0.21971) (xy 3.376676 -0.216662)
				(xy 3.361944 -0.213614) (xy 3.361182 -0.21336) (xy 3.354324 -0.212852) (xy 3.33502 -0.21082) (xy 3.333496 -0.21082)
				(xy 3.326638 -0.210058) (xy 3.325876 -0.210058) (xy 3.314954 -0.209804) (xy 3.312414 -0.20955) (xy 3.308858 -0.20955)
				(xy 3.299714 -0.20955) (xy 3.29819 -0.209296)
			)
			(stroke
				(width 0)
				(type default)
			)
			(fill yes)
			(layer "F.SilkS")
		)
		(fp_poly
			(pts
				(xy 6.835902 -0.209296) (xy 6.83387 -0.20955) (xy 6.831076 -0.20955) (xy 6.82117 -0.209804) (xy 6.818122 -0.209804)
				(xy 6.815074 -0.210312) (xy 6.808216 -0.21082) (xy 6.801866 -0.211582) (xy 6.797548 -0.21209) (xy 6.793992 -0.212344)
				(xy 6.791706 -0.212598) (xy 6.788912 -0.212852) (xy 6.784086 -0.21336) (xy 6.782562 -0.213614) (xy 6.77926 -0.213868)
				(xy 6.778244 -0.214122) (xy 6.77672 -0.214122) (xy 6.776466 -0.214122) (xy 6.77545 -0.214376) (xy 6.766052 -0.215138)
				(xy 6.765036 -0.215392) (xy 6.76148 -0.215646) (xy 6.757924 -0.216154) (xy 6.75386 -0.216408) (xy 6.748526 -0.21717)
				(xy 6.74497 -0.217932) (xy 6.743446 -0.218186) (xy 6.718046 -0.224536) (xy 6.697472 -0.229616) (xy 6.693916 -0.230378)
				(xy 6.687566 -0.231902) (xy 6.68528 -0.23241) (xy 6.685026 -0.232664) (xy 6.682232 -0.233172) (xy 6.679692 -0.234188)
				(xy 6.679184 -0.234442) (xy 6.67893 -0.234696) (xy 6.623812 -0.257556) (xy 6.621272 -0.258572) (xy 6.568186 -0.2921)
				(xy 6.566408 -0.293116) (xy 6.521196 -0.336042) (xy 6.519926 -0.337058) (xy 6.484112 -0.38862) (xy 6.482842 -0.390398)
				(xy 6.457696 -0.450596) (xy 6.45668 -0.45339) (xy 6.443218 -0.52451) (xy 6.442964 -0.52578) (xy 6.443218 -0.60833)
				(xy 6.45668 -0.688086) (xy 6.457696 -0.69469) (xy 6.482842 -0.767588) (xy 6.484112 -0.771144) (xy 6.519926 -0.836676)
				(xy 6.521196 -0.838708) (xy 6.566408 -0.896112) (xy 6.568186 -0.89789) (xy 6.621272 -0.945896) (xy 6.623812 -0.948436)
				(xy 6.67893 -0.984758) (xy 6.679184 -0.985012) (xy 6.679692 -0.98552) (xy 6.682232 -0.987044) (xy 6.685026 -0.988822)
				(xy 6.68528 -0.989076) (xy 6.687566 -0.990346) (xy 6.693916 -0.993394) (xy 6.697472 -0.995172) (xy 6.718046 -1.004824)
				(xy 6.743446 -1.017016) (xy 6.74497 -1.017778) (xy 6.748526 -1.019302) (xy 6.75386 -1.021842) (xy 6.757924 -1.023874)
				(xy 6.76148 -1.02489) (xy 6.765036 -1.02616) (xy 6.766052 -1.026414) (xy 6.77545 -1.029462) (xy 6.776466 -1.029716)
				(xy 6.77672 -1.02997) (xy 6.778244 -1.030478) (xy 6.77926 -1.030732) (xy 6.782562 -1.031748) (xy 6.784086 -1.03251)
				(xy 6.788912 -1.03378) (xy 6.791706 -1.034796) (xy 6.793992 -1.035558) (xy 6.797548 -1.036828) (xy 6.801866 -1.038098)
				(xy 6.808216 -1.04013) (xy 6.815074 -1.042416) (xy 6.818122 -1.043432) (xy 6.82117 -1.044448) (xy 6.831076 -1.047496)
				(xy 6.83387 -1.048512) (xy 6.835902 -1.04902) (xy 6.83768 -1.049274) (xy 6.846824 -1.051052) (xy 6.85038 -1.051814)
				(xy 6.852666 -1.052322) (xy 6.863588 -1.054608) (xy 6.864604 -1.054608) (xy 6.871462 -1.056132)
				(xy 6.872986 -1.056386) (xy 6.892036 -1.060196) (xy 6.898894 -1.06172) (xy 6.89991 -1.06172) (xy 6.914388 -1.064768)
				(xy 6.914642 -1.064768) (xy 6.928612 -1.066038) (xy 6.93039 -1.066292) (xy 6.93166 -1.066292) (xy 6.939026 -1.0668)
				(xy 6.944106 -1.067308) (xy 6.956806 -1.068578) (xy 6.964934 -1.06934) (xy 6.968236 -1.069594) (xy 6.981444 -1.070864)
				(xy 6.993128 -1.07188) (xy 6.99897 -1.072388) (xy 6.999732 -1.072388) (xy 7.020052 -1.072896) (xy 7.02056 -1.072896)
				(xy 7.028688 -1.072896) (xy 7.036308 -1.072896) (xy 7.044436 -1.072896) (xy 7.053326 -1.072642)
				(xy 7.067042 -1.071626) (xy 7.072884 -1.071372) (xy 7.077202 -1.071118) (xy 7.089394 -1.070102)
				(xy 7.106412 -1.068832) (xy 7.113016 -1.068324) (xy 7.11454 -1.068324) (xy 7.12089 -1.067308) (xy 7.126732 -1.066292)
				(xy 7.12851 -1.065784) (xy 7.132066 -1.065276) (xy 7.136384 -1.064514) (xy 7.138162 -1.06426) (xy 7.13994 -1.064006)
				(xy 7.140194 -1.064006) (xy 7.14121 -1.063752) (xy 7.141464 -1.063752) (xy 7.144258 -1.063244) (xy 7.148068 -1.062482)
				(xy 7.156196 -1.061212) (xy 7.162038 -1.060196) (xy 7.166356 -1.059434) (xy 7.168896 -1.058672)
				(xy 7.175754 -1.05664) (xy 7.177024 -1.056386) (xy 7.186422 -1.053592) (xy 7.189216 -1.05283) (xy 7.191248 -1.052322)
				(xy 7.191502 -1.052322) (xy 7.192772 -1.051814) (xy 7.194804 -1.051306) (xy 7.19709 -1.050544) (xy 7.200138 -1.049782)
				(xy 7.206488 -1.048004) (xy 7.20979 -1.046988) (xy 7.212076 -1.045972) (xy 7.212584 -1.045972) (xy 7.215124 -1.044702)
				(xy 7.21741 -1.04394) (xy 7.21868 -1.043432) (xy 7.219188 -1.043178) (xy 7.220966 -1.042416) (xy 7.233666 -1.037336)
				(xy 7.245604 -1.03251) (xy 7.246112 -1.032256) (xy 7.250684 -1.02997) (xy 7.261352 -1.024382) (xy 7.264908 -1.022858)
				(xy 7.264908 -1.023874) (xy 7.26694 -1.034796) (xy 7.272782 -1.067816) (xy 7.27329 -1.07061) (xy 7.275322 -1.082802)
				(xy 7.27583 -1.085088) (xy 7.278624 -1.109218) (xy 7.27583 -1.132078) (xy 7.275322 -1.135126) (xy 7.27329 -1.153922)
				(xy 7.272782 -1.157732) (xy 7.26694 -1.168654) (xy 7.264908 -1.17221) (xy 7.264908 -1.172464) (xy 7.261352 -1.178814)
				(xy 7.250684 -1.198118) (xy 7.246112 -1.20269) (xy 7.245604 -1.202944) (xy 7.233666 -1.214374) (xy 7.220966 -1.221994)
				(xy 7.219188 -1.223264) (xy 7.21868 -1.223518) (xy 7.21741 -1.22428) (xy 7.215124 -1.225804) (xy 7.212584 -1.227328)
				(xy 7.212076 -1.227582) (xy 7.20979 -1.228598) (xy 7.206488 -1.229614) (xy 7.200138 -1.232154) (xy 7.19709 -1.23317)
				(xy 7.194804 -1.234186) (xy 7.192772 -1.234948) (xy 7.191502 -1.235202) (xy 7.191502 -1.235456)
				(xy 7.191248 -1.235456) (xy 7.189216 -1.236218) (xy 7.186422 -1.237234) (xy 7.177024 -1.239012)
				(xy 7.175754 -1.23952) (xy 7.168896 -1.24079) (xy 7.166356 -1.241298) (xy 7.162038 -1.24206) (xy 7.156196 -1.24333)
				(xy 7.148068 -1.243584) (xy 7.144258 -1.243838) (xy 7.141464 -1.244092) (xy 7.14121 -1.244092) (xy 7.13994 -1.244092)
				(xy 7.138162 -1.244092) (xy 7.136384 -1.244346) (xy 7.132066 -1.2446) (xy 7.12851 -1.2446) (xy 7.126732 -1.244854)
				(xy 7.12089 -1.245108) (xy 7.11454 -1.245108) (xy 7.113016 -1.245108) (xy 7.106412 -1.244854) (xy 7.089394 -1.2446)
				(xy 7.077202 -1.244346) (xy 7.072884 -1.244092) (xy 7.067042 -1.243584) (xy 7.053326 -1.242314)
				(xy 7.044436 -1.241806) (xy 7.036308 -1.241044) (xy 7.03199 -1.24079) (xy 7.031482 -1.24079) (xy 7.028688 -1.240536)
				(xy 7.02056 -1.240028) (xy 7.020052 -1.239774) (xy 6.999732 -1.23825) (xy 6.99897 -1.237996) (xy 6.993128 -1.23698)
				(xy 6.981444 -1.234694) (xy 6.968236 -1.232408) (xy 6.964934 -1.2319) (xy 6.956806 -1.230376) (xy 6.944106 -1.227836)
				(xy 6.939026 -1.22682) (xy 6.93166 -1.22555) (xy 6.93039 -1.225296) (xy 6.928612 -1.224788) (xy 6.914642 -1.22047)
				(xy 6.914388 -1.22047) (xy 6.89991 -1.215898) (xy 6.898894 -1.215644) (xy 6.892036 -1.213612) (xy 6.872986 -1.207516)
				(xy 6.871462 -1.207008) (xy 6.864604 -1.204976) (xy 6.863588 -1.204722) (xy 6.852666 -1.199896)
				(xy 6.85038 -1.199134) (xy 6.846824 -1.19761) (xy 6.83768 -1.1938) (xy 6.835902 -1.193038) (xy 6.835902 -1.192784)
				(xy 6.83387 -1.192022) (xy 6.831076 -1.191006) (xy 6.82117 -1.186688) (xy 6.818122 -1.185418) (xy 6.815074 -1.184148)
				(xy 6.808216 -1.181354) (xy 6.801866 -1.17856) (xy 6.797548 -1.176782) (xy 6.793992 -1.175258) (xy 6.791706 -1.173988)
				(xy 6.788912 -1.172972) (xy 6.784086 -1.170686) (xy 6.782562 -1.16967) (xy 6.77926 -1.168146) (xy 6.778244 -1.167892)
				(xy 6.77672 -1.166876) (xy 6.776466 -1.166876) (xy 6.77545 -1.166368) (xy 6.766052 -1.161796) (xy 6.765036 -1.161796)
				(xy 6.76148 -1.171194) (xy 6.757924 -1.1811) (xy 6.75386 -1.191514) (xy 6.748526 -1.206246) (xy 6.74497 -1.215136)
				(xy 6.743446 -1.2192) (xy 6.718046 -1.287018) (xy 6.697472 -1.341374) (xy 6.693916 -1.351026) (xy 6.687566 -1.368044)
				(xy 6.68528 -1.373378) (xy 6.685026 -1.374394) (xy 6.682232 -1.382014) (xy 6.679692 -1.388364) (xy 6.679184 -1.389634)
				(xy 6.67893 -1.390904) (xy 6.679184 -1.391158) (xy 6.679692 -1.391412) (xy 6.682232 -1.392682) (xy 6.685026 -1.394206)
				(xy 6.68528 -1.39446) (xy 6.687566 -1.395476) (xy 6.693916 -1.398778) (xy 6.697472 -1.400556) (xy 6.718046 -1.410716)
				(xy 6.743446 -1.423162) (xy 6.74497 -1.423924) (xy 6.748526 -1.425194) (xy 6.75386 -1.42748) (xy 6.757924 -1.429258)
				(xy 6.765036 -1.432306) (xy 6.766052 -1.432814) (xy 6.77545 -1.436624) (xy 6.776466 -1.437132) (xy 6.77672 -1.437132)
				(xy 6.778244 -1.437894) (xy 6.77926 -1.438402) (xy 6.782562 -1.439672) (xy 6.784086 -1.440434) (xy 6.788912 -1.442466)
				(xy 6.791706 -1.443482) (xy 6.793992 -1.444498) (xy 6.797548 -1.446022) (xy 6.801866 -1.4478) (xy 6.808216 -1.450594)
				(xy 6.815074 -1.453388) (xy 6.818122 -1.454658) (xy 6.82117 -1.455928) (xy 6.831076 -1.459992) (xy 6.83387 -1.461262)
				(xy 6.835902 -1.462024) (xy 6.83768 -1.462786) (xy 6.846824 -1.46558) (xy 6.85038 -1.466596) (xy 6.852666 -1.467358)
				(xy 6.863588 -1.470914) (xy 6.864604 -1.471168) (xy 6.871462 -1.4732) (xy 6.872986 -1.473708) (xy 6.892036 -1.479296)
				(xy 6.898894 -1.481582) (xy 6.89991 -1.481836) (xy 6.914388 -1.486408) (xy 6.914642 -1.486408) (xy 6.928612 -1.490472)
				(xy 6.93039 -1.49098) (xy 6.93166 -1.491488) (xy 6.939026 -1.492758) (xy 6.944106 -1.493774) (xy 6.956806 -1.49606)
				(xy 6.964934 -1.497584) (xy 6.968236 -1.498092) (xy 6.981444 -1.500632) (xy 6.993128 -1.502664)
				(xy 6.99897 -1.50368) (xy 6.999732 -1.503934) (xy 7.020052 -1.50749) (xy 7.02056 -1.507744) (xy 7.028688 -1.509268)
				(xy 7.031482 -1.509522) (xy 7.03199 -1.509776) (xy 7.036308 -1.51003) (xy 7.044436 -1.510538) (xy 7.053326 -1.5113)
				(xy 7.067042 -1.512316) (xy 7.072884 -1.51257) (xy 7.077202 -1.512824) (xy 7.089394 -1.513586) (xy 7.106412 -1.514856)
				(xy 7.113016 -1.515364) (xy 7.11454 -1.515364) (xy 7.12089 -1.515872) (xy 7.126732 -1.51638) (xy 7.12851 -1.51638)
				(xy 7.132066 -1.516634) (xy 7.136384 -1.516888) (xy 7.138162 -1.517142) (xy 7.13994 -1.517142) (xy 7.140194 -1.517142)
				(xy 7.14121 -1.517396) (xy 7.141464 -1.517396) (xy 7.144258 -1.517396) (xy 7.148068 -1.517396) (xy 7.156196 -1.51765)
				(xy 7.162038 -1.51765) (xy 7.166356 -1.51765) (xy 7.168896 -1.51765) (xy 7.175754 -1.517904) (xy 7.177024 -1.51765)
				(xy 7.186422 -1.517396) (xy 7.189216 -1.517396) (xy 7.191248 -1.517396) (xy 7.191502 -1.517396)
				(xy 7.192772 -1.517142) (xy 7.194804 -1.517142) (xy 7.19709 -1.517142) (xy 7.200138 -1.516888) (xy 7.206488 -1.516888)
				(xy 7.20979 -1.516634) (xy 7.212076 -1.516634) (xy 7.212584 -1.516634) (xy 7.215124 -1.51638) (xy 7.21741 -1.51638)
				(xy 7.21868 -1.51638) (xy 7.220966 -1.51638) (xy 7.233666 -1.514856) (xy 7.245604 -1.513332) (xy 7.246112 -1.513332)
				(xy 7.250684 -1.512824) (xy 7.261352 -1.511554) (xy 7.264908 -1.511046) (xy 7.26694 -1.510792) (xy 7.272782 -1.510284)
				(xy 7.27329 -1.51003) (xy 7.275322 -1.509776) (xy 7.27583 -1.509776) (xy 7.278624 -1.509522) (xy 7.30504 -1.50622)
				(xy 7.345172 -1.49606) (xy 7.380478 -1.486916) (xy 7.39013 -1.482598) (xy 7.426452 -1.46685) (xy 7.446518 -1.458214)
				(xy 7.450074 -1.455928) (xy 7.456932 -1.451102) (xy 7.45871 -1.449832) (xy 7.46252 -1.447292) (xy 7.468108 -1.443482)
				(xy 7.474966 -1.43891) (xy 7.483348 -1.433322) (xy 7.492492 -1.426972) (xy 7.502398 -1.420368) (xy 7.513574 -1.408938)
				(xy 7.54761 -1.373886) (xy 7.55777 -1.357122) (xy 7.577328 -1.325118) (xy 7.581392 -1.318768) (xy 7.58571 -1.305814)
				(xy 7.592822 -1.284986) (xy 7.59841 -1.26873) (xy 7.602474 -1.257554) (xy 7.603236 -1.255268) (xy 7.604252 -1.246378)
				(xy 7.604506 -1.245362) (xy 7.605268 -1.238504) (xy 7.60857 -1.214374) (xy 7.61238 -1.183386) (xy 7.60857 -1.103884)
				(xy 7.605268 -1.082802) (xy 7.604506 -1.077722) (xy 7.604252 -1.076706) (xy 7.603236 -1.070356)
				(xy 7.602474 -1.065784) (xy 7.59841 -1.043686) (xy 7.592822 -1.011682) (xy 7.58571 -0.971042) (xy 7.581392 -0.945388)
				(xy 7.577328 -0.92329) (xy 7.55777 -0.811276) (xy 7.54761 -0.752348) (xy 7.513574 -0.5588) (xy 7.502398 -0.494792)
				(xy 7.492492 -0.43942) (xy 7.483348 -0.38608) (xy 7.474966 -0.33909) (xy 7.468108 -0.298958) (xy 7.46252 -0.267716)
				(xy 7.45871 -0.24638) (xy 7.456932 -0.23622) (xy 7.450074 -0.235712) (xy 7.126732 -0.235712) (xy 7.12851 -0.244602)
				(xy 7.132066 -0.265938) (xy 7.136384 -0.290068) (xy 7.138162 -0.300482) (xy 7.13994 -0.310642) (xy 7.140194 -0.311912)
				(xy 7.14121 -0.317754) (xy 7.141464 -0.319278) (xy 7.14121 -0.319278) (xy 7.140194 -0.318262) (xy 7.13994 -0.318008)
				(xy 7.138162 -0.316484) (xy 7.136384 -0.315214) (xy 7.132066 -0.312166) (xy 7.12851 -0.309372) (xy 7.126732 -0.308356)
				(xy 7.12089 -0.304038) (xy 7.11454 -0.299466) (xy 7.113016 -0.298196) (xy 7.106412 -0.293624) (xy 7.089394 -0.281178)
				(xy 7.077202 -0.274828) (xy 7.072884 -0.272288) (xy 7.067042 -0.26924) (xy 7.053326 -0.262128) (xy 7.044436 -0.257556)
				(xy 7.036308 -0.252984) (xy 7.03199 -0.250952) (xy 7.031482 -0.250698) (xy 7.028688 -0.249682) (xy 7.02056 -0.246888)
				(xy 7.020052 -0.246634) (xy 6.999732 -0.239268) (xy 6.99897 -0.239014) (xy 6.993128 -0.236728) (xy 6.981444 -0.232664)
				(xy 6.968236 -0.227838) (xy 6.964934 -0.227076) (xy 6.956806 -0.225298) (xy 6.944106 -0.222758)
				(xy 6.939026 -0.221742) (xy 6.93166 -0.220218) (xy 6.93039 -0.219964) (xy 6.928612 -0.21971) (xy 6.914642 -0.216662)
				(xy 6.914388 -0.216662) (xy 6.89991 -0.213614) (xy 6.898894 -0.21336) (xy 6.892036 -0.212598) (xy 6.872986 -0.21082)
				(xy 6.871462 -0.21082) (xy 6.864604 -0.210058) (xy 6.863588 -0.210058) (xy 6.852666 -0.209804) (xy 6.85038 -0.20955)
				(xy 6.846824 -0.20955) (xy 6.83768 -0.20955)
			)
			(stroke
				(width 0)
				(type default)
			)
			(fill yes)
			(layer "F.SilkS")
		)
	)
	(footprint ""
		(layer "F.Cu")
		(at 9.525 -26.289 180)
		(property "Reference" "R6"
			(at 1.651 0.35433 0)
			(unlocked yes)
			(layer "F.SilkS")
			(effects
				(font
					(size 0.7874 0.5842)
					(thickness 0.1524)
				)
			)
		)
		(property "Value" ""
			(at 0 0 180)
			(layer "F.Fab")
			(effects
				(font
					(size 1.27 1.27)
				)
			)
		)
		(duplicate_pad_numbers_are_jumpers no)
		(fp_line
			(start 0.7874 0.4064)
			(end -0.7874 0.4064)
			(stroke
				(width 0.1524)
				(type default)
			)
			(layer "F.SilkS")
		)
		(fp_line
			(start 0.7874 -0.4064)
			(end 0.7874 0.4064)
			(stroke
				(width 0.1524)
				(type default)
			)
			(layer "F.SilkS")
		)
		(fp_line
			(start -0.7874 0.4064)
			(end -0.7874 -0.4064)
			(stroke
				(width 0.1524)
				(type default)
			)
			(layer "F.SilkS")
		)
		(fp_line
			(start -0.7874 -0.4064)
			(end 0.7874 -0.4064)
			(stroke
				(width 0.1524)
				(type default)
			)
			(layer "F.SilkS")
		)
		(fp_line
			(start 0.67945 0.3048)
			(end 0.120396 0.3048)
			(stroke
				(width 0.1)
				(type default)
			)
			(layer "F.Fab")
		)
		(fp_line
			(start 0.67945 -0.3048)
			(end 0.67945 0.3048)
			(stroke
				(width 0.1)
				(type default)
			)
			(layer "F.Fab")
		)
		(fp_line
			(start 0.12065 -0.2794)
			(end 0.12065 -0.3048)
			(stroke
				(width 0.1)
				(type default)
			)
			(layer "F.Fab")
		)
		(fp_line
			(start 0.12065 -0.3048)
			(end 0.67945 -0.3048)
			(stroke
				(width 0.1)
				(type default)
			)
			(layer "F.Fab")
		)
		(fp_line
			(start 0.120396 0.3048)
			(end 0.120396 0.2794)
			(stroke
				(width 0.1)
				(type default)
			)
			(layer "F.Fab")
		)
		(fp_line
			(start 0.120396 0.2794)
			(end -0.12065 0.2794)
			(stroke
				(width 0.1)
				(type default)
			)
			(layer "F.Fab")
		)
		(fp_line
			(start -0.12065 0.3048)
			(end -0.67945 0.3048)
			(stroke
				(width 0.1)
				(type default)
			)
			(layer "F.Fab")
		)
		(fp_line
			(start -0.12065 0.2794)
			(end -0.12065 0.3048)
			(stroke
				(width 0.1)
				(type default)
			)
			(layer "F.Fab")
		)
		(fp_line
			(start -0.12065 -0.2794)
			(end 0.12065 -0.2794)
			(stroke
				(width 0.1)
				(type default)
			)
			(layer "F.Fab")
		)
		(fp_line
			(start -0.12065 -0.305054)
			(end -0.12065 -0.2794)
			(stroke
				(width 0.1)
				(type default)
			)
			(layer "F.Fab")
		)
		(fp_line
			(start -0.67945 0.3048)
			(end -0.67945 -0.305054)
			(stroke
				(width 0.1)
				(type default)
			)
			(layer "F.Fab")
		)
		(fp_line
			(start -0.67945 -0.305054)
			(end -0.12065 -0.305054)
			(stroke
				(width 0.1)
				(type default)
			)
			(layer "F.Fab")
		)
		(pad "1" smd circle
			(at -0.40005 0 180)
			(size 0 0)
			(layers "F.Cu" "F.Mask" "F.Paste")
			(net "P5V_STBY")
		)
		(pad "2" smd circle
			(at 0.40005 0 180)
			(size 0 0)
			(layers "F.Cu" "F.Mask" "F.Paste")
			(net "SYSTEM_FAULT_ID_LED_R1_N")
		)
	)
	(footprint ""
		(layer "F.Cu")
		(at 3.048 -29.083)
		(property "Reference" "R9"
			(at -0.381 -2.13233 0)
			(unlocked yes)
			(layer "F.SilkS")
			(effects
				(font
					(size 0.7874 0.5842)
					(thickness 0.1524)
				)
			)
		)
		(property "Value" ""
			(at 0 0 0)
			(layer "F.Fab")
			(effects
				(font
					(size 1.27 1.27)
				)
			)
		)
		(duplicate_pad_numbers_are_jumpers no)
		(fp_line
			(start -0.7874 -0.4064)
			(end 0.7874 -0.4064)
			(stroke
				(width 0.1524)
				(type default)
			)
			(layer "F.SilkS")
		)
		(fp_line
			(start -0.7874 0.4064)
			(end -0.7874 -0.4064)
			(stroke
				(width 0.1524)
				(type default)
			)
			(layer "F.SilkS")
		)
		(fp_line
			(start 0.7874 -0.4064)
			(end 0.7874 0.4064)
			(stroke
				(width 0.1524)
				(type default)
			)
			(layer "F.SilkS")
		)
		(fp_line
			(start 0.7874 0.4064)
			(end -0.7874 0.4064)
			(stroke
				(width 0.1524)
				(type default)
			)
			(layer "F.SilkS")
		)
		(fp_line
			(start -0.67945 -0.305054)
			(end -0.12065 -0.305054)
			(stroke
				(width 0.1)
				(type default)
			)
			(layer "F.Fab")
		)
		(fp_line
			(start -0.67945 0.3048)
			(end -0.67945 -0.305054)
			(stroke
				(width 0.1)
				(type default)
			)
			(layer "F.Fab")
		)
		(fp_line
			(start -0.12065 -0.305054)
			(end -0.12065 -0.2794)
			(stroke
				(width 0.1)
				(type default)
			)
			(layer "F.Fab")
		)
		(fp_line
			(start -0.12065 -0.2794)
			(end 0.12065 -0.2794)
			(stroke
				(width 0.1)
				(type default)
			)
			(layer "F.Fab")
		)
		(fp_line
			(start -0.12065 0.2794)
			(end -0.12065 0.3048)
			(stroke
				(width 0.1)
				(type default)
			)
			(layer "F.Fab")
		)
		(fp_line
			(start -0.12065 0.3048)
			(end -0.67945 0.3048)
			(stroke
				(width 0.1)
				(type default)
			)
			(layer "F.Fab")
		)
		(fp_line
			(start 0.120396 0.2794)
			(end -0.12065 0.2794)
			(stroke
				(width 0.1)
				(type default)
			)
			(layer "F.Fab")
		)
		(fp_line
			(start 0.120396 0.3048)
			(end 0.120396 0.2794)
			(stroke
				(width 0.1)
				(type default)
			)
			(layer "F.Fab")
		)
		(fp_line
			(start 0.12065 -0.3048)
			(end 0.67945 -0.3048)
			(stroke
				(width 0.1)
				(type default)
			)
			(layer "F.Fab")
		)
		(fp_line
			(start 0.12065 -0.2794)
			(end 0.12065 -0.3048)
			(stroke
				(width 0.1)
				(type default)
			)
			(layer "F.Fab")
		)
		(fp_line
			(start 0.67945 -0.3048)
			(end 0.67945 0.3048)
			(stroke
				(width 0.1)
				(type default)
			)
			(layer "F.Fab")
		)
		(fp_line
			(start 0.67945 0.3048)
			(end 0.120396 0.3048)
			(stroke
				(width 0.1)
				(type default)
			)
			(layer "F.Fab")
		)
		(pad "1" smd circle
			(at -0.40005 0)
			(size 0 0)
			(layers "F.Cu" "F.Mask" "F.Paste")
			(net "P3V3_STBY")
		)
		(pad "2" smd circle
			(at 0.40005 0)
			(size 0 0)
			(layers "F.Cu" "F.Mask" "F.Paste")
			(net "PWR_LED_R1")
		)
	)
	(footprint ""
		(layer "F.Cu")
		(at 35.941 -28.829)
		(property "Reference" "C9"
			(at 0.762 -6.83133 0)
			(unlocked yes)
			(layer "F.SilkS")
			(effects
				(font
					(size 0.7874 0.5842)
					(thickness 0.1524)
				)
				(justify left)
			)
		)
		(property "Value" ""
			(at 0 0 0)
			(layer "F.Fab")
			(effects
				(font
					(size 1.27 1.27)
				)
			)
		)
		(duplicate_pad_numbers_are_jumpers no)
		(fp_line
			(start -1.524 -0.762)
			(end 1.524 -0.762)
			(stroke
				(width 0.1524)
				(type default)
			)
			(layer "F.SilkS")
		)
		(fp_line
			(start -1.524 0.762)
			(end -1.524 -0.762)
			(stroke
				(width 0.1524)
				(type default)
			)
			(layer "F.SilkS")
		)
		(fp_line
			(start 1.524 -0.762)
			(end 1.524 0.762)
			(stroke
				(width 0.1524)
				(type default)
			)
			(layer "F.SilkS")
		)
		(fp_line
			(start 1.524 0.762)
			(end -1.524 0.762)
			(stroke
				(width 0.1524)
				(type default)
			)
			(layer "F.SilkS")
		)
		(fp_line
			(start -1.1049 -0.724916)
			(end -1.1049 0.724916)
			(stroke
				(width 0.1)
				(type default)
			)
			(layer "F.Fab")
		)
		(fp_line
			(start -1.1049 0.724916)
			(end 1.1049 0.724916)
			(stroke
				(width 0.1)
				(type default)
			)
			(layer "F.Fab")
		)
		(fp_line
			(start 1.1049 -0.724916)
			(end -1.1049 -0.724916)
			(stroke
				(width 0.1)
				(type default)
			)
			(layer "F.Fab")
		)
		(fp_line
			(start 1.1049 0.724916)
			(end 1.1049 -0.724916)
			(stroke
				(width 0.1)
				(type default)
			)
			(layer "F.Fab")
		)
		(pad "1" smd rect
			(at -0.889 0 180)
			(size 1.016 1.27)
			(layers "F.Cu" "F.Mask" "F.Paste")
			(net "P5V_STBY_DEBUG")
		)
		(pad "2" smd rect
			(at 0.889 0 180)
			(size 1.016 1.27)
			(layers "F.Cu" "F.Mask" "F.Paste")
			(net "GND")
		)
	)
	(footprint ""
		(layer "F.Cu")
		(at 3.937 -46.736 180)
		(property "Reference" "R61"
			(at 2.413 -0.15367 0)
			(unlocked yes)
			(layer "F.SilkS")
			(effects
				(font
					(size 0.7874 0.5842)
					(thickness 0.1524)
				)
			)
		)
		(property "Value" ""
			(at 0 0 180)
			(layer "F.Fab")
			(effects
				(font
					(size 1.27 1.27)
				)
			)
		)
		(duplicate_pad_numbers_are_jumpers no)
		(fp_line
			(start 0.7874 0.4064)
			(end -0.7874 0.4064)
			(stroke
				(width 0.1524)
				(type default)
			)
			(layer "F.SilkS")
		)
		(fp_line
			(start 0.7874 -0.4064)
			(end 0.7874 0.4064)
			(stroke
				(width 0.1524)
				(type default)
			)
			(layer "F.SilkS")
		)
		(fp_line
			(start -0.7874 0.4064)
			(end -0.7874 -0.4064)
			(stroke
				(width 0.1524)
				(type default)
			)
			(layer "F.SilkS")
		)
		(fp_line
			(start -0.7874 -0.4064)
			(end 0.7874 -0.4064)
			(stroke
				(width 0.1524)
				(type default)
			)
			(layer "F.SilkS")
		)
		(fp_line
			(start 0.67945 0.3048)
			(end 0.120396 0.3048)
			(stroke
				(width 0.1)
				(type default)
			)
			(layer "F.Fab")
		)
		(fp_line
			(start 0.67945 -0.3048)
			(end 0.67945 0.3048)
			(stroke
				(width 0.1)
				(type default)
			)
			(layer "F.Fab")
		)
		(fp_line
			(start 0.12065 -0.2794)
			(end 0.12065 -0.3048)
			(stroke
				(width 0.1)
				(type default)
			)
			(layer "F.Fab")
		)
		(fp_line
			(start 0.12065 -0.3048)
			(end 0.67945 -0.3048)
			(stroke
				(width 0.1)
				(type default)
			)
			(layer "F.Fab")
		)
		(fp_line
			(start 0.120396 0.3048)
			(end 0.120396 0.2794)
			(stroke
				(width 0.1)
				(type default)
			)
			(layer "F.Fab")
		)
		(fp_line
			(start 0.120396 0.2794)
			(end -0.12065 0.2794)
			(stroke
				(width 0.1)
				(type default)
			)
			(layer "F.Fab")
		)
		(fp_line
			(start -0.12065 0.3048)
			(end -0.67945 0.3048)
			(stroke
				(width 0.1)
				(type default)
			)
			(layer "F.Fab")
		)
		(fp_line
			(start -0.12065 0.2794)
			(end -0.12065 0.3048)
			(stroke
				(width 0.1)
				(type default)
			)
			(layer "F.Fab")
		)
		(fp_line
			(start -0.12065 -0.2794)
			(end 0.12065 -0.2794)
			(stroke
				(width 0.1)
				(type default)
			)
			(layer "F.Fab")
		)
		(fp_line
			(start -0.12065 -0.305054)
			(end -0.12065 -0.2794)
			(stroke
				(width 0.1)
				(type default)
			)
			(layer "F.Fab")
		)
		(fp_line
			(start -0.67945 0.3048)
			(end -0.67945 -0.305054)
			(stroke
				(width 0.1)
				(type default)
			)
			(layer "F.Fab")
		)
		(fp_line
			(start -0.67945 -0.305054)
			(end -0.12065 -0.305054)
			(stroke
				(width 0.1)
				(type default)
			)
			(layer "F.Fab")
		)
		(pad "1" smd circle
			(at -0.40005 0 180)
			(size 0 0)
			(layers "F.Cu" "F.Mask" "F.Paste")
			(net "PD_FRU_A2")
		)
		(pad "2" smd circle
			(at 0.40005 0 180)
			(size 0 0)
			(layers "F.Cu" "F.Mask" "F.Paste")
			(net "GND")
		)
	)
	(footprint ""
		(layer "F.Cu")
		(at 19.685 -63.373 90)
		(property "Reference" "R65"
			(at 0.762 -2.25933 90)
			(unlocked yes)
			(layer "F.SilkS")
			(effects
				(font
					(size 0.7874 0.5842)
					(thickness 0.1524)
				)
			)
		)
		(property "Value" ""
			(at 0 0 90)
			(layer "F.Fab")
			(effects
				(font
					(size 1.27 1.27)
				)
			)
		)
		(duplicate_pad_numbers_are_jumpers no)
		(fp_line
			(start 0.7874 -0.4064)
			(end 0.7874 0.4064)
			(stroke
				(width 0.1524)
				(type default)
			)
			(layer "F.SilkS")
		)
		(fp_line
			(start -0.7874 -0.4064)
			(end 0.7874 -0.4064)
			(stroke
				(width 0.1524)
				(type default)
			)
			(layer "F.SilkS")
		)
		(fp_line
			(start 0.7874 0.4064)
			(end -0.7874 0.4064)
			(stroke
				(width 0.1524)
				(type default)
			)
			(layer "F.SilkS")
		)
		(fp_line
			(start -0.7874 0.4064)
			(end -0.7874 -0.4064)
			(stroke
				(width 0.1524)
				(type default)
			)
			(layer "F.SilkS")
		)
		(fp_line
			(start -0.12065 -0.305054)
			(end -0.12065 -0.2794)
			(stroke
				(width 0.1)
				(type default)
			)
			(layer "F.Fab")
		)
		(fp_line
			(start -0.67945 -0.305054)
			(end -0.12065 -0.305054)
			(stroke
				(width 0.1)
				(type default)
			)
			(layer "F.Fab")
		)
		(fp_line
			(start 0.67945 -0.3048)
			(end 0.67945 0.3048)
			(stroke
				(width 0.1)
				(type default)
			)
			(layer "F.Fab")
		)
		(fp_line
			(start 0.12065 -0.3048)
			(end 0.67945 -0.3048)
			(stroke
				(width 0.1)
				(type default)
			)
			(layer "F.Fab")
		)
		(fp_line
			(start 0.12065 -0.2794)
			(end 0.12065 -0.3048)
			(stroke
				(width 0.1)
				(type default)
			)
			(layer "F.Fab")
		)
		(fp_line
			(start -0.12065 -0.2794)
			(end 0.12065 -0.2794)
			(stroke
				(width 0.1)
				(type default)
			)
			(layer "F.Fab")
		)
		(fp_line
			(start 0.120396 0.2794)
			(end -0.12065 0.2794)
			(stroke
				(width 0.1)
				(type default)
			)
			(layer "F.Fab")
		)
		(fp_line
			(start -0.12065 0.2794)
			(end -0.12065 0.3048)
			(stroke
				(width 0.1)
				(type default)
			)
			(layer "F.Fab")
		)
		(fp_line
			(start 0.67945 0.3048)
			(end 0.120396 0.3048)
			(stroke
				(width 0.1)
				(type default)
			)
			(layer "F.Fab")
		)
		(fp_line
			(start 0.120396 0.3048)
			(end 0.120396 0.2794)
			(stroke
				(width 0.1)
				(type default)
			)
			(layer "F.Fab")
		)
		(fp_line
			(start -0.12065 0.3048)
			(end -0.67945 0.3048)
			(stroke
				(width 0.1)
				(type default)
			)
			(layer "F.Fab")
		)
		(fp_line
			(start -0.67945 0.3048)
			(end -0.67945 -0.305054)
			(stroke
				(width 0.1)
				(type default)
			)
			(layer "F.Fab")
		)
		(pad "1" smd circle
			(at -0.40005 0 90)
			(size 0 0)
			(layers "F.Cu" "F.Mask" "F.Paste")
			(net "UART_DEBUG_R_TX")
		)
		(pad "2" smd circle
			(at 0.40005 0 90)
			(size 0 0)
			(layers "F.Cu" "F.Mask" "F.Paste")
			(net "UART_DEBUG_TX")
		)
	)
	(footprint ""
		(layer "F.Cu")
		(at 18.415 -57.785)
		(property "Reference" "R25"
			(at 3.81 0.02667 0)
			(unlocked yes)
			(layer "F.SilkS")
			(effects
				(font
					(size 0.7874 0.5842)
					(thickness 0.1524)
				)
			)
		)
		(property "Value" ""
			(at 0 0 0)
			(layer "F.Fab")
			(effects
				(font
					(size 1.27 1.27)
				)
			)
		)
		(duplicate_pad_numbers_are_jumpers no)
		(fp_line
			(start -0.7874 -0.4064)
			(end 0.7874 -0.4064)
			(stroke
				(width 0.1524)
				(type default)
			)
			(layer "F.SilkS")
		)
		(fp_line
			(start -0.7874 0.4064)
			(end -0.7874 -0.4064)
			(stroke
				(width 0.1524)
				(type default)
			)
			(layer "F.SilkS")
		)
		(fp_line
			(start 0.7874 -0.4064)
			(end 0.7874 0.4064)
			(stroke
				(width 0.1524)
				(type default)
			)
			(layer "F.SilkS")
		)
		(fp_line
			(start 0.7874 0.4064)
			(end -0.7874 0.4064)
			(stroke
				(width 0.1524)
				(type default)
			)
			(layer "F.SilkS")
		)
		(fp_line
			(start -0.67945 -0.305054)
			(end -0.12065 -0.305054)
			(stroke
				(width 0.1)
				(type default)
			)
			(layer "F.Fab")
		)
		(fp_line
			(start -0.67945 0.3048)
			(end -0.67945 -0.305054)
			(stroke
				(width 0.1)
				(type default)
			)
			(layer "F.Fab")
		)
		(fp_line
			(start -0.12065 -0.305054)
			(end -0.12065 -0.2794)
			(stroke
				(width 0.1)
				(type default)
			)
			(layer "F.Fab")
		)
		(fp_line
			(start -0.12065 -0.2794)
			(end 0.12065 -0.2794)
			(stroke
				(width 0.1)
				(type default)
			)
			(layer "F.Fab")
		)
		(fp_line
			(start -0.12065 0.2794)
			(end -0.12065 0.3048)
			(stroke
				(width 0.1)
				(type default)
			)
			(layer "F.Fab")
		)
		(fp_line
			(start -0.12065 0.3048)
			(end -0.67945 0.3048)
			(stroke
				(width 0.1)
				(type default)
			)
			(layer "F.Fab")
		)
		(fp_line
			(start 0.120396 0.2794)
			(end -0.12065 0.2794)
			(stroke
				(width 0.1)
				(type default)
			)
			(layer "F.Fab")
		)
		(fp_line
			(start 0.120396 0.3048)
			(end 0.120396 0.2794)
			(stroke
				(width 0.1)
				(type default)
			)
			(layer "F.Fab")
		)
		(fp_line
			(start 0.12065 -0.3048)
			(end 0.67945 -0.3048)
			(stroke
				(width 0.1)
				(type default)
			)
			(layer "F.Fab")
		)
		(fp_line
			(start 0.12065 -0.2794)
			(end 0.12065 -0.3048)
			(stroke
				(width 0.1)
				(type default)
			)
			(layer "F.Fab")
		)
		(fp_line
			(start 0.67945 -0.3048)
			(end 0.67945 0.3048)
			(stroke
				(width 0.1)
				(type default)
			)
			(layer "F.Fab")
		)
		(fp_line
			(start 0.67945 0.3048)
			(end 0.120396 0.3048)
			(stroke
				(width 0.1)
				(type default)
			)
			(layer "F.Fab")
		)
		(pad "1" smd circle
			(at -0.40005 0)
			(size 0 0)
			(layers "F.Cu" "F.Mask" "F.Paste")
			(net "PCA9539_A0")
		)
		(pad "2" smd circle
			(at 0.40005 0)
			(size 0 0)
			(layers "F.Cu" "F.Mask" "F.Paste")
			(net "GND")
		)
	)
	(footprint ""
		(layer "F.Cu")
		(at 36.703 -24.384)
		(property "Reference" "R39"
			(at -2.032 0.02667 0)
			(unlocked yes)
			(layer "F.SilkS")
			(effects
				(font
					(size 0.7874 0.5842)
					(thickness 0.1524)
				)
			)
		)
		(property "Value" ""
			(at 0 0 0)
			(layer "F.Fab")
			(effects
				(font
					(size 1.27 1.27)
				)
			)
		)
		(duplicate_pad_numbers_are_jumpers no)
		(fp_line
			(start -0.7874 -0.4064)
			(end 0.7874 -0.4064)
			(stroke
				(width 0.1524)
				(type default)
			)
			(layer "F.SilkS")
		)
		(fp_line
			(start -0.7874 0.4064)
			(end -0.7874 -0.4064)
			(stroke
				(width 0.1524)
				(type default)
			)
			(layer "F.SilkS")
		)
		(fp_line
			(start 0.7874 -0.4064)
			(end 0.7874 0.4064)
			(stroke
				(width 0.1524)
				(type default)
			)
			(layer "F.SilkS")
		)
		(fp_line
			(start 0.7874 0.4064)
			(end -0.7874 0.4064)
			(stroke
				(width 0.1524)
				(type default)
			)
			(layer "F.SilkS")
		)
		(fp_line
			(start -0.67945 -0.305054)
			(end -0.12065 -0.305054)
			(stroke
				(width 0.1)
				(type default)
			)
			(layer "F.Fab")
		)
		(fp_line
			(start -0.67945 0.3048)
			(end -0.67945 -0.305054)
			(stroke
				(width 0.1)
				(type default)
			)
			(layer "F.Fab")
		)
		(fp_line
			(start -0.12065 -0.305054)
			(end -0.12065 -0.2794)
			(stroke
				(width 0.1)
				(type default)
			)
			(layer "F.Fab")
		)
		(fp_line
			(start -0.12065 -0.2794)
			(end 0.12065 -0.2794)
			(stroke
				(width 0.1)
				(type default)
			)
			(layer "F.Fab")
		)
		(fp_line
			(start -0.12065 0.2794)
			(end -0.12065 0.3048)
			(stroke
				(width 0.1)
				(type default)
			)
			(layer "F.Fab")
		)
		(fp_line
			(start -0.12065 0.3048)
			(end -0.67945 0.3048)
			(stroke
				(width 0.1)
				(type default)
			)
			(layer "F.Fab")
		)
		(fp_line
			(start 0.120396 0.2794)
			(end -0.12065 0.2794)
			(stroke
				(width 0.1)
				(type default)
			)
			(layer "F.Fab")
		)
		(fp_line
			(start 0.120396 0.3048)
			(end 0.120396 0.2794)
			(stroke
				(width 0.1)
				(type default)
			)
			(layer "F.Fab")
		)
		(fp_line
			(start 0.12065 -0.3048)
			(end 0.67945 -0.3048)
			(stroke
				(width 0.1)
				(type default)
			)
			(layer "F.Fab")
		)
		(fp_line
			(start 0.12065 -0.2794)
			(end 0.12065 -0.3048)
			(stroke
				(width 0.1)
				(type default)
			)
			(layer "F.Fab")
		)
		(fp_line
			(start 0.67945 -0.3048)
			(end 0.67945 0.3048)
			(stroke
				(width 0.1)
				(type default)
			)
			(layer "F.Fab")
		)
		(fp_line
			(start 0.67945 0.3048)
			(end 0.120396 0.3048)
			(stroke
				(width 0.1)
				(type default)
			)
			(layer "F.Fab")
		)
		(pad "1" smd circle
			(at -0.40005 0)
			(size 0 0)
			(layers "F.Cu" "F.Mask" "F.Paste")
			(net "THERMAL_ADDR_A2")
		)
		(pad "2" smd circle
			(at 0.40005 0)
			(size 0 0)
			(layers "F.Cu" "F.Mask" "F.Paste")
			(net "GND")
		)
	)
	(footprint ""
		(layer "F.Cu")
		(at 13.462 -27.94 180)
		(property "Reference" "R44"
			(at -0.127 0.98933 0)
			(unlocked yes)
			(layer "F.SilkS")
			(effects
				(font
					(size 0.7874 0.5842)
					(thickness 0.1524)
				)
			)
		)
		(property "Value" ""
			(at 0 0 180)
			(layer "F.Fab")
			(effects
				(font
					(size 1.27 1.27)
				)
			)
		)
		(duplicate_pad_numbers_are_jumpers no)
		(fp_line
			(start 0.7874 0.4064)
			(end -0.7874 0.4064)
			(stroke
				(width 0.1524)
				(type default)
			)
			(layer "F.SilkS")
		)
		(fp_line
			(start 0.7874 -0.4064)
			(end 0.7874 0.4064)
			(stroke
				(width 0.1524)
				(type default)
			)
			(layer "F.SilkS")
		)
		(fp_line
			(start -0.7874 0.4064)
			(end -0.7874 -0.4064)
			(stroke
				(width 0.1524)
				(type default)
			)
			(layer "F.SilkS")
		)
		(fp_line
			(start -0.7874 -0.4064)
			(end 0.7874 -0.4064)
			(stroke
				(width 0.1524)
				(type default)
			)
			(layer "F.SilkS")
		)
		(fp_line
			(start 0.67945 0.3048)
			(end 0.120396 0.3048)
			(stroke
				(width 0.1)
				(type default)
			)
			(layer "F.Fab")
		)
		(fp_line
			(start 0.67945 -0.3048)
			(end 0.67945 0.3048)
			(stroke
				(width 0.1)
				(type default)
			)
			(layer "F.Fab")
		)
		(fp_line
			(start 0.12065 -0.2794)
			(end 0.12065 -0.3048)
			(stroke
				(width 0.1)
				(type default)
			)
			(layer "F.Fab")
		)
		(fp_line
			(start 0.12065 -0.3048)
			(end 0.67945 -0.3048)
			(stroke
				(width 0.1)
				(type default)
			)
			(layer "F.Fab")
		)
		(fp_line
			(start 0.120396 0.3048)
			(end 0.120396 0.2794)
			(stroke
				(width 0.1)
				(type default)
			)
			(layer "F.Fab")
		)
		(fp_line
			(start 0.120396 0.2794)
			(end -0.12065 0.2794)
			(stroke
				(width 0.1)
				(type default)
			)
			(layer "F.Fab")
		)
		(fp_line
			(start -0.12065 0.3048)
			(end -0.67945 0.3048)
			(stroke
				(width 0.1)
				(type default)
			)
			(layer "F.Fab")
		)
		(fp_line
			(start -0.12065 0.2794)
			(end -0.12065 0.3048)
			(stroke
				(width 0.1)
				(type default)
			)
			(layer "F.Fab")
		)
		(fp_line
			(start -0.12065 -0.2794)
			(end 0.12065 -0.2794)
			(stroke
				(width 0.1)
				(type default)
			)
			(layer "F.Fab")
		)
		(fp_line
			(start -0.12065 -0.305054)
			(end -0.12065 -0.2794)
			(stroke
				(width 0.1)
				(type default)
			)
			(layer "F.Fab")
		)
		(fp_line
			(start -0.67945 0.3048)
			(end -0.67945 -0.305054)
			(stroke
				(width 0.1)
				(type default)
			)
			(layer "F.Fab")
		)
		(fp_line
			(start -0.67945 -0.305054)
			(end -0.12065 -0.305054)
			(stroke
				(width 0.1)
				(type default)
			)
			(layer "F.Fab")
		)
		(pad "1" smd circle
			(at -0.40005 0 180)
			(size 0 0)
			(layers "F.Cu" "F.Mask" "F.Paste")
			(net "P3V3_STBY")
		)
		(pad "2" smd circle
			(at 0.40005 0 180)
			(size 0 0)
			(layers "F.Cu" "F.Mask" "F.Paste")
			(net "PRSNT_DBV2_USB_N")
		)
	)
	(footprint ""
		(layer "F.Cu")
		(at 29.591 -33.02)
		(property "Reference" "C13"
			(at -2.032 0.02667 0)
			(unlocked yes)
			(layer "F.SilkS")
			(effects
				(font
					(size 0.7874 0.5842)
					(thickness 0.1524)
				)
			)
		)
		(property "Value" ""
			(at 0 0 0)
			(layer "F.Fab")
			(effects
				(font
					(size 1.27 1.27)
				)
			)
		)
		(duplicate_pad_numbers_are_jumpers no)
		(fp_line
			(start -0.7874 -0.4064)
			(end 0.7874 -0.4064)
			(stroke
				(width 0.1524)
				(type default)
			)
			(layer "F.SilkS")
		)
		(fp_line
			(start -0.7874 0.4064)
			(end -0.7874 -0.4064)
			(stroke
				(width 0.1524)
				(type default)
			)
			(layer "F.SilkS")
		)
		(fp_line
			(start 0.7874 -0.4064)
			(end 0.7874 0.4064)
			(stroke
				(width 0.1524)
				(type default)
			)
			(layer "F.SilkS")
		)
		(fp_line
			(start 0.7874 0.4064)
			(end -0.7874 0.4064)
			(stroke
				(width 0.1524)
				(type default)
			)
			(layer "F.SilkS")
		)
		(fp_line
			(start -0.67945 -0.305054)
			(end -0.12065 -0.305054)
			(stroke
				(width 0.1)
				(type default)
			)
			(layer "F.Fab")
		)
		(fp_line
			(start -0.67945 0.3048)
			(end -0.67945 -0.305054)
			(stroke
				(width 0.1)
				(type default)
			)
			(layer "F.Fab")
		)
		(fp_line
			(start -0.12065 -0.305054)
			(end -0.12065 -0.2794)
			(stroke
				(width 0.1)
				(type default)
			)
			(layer "F.Fab")
		)
		(fp_line
			(start -0.12065 -0.2794)
			(end 0.12065 -0.2794)
			(stroke
				(width 0.1)
				(type default)
			)
			(layer "F.Fab")
		)
		(fp_line
			(start -0.12065 0.2794)
			(end -0.12065 0.3048)
			(stroke
				(width 0.1)
				(type default)
			)
			(layer "F.Fab")
		)
		(fp_line
			(start -0.12065 0.3048)
			(end -0.67945 0.3048)
			(stroke
				(width 0.1)
				(type default)
			)
			(layer "F.Fab")
		)
		(fp_line
			(start 0.120396 0.2794)
			(end -0.12065 0.2794)
			(stroke
				(width 0.1)
				(type default)
			)
			(layer "F.Fab")
		)
		(fp_line
			(start 0.120396 0.3048)
			(end 0.120396 0.2794)
			(stroke
				(width 0.1)
				(type default)
			)
			(layer "F.Fab")
		)
		(fp_line
			(start 0.12065 -0.3048)
			(end 0.67945 -0.3048)
			(stroke
				(width 0.1)
				(type default)
			)
			(layer "F.Fab")
		)
		(fp_line
			(start 0.12065 -0.2794)
			(end 0.12065 -0.3048)
			(stroke
				(width 0.1)
				(type default)
			)
			(layer "F.Fab")
		)
		(fp_line
			(start 0.67945 -0.3048)
			(end 0.67945 0.3048)
			(stroke
				(width 0.1)
				(type default)
			)
			(layer "F.Fab")
		)
		(fp_line
			(start 0.67945 0.3048)
			(end 0.120396 0.3048)
			(stroke
				(width 0.1)
				(type default)
			)
			(layer "F.Fab")
		)
		(pad "1" smd circle
			(at -0.40005 0)
			(size 0 0)
			(layers "F.Cu" "F.Mask" "F.Paste")
			(net "P5V_STBY")
		)
		(pad "2" smd circle
			(at 0.40005 0)
			(size 0 0)
			(layers "F.Cu" "F.Mask" "F.Paste")
			(net "GND")
		)
	)
	(footprint ""
		(layer "F.Cu")
		(at 17.145 -62.103)
		(property "Reference" "C5"
			(at 1.651 0.15367 0)
			(unlocked yes)
			(layer "F.SilkS")
			(effects
				(font
					(size 0.7874 0.5842)
					(thickness 0.1524)
				)
			)
		)
		(property "Value" ""
			(at 0 0 0)
			(layer "F.Fab")
			(effects
				(font
					(size 1.27 1.27)
				)
			)
		)
		(duplicate_pad_numbers_are_jumpers no)
		(fp_line
			(start -0.7874 -0.4064)
			(end 0.7874 -0.4064)
			(stroke
				(width 0.1524)
				(type default)
			)
			(layer "F.SilkS")
		)
		(fp_line
			(start -0.7874 0.4064)
			(end -0.7874 -0.4064)
			(stroke
				(width 0.1524)
				(type default)
			)
			(layer "F.SilkS")
		)
		(fp_line
			(start 0.7874 -0.4064)
			(end 0.7874 0.4064)
			(stroke
				(width 0.1524)
				(type default)
			)
			(layer "F.SilkS")
		)
		(fp_line
			(start 0.7874 0.4064)
			(end -0.7874 0.4064)
			(stroke
				(width 0.1524)
				(type default)
			)
			(layer "F.SilkS")
		)
		(fp_line
			(start -0.67945 -0.305054)
			(end -0.12065 -0.305054)
			(stroke
				(width 0.1)
				(type default)
			)
			(layer "F.Fab")
		)
		(fp_line
			(start -0.67945 0.3048)
			(end -0.67945 -0.305054)
			(stroke
				(width 0.1)
				(type default)
			)
			(layer "F.Fab")
		)
		(fp_line
			(start -0.12065 -0.305054)
			(end -0.12065 -0.2794)
			(stroke
				(width 0.1)
				(type default)
			)
			(layer "F.Fab")
		)
		(fp_line
			(start -0.12065 -0.2794)
			(end 0.12065 -0.2794)
			(stroke
				(width 0.1)
				(type default)
			)
			(layer "F.Fab")
		)
		(fp_line
			(start -0.12065 0.2794)
			(end -0.12065 0.3048)
			(stroke
				(width 0.1)
				(type default)
			)
			(layer "F.Fab")
		)
		(fp_line
			(start -0.12065 0.3048)
			(end -0.67945 0.3048)
			(stroke
				(width 0.1)
				(type default)
			)
			(layer "F.Fab")
		)
		(fp_line
			(start 0.120396 0.2794)
			(end -0.12065 0.2794)
			(stroke
				(width 0.1)
				(type default)
			)
			(layer "F.Fab")
		)
		(fp_line
			(start 0.120396 0.3048)
			(end 0.120396 0.2794)
			(stroke
				(width 0.1)
				(type default)
			)
			(layer "F.Fab")
		)
		(fp_line
			(start 0.12065 -0.3048)
			(end 0.67945 -0.3048)
			(stroke
				(width 0.1)
				(type default)
			)
			(layer "F.Fab")
		)
		(fp_line
			(start 0.12065 -0.2794)
			(end 0.12065 -0.3048)
			(stroke
				(width 0.1)
				(type default)
			)
			(layer "F.Fab")
		)
		(fp_line
			(start 0.67945 -0.3048)
			(end 0.67945 0.3048)
			(stroke
				(width 0.1)
				(type default)
			)
			(layer "F.Fab")
		)
		(fp_line
			(start 0.67945 0.3048)
			(end 0.120396 0.3048)
			(stroke
				(width 0.1)
				(type default)
			)
			(layer "F.Fab")
		)
		(pad "1" smd circle
			(at -0.40005 0)
			(size 0 0)
			(layers "F.Cu" "F.Mask" "F.Paste")
			(net "P3V3_STBY")
		)
		(pad "2" smd circle
			(at 0.40005 0)
			(size 0 0)
			(layers "F.Cu" "F.Mask" "F.Paste")
			(net "GND")
		)
	)
	(footprint ""
		(layer "F.Cu")
		(at 5.969 -55.245)
		(property "Reference" "R22"
			(at -2.794 0.40767 0)
			(unlocked yes)
			(layer "F.SilkS")
			(effects
				(font
					(size 0.7874 0.5842)
					(thickness 0.1524)
				)
			)
		)
		(property "Value" ""
			(at 0 0 0)
			(layer "F.Fab")
			(effects
				(font
					(size 1.27 1.27)
				)
			)
		)
		(duplicate_pad_numbers_are_jumpers no)
		(fp_line
			(start -0.7874 -0.4064)
			(end 0.7874 -0.4064)
			(stroke
				(width 0.1524)
				(type default)
			)
			(layer "F.SilkS")
		)
		(fp_line
			(start -0.7874 0.4064)
			(end -0.7874 -0.4064)
			(stroke
				(width 0.1524)
				(type default)
			)
			(layer "F.SilkS")
		)
		(fp_line
			(start 0.7874 -0.4064)
			(end 0.7874 0.4064)
			(stroke
				(width 0.1524)
				(type default)
			)
			(layer "F.SilkS")
		)
		(fp_line
			(start 0.7874 0.4064)
			(end -0.7874 0.4064)
			(stroke
				(width 0.1524)
				(type default)
			)
			(layer "F.SilkS")
		)
		(fp_line
			(start -0.67945 -0.305054)
			(end -0.12065 -0.305054)
			(stroke
				(width 0.1)
				(type default)
			)
			(layer "F.Fab")
		)
		(fp_line
			(start -0.67945 0.3048)
			(end -0.67945 -0.305054)
			(stroke
				(width 0.1)
				(type default)
			)
			(layer "F.Fab")
		)
		(fp_line
			(start -0.12065 -0.305054)
			(end -0.12065 -0.2794)
			(stroke
				(width 0.1)
				(type default)
			)
			(layer "F.Fab")
		)
		(fp_line
			(start -0.12065 -0.2794)
			(end 0.12065 -0.2794)
			(stroke
				(width 0.1)
				(type default)
			)
			(layer "F.Fab")
		)
		(fp_line
			(start -0.12065 0.2794)
			(end -0.12065 0.3048)
			(stroke
				(width 0.1)
				(type default)
			)
			(layer "F.Fab")
		)
		(fp_line
			(start -0.12065 0.3048)
			(end -0.67945 0.3048)
			(stroke
				(width 0.1)
				(type default)
			)
			(layer "F.Fab")
		)
		(fp_line
			(start 0.120396 0.2794)
			(end -0.12065 0.2794)
			(stroke
				(width 0.1)
				(type default)
			)
			(layer "F.Fab")
		)
		(fp_line
			(start 0.120396 0.3048)
			(end 0.120396 0.2794)
			(stroke
				(width 0.1)
				(type default)
			)
			(layer "F.Fab")
		)
		(fp_line
			(start 0.12065 -0.3048)
			(end 0.67945 -0.3048)
			(stroke
				(width 0.1)
				(type default)
			)
			(layer "F.Fab")
		)
		(fp_line
			(start 0.12065 -0.2794)
			(end 0.12065 -0.3048)
			(stroke
				(width 0.1)
				(type default)
			)
			(layer "F.Fab")
		)
		(fp_line
			(start 0.67945 -0.3048)
			(end 0.67945 0.3048)
			(stroke
				(width 0.1)
				(type default)
			)
			(layer "F.Fab")
		)
		(fp_line
			(start 0.67945 0.3048)
			(end 0.120396 0.3048)
			(stroke
				(width 0.1)
				(type default)
			)
			(layer "F.Fab")
		)
		(pad "1" smd circle
			(at -0.40005 0)
			(size 0 0)
			(layers "F.Cu" "F.Mask" "F.Paste")
			(net "P3V3_STBY")
		)
		(pad "2" smd circle
			(at 0.40005 0)
			(size 0 0)
			(layers "F.Cu" "F.Mask" "F.Paste")
			(net "REV_ID<1>")
		)
	)
	(footprint ""
		(layer "F.Cu")
		(at 20.701 -63.373 -90)
		(property "Reference" "R68"
			(at -0.254 -2.18567 90)
			(unlocked yes)
			(layer "F.SilkS")
			(effects
				(font
					(size 0.7874 0.5842)
					(thickness 0.1524)
				)
			)
		)
		(property "Value" ""
			(at 0 0 270)
			(layer "F.Fab")
			(effects
				(font
					(size 1.27 1.27)
				)
			)
		)
		(duplicate_pad_numbers_are_jumpers no)
		(fp_line
			(start -0.7874 0.4064)
			(end -0.7874 -0.4064)
			(stroke
				(width 0.1524)
				(type default)
			)
			(layer "F.SilkS")
		)
		(fp_line
			(start 0.7874 0.4064)
			(end -0.7874 0.4064)
			(stroke
				(width 0.1524)
				(type default)
			)
			(layer "F.SilkS")
		)
		(fp_line
			(start -0.7874 -0.4064)
			(end 0.7874 -0.4064)
			(stroke
				(width 0.1524)
				(type default)
			)
			(layer "F.SilkS")
		)
		(fp_line
			(start 0.7874 -0.4064)
			(end 0.7874 0.4064)
			(stroke
				(width 0.1524)
				(type default)
			)
			(layer "F.SilkS")
		)
		(fp_line
			(start -0.67945 0.3048)
			(end -0.67945 -0.305054)
			(stroke
				(width 0.1)
				(type default)
			)
			(layer "F.Fab")
		)
		(fp_line
			(start -0.12065 0.3048)
			(end -0.67945 0.3048)
			(stroke
				(width 0.1)
				(type default)
			)
			(layer "F.Fab")
		)
		(fp_line
			(start 0.120396 0.3048)
			(end 0.120396 0.2794)
			(stroke
				(width 0.1)
				(type default)
			)
			(layer "F.Fab")
		)
		(fp_line
			(start 0.67945 0.3048)
			(end 0.120396 0.3048)
			(stroke
				(width 0.1)
				(type default)
			)
			(layer "F.Fab")
		)
		(fp_line
			(start -0.12065 0.2794)
			(end -0.12065 0.3048)
			(stroke
				(width 0.1)
				(type default)
			)
			(layer "F.Fab")
		)
		(fp_line
			(start 0.120396 0.2794)
			(end -0.12065 0.2794)
			(stroke
				(width 0.1)
				(type default)
			)
			(layer "F.Fab")
		)
		(fp_line
			(start -0.12065 -0.2794)
			(end 0.12065 -0.2794)
			(stroke
				(width 0.1)
				(type default)
			)
			(layer "F.Fab")
		)
		(fp_line
			(start 0.12065 -0.2794)
			(end 0.12065 -0.3048)
			(stroke
				(width 0.1)
				(type default)
			)
			(layer "F.Fab")
		)
		(fp_line
			(start 0.12065 -0.3048)
			(end 0.67945 -0.3048)
			(stroke
				(width 0.1)
				(type default)
			)
			(layer "F.Fab")
		)
		(fp_line
			(start 0.67945 -0.3048)
			(end 0.67945 0.3048)
			(stroke
				(width 0.1)
				(type default)
			)
			(layer "F.Fab")
		)
		(fp_line
			(start -0.67945 -0.305054)
			(end -0.12065 -0.305054)
			(stroke
				(width 0.1)
				(type default)
			)
			(layer "F.Fab")
		)
		(fp_line
			(start -0.12065 -0.305054)
			(end -0.12065 -0.2794)
			(stroke
				(width 0.1)
				(type default)
			)
			(layer "F.Fab")
		)
		(pad "1" smd circle
			(at -0.40005 0 270)
			(size 0 0)
			(layers "F.Cu" "F.Mask" "F.Paste")
			(net "SMB_SWB_SDA")
		)
		(pad "2" smd circle
			(at 0.40005 0 270)
			(size 0 0)
			(layers "F.Cu" "F.Mask" "F.Paste")
			(net "SMB_SDA")
		)
	)
	(footprint ""
		(layer "F.Cu")
		(at 11.176 -62.738 180)
		(property "Reference" "R13"
			(at -3.302 -0.02667 0)
			(unlocked yes)
			(layer "F.SilkS")
			(effects
				(font
					(size 0.7874 0.5842)
					(thickness 0.1524)
				)
			)
		)
		(property "Value" ""
			(at 0 0 180)
			(layer "F.Fab")
			(effects
				(font
					(size 1.27 1.27)
				)
			)
		)
		(duplicate_pad_numbers_are_jumpers no)
		(fp_line
			(start 0.7874 0.4064)
			(end -0.7874 0.4064)
			(stroke
				(width 0.1524)
				(type default)
			)
			(layer "F.SilkS")
		)
		(fp_line
			(start 0.7874 -0.4064)
			(end 0.7874 0.4064)
			(stroke
				(width 0.1524)
				(type default)
			)
			(layer "F.SilkS")
		)
		(fp_line
			(start -0.7874 0.4064)
			(end -0.7874 -0.4064)
			(stroke
				(width 0.1524)
				(type default)
			)
			(layer "F.SilkS")
		)
		(fp_line
			(start -0.7874 -0.4064)
			(end 0.7874 -0.4064)
			(stroke
				(width 0.1524)
				(type default)
			)
			(layer "F.SilkS")
		)
		(fp_line
			(start 0.67945 0.3048)
			(end 0.120396 0.3048)
			(stroke
				(width 0.1)
				(type default)
			)
			(layer "F.Fab")
		)
		(fp_line
			(start 0.67945 -0.3048)
			(end 0.67945 0.3048)
			(stroke
				(width 0.1)
				(type default)
			)
			(layer "F.Fab")
		)
		(fp_line
			(start 0.12065 -0.2794)
			(end 0.12065 -0.3048)
			(stroke
				(width 0.1)
				(type default)
			)
			(layer "F.Fab")
		)
		(fp_line
			(start 0.12065 -0.3048)
			(end 0.67945 -0.3048)
			(stroke
				(width 0.1)
				(type default)
			)
			(layer "F.Fab")
		)
		(fp_line
			(start 0.120396 0.3048)
			(end 0.120396 0.2794)
			(stroke
				(width 0.1)
				(type default)
			)
			(layer "F.Fab")
		)
		(fp_line
			(start 0.120396 0.2794)
			(end -0.12065 0.2794)
			(stroke
				(width 0.1)
				(type default)
			)
			(layer "F.Fab")
		)
		(fp_line
			(start -0.12065 0.3048)
			(end -0.67945 0.3048)
			(stroke
				(width 0.1)
				(type default)
			)
			(layer "F.Fab")
		)
		(fp_line
			(start -0.12065 0.2794)
			(end -0.12065 0.3048)
			(stroke
				(width 0.1)
				(type default)
			)
			(layer "F.Fab")
		)
		(fp_line
			(start -0.12065 -0.2794)
			(end 0.12065 -0.2794)
			(stroke
				(width 0.1)
				(type default)
			)
			(layer "F.Fab")
		)
		(fp_line
			(start -0.12065 -0.305054)
			(end -0.12065 -0.2794)
			(stroke
				(width 0.1)
				(type default)
			)
			(layer "F.Fab")
		)
		(fp_line
			(start -0.67945 0.3048)
			(end -0.67945 -0.305054)
			(stroke
				(width 0.1)
				(type default)
			)
			(layer "F.Fab")
		)
		(fp_line
			(start -0.67945 -0.305054)
			(end -0.12065 -0.305054)
			(stroke
				(width 0.1)
				(type default)
			)
			(layer "F.Fab")
		)
		(pad "1" smd circle
			(at -0.40005 0 180)
			(size 0 0)
			(layers "F.Cu" "F.Mask" "F.Paste")
			(net "RST_SMB_N")
		)
		(pad "2" smd circle
			(at 0.40005 0 180)
			(size 0 0)
			(layers "F.Cu" "F.Mask" "F.Paste")
			(net "RST_SMB_R_N")
		)
	)
	(footprint ""
		(layer "F.Cu")
		(at 87.757 -155.194 -90)
		(property "Reference" "J6"
			(at -4.28371 0.5969 0)
			(unlocked yes)
			(layer "F.SilkS")
			(effects
				(font
					(size 0.7874 0.5842)
					(thickness 0.1524)
				)
				(justify left)
			)
		)
		(property "Value" ""
			(at 0 0 270)
			(layer "F.Fab")
			(effects
				(font
					(size 1.27 1.27)
				)
			)
		)
		(duplicate_pad_numbers_are_jumpers no)
		(fp_line
			(start -1.2192 2.1082)
			(end -1.2192 -2.1082)
			(stroke
				(width 0.1524)
				(type default)
			)
			(layer "F.SilkS")
		)
		(fp_line
			(start 1.2192 2.1082)
			(end -1.2192 2.1082)
			(stroke
				(width 0.1524)
				(type default)
			)
			(layer "F.SilkS")
		)
		(fp_line
			(start -1.2192 -2.1082)
			(end 1.2192 -2.1082)
			(stroke
				(width 0.1524)
				(type default)
			)
			(layer "F.SilkS")
		)
		(fp_line
			(start 1.2192 -2.1082)
			(end 1.2192 2.1082)
			(stroke
				(width 0.1524)
				(type default)
			)
			(layer "F.SilkS")
		)
		(pad "" np_thru_hole circle
			(at -2.8829 -1.27 180)
			(size 1.0414 1.0414)
			(drill 1.0414)
			(layers "*.Cu" "*.Mask")
			(clearance 0.381)
			(thermal_gap 0.381)
		)
		(pad "" np_thru_hole circle
			(at -2.8829 1.27 180)
			(size 1.0414 1.0414)
			(drill 1.0414)
			(layers "*.Cu" "*.Mask")
			(clearance 0.381)
			(thermal_gap 0.381)
		)
		(pad "" np_thru_hole circle
			(at 3.4671 -1.27 180)
			(size 1.0414 1.0414)
			(drill 1.0414)
			(layers "*.Cu" "*.Mask")
			(clearance 0.381)
			(thermal_gap 0.381)
		)
		(pad "" np_thru_hole circle
			(at 3.4671 1.27 180)
			(size 1.0414 1.0414)
			(drill 1.0414)
			(layers "*.Cu" "*.Mask")
			(clearance 0.381)
			(thermal_gap 0.381)
		)
		(pad "1" smd rect
			(at 0.8255 -0.249936 180)
			(size 0.3048 0.508)
			(layers "F.Cu" "F.Mask" "F.Paste")
			(net "DELTA_L_85_5INCH_TOP_DP")
		)
		(pad "2" smd rect
			(at 0.8255 0.249936 180)
			(size 0.3048 0.508)
			(layers "F.Cu" "F.Mask" "F.Paste")
			(net "DELTA_L_85_5INCH_TOP_DN")
		)
		(pad "3" smd circle
			(at 0 0 270)
			(size 0 0)
			(layers "F.Cu" "F.Mask" "F.Paste")
			(net "GND1")
		)
		(zone
			(layer "F.Cu")
			(hatch none 0.5)
			(connect_pads
				(clearance 0)
			)
			(min_thickness 0.25)
			(keepout
				(tracks not_allowed)
				(vias allowed)
				(pads allowed)
				(copperpour not_allowed)
				(footprints allowed)
			)
			(placement
				(enabled no)
				(sheetname "")
			)
			(fill
				(thermal_gap 0.5)
				(thermal_bridge_width 0.5)
				(island_removal_mode 0)
			)
			(polygon
				(pts
					(xy 88.30564 -154.0764) (xy 88.210136 -154.0764) (xy 88.210136 -154.6733) (xy 87.803736 -154.6733)
					(xy 87.803736 -154.0764) (xy 87.710264 -154.0764) (xy 87.710264 -154.6733) (xy 87.303864 -154.6733)
					(xy 87.303864 -154.0764) (xy 87.20836 -154.0764) (xy 87.20836 -154.7749) (xy 88.30564 -154.7749)
				)
			)
		)
		(zone
			(layers "F.Cu" "B.Cu" "In1.Cu" "In2.Cu")
			(hatch none 0.5)
			(connect_pads
				(clearance 0)
			)
			(min_thickness 0.25)
			(keepout
				(tracks not_allowed)
				(vias allowed)
				(pads allowed)
				(copperpour not_allowed)
				(footprints allowed)
			)
			(placement
				(enabled no)
				(sheetname "")
			)
			(fill
				(thermal_gap 0.5)
				(thermal_bridge_width 0.5)
				(island_removal_mode 0)
			)
			(polygon
				(pts
					(arc
						(start 87.4141 -158.0769)
						(mid 85.5599 -158.0769)
						(end 87.4141 -158.0769)
					)
				)
			)
		)
		(zone
			(layers "F.Cu" "B.Cu" "In1.Cu" "In2.Cu")
			(hatch none 0.5)
			(connect_pads
				(clearance 0)
			)
			(min_thickness 0.25)
			(keepout
				(tracks not_allowed)
				(vias allowed)
				(pads allowed)
				(copperpour not_allowed)
				(footprints allowed)
			)
			(placement
				(enabled no)
				(sheetname "")
			)
			(fill
				(thermal_gap 0.5)
				(thermal_bridge_width 0.5)
				(island_removal_mode 0)
			)
			(polygon
				(pts
					(arc
						(start 87.4141 -151.7269)
						(mid 85.5599 -151.7269)
						(end 87.4141 -151.7269)
					)
				)
			)
		)
		(zone
			(layers "F.Cu" "B.Cu" "In1.Cu" "In2.Cu")
			(hatch none 0.5)
			(connect_pads
				(clearance 0)
			)
			(min_thickness 0.25)
			(keepout
				(tracks not_allowed)
				(vias allowed)
				(pads allowed)
				(copperpour not_allowed)
				(footprints allowed)
			)
			(placement
				(enabled no)
				(sheetname "")
			)
			(fill
				(thermal_gap 0.5)
				(thermal_bridge_width 0.5)
				(island_removal_mode 0)
			)
			(polygon
				(pts
					(arc
						(start 89.9541 -158.0769)
						(mid 88.0999 -158.0769)
						(end 89.9541 -158.0769)
					)
				)
			)
		)
		(zone
			(layers "F.Cu" "B.Cu" "In1.Cu" "In2.Cu")
			(hatch none 0.5)
			(connect_pads
				(clearance 0)
			)
			(min_thickness 0.25)
			(keepout
				(tracks not_allowed)
				(vias allowed)
				(pads allowed)
				(copperpour not_allowed)
				(footprints allowed)
			)
			(placement
				(enabled no)
				(sheetname "")
			)
			(fill
				(thermal_gap 0.5)
				(thermal_bridge_width 0.5)
				(island_removal_mode 0)
			)
			(polygon
				(pts
					(arc
						(start 89.9541 -151.7269)
						(mid 88.0999 -151.7269)
						(end 89.9541 -151.7269)
					)
				)
			)
		)
	)
	(footprint ""
		(layer "F.Cu")
		(at 10.033 -25.019 180)
		(property "Reference" "R7"
			(at 0.762 -1.29667 0)
			(unlocked yes)
			(layer "F.SilkS")
			(effects
				(font
					(size 0.7874 0.5842)
					(thickness 0.1524)
				)
			)
		)
		(property "Value" ""
			(at 0 0 180)
			(layer "F.Fab")
			(effects
				(font
					(size 1.27 1.27)
				)
			)
		)
		(duplicate_pad_numbers_are_jumpers no)
		(fp_line
			(start 1.2954 0.5842)
			(end -1.2954 0.5842)
			(stroke
				(width 0.1524)
				(type default)
			)
			(layer "F.SilkS")
		)
		(fp_line
			(start 1.2954 -0.5842)
			(end 1.2954 0.5842)
			(stroke
				(width 0.1524)
				(type default)
			)
			(layer "F.SilkS")
		)
		(fp_line
			(start -1.2954 0.5842)
			(end -1.2954 -0.5842)
			(stroke
				(width 0.1524)
				(type default)
			)
			(layer "F.SilkS")
		)
		(fp_line
			(start -1.2954 -0.5842)
			(end 1.2954 -0.5842)
			(stroke
				(width 0.1524)
				(type default)
			)
			(layer "F.SilkS")
		)
		(fp_line
			(start 1.1938 0.4064)
			(end 0.8636 0.4064)
			(stroke
				(width 0.1)
				(type default)
			)
			(layer "F.Fab")
		)
		(fp_line
			(start 1.1938 -0.406654)
			(end 1.1938 0.4064)
			(stroke
				(width 0.1)
				(type default)
			)
			(layer "F.Fab")
		)
		(fp_line
			(start 0.8636 0.4572)
			(end -0.8636 0.4572)
			(stroke
				(width 0.1)
				(type default)
			)
			(layer "F.Fab")
		)
		(fp_line
			(start 0.8636 0.4064)
			(end 0.8636 0.4572)
			(stroke
				(width 0.1)
				(type default)
			)
			(layer "F.Fab")
		)
		(fp_line
			(start 0.8636 -0.406654)
			(end 1.1938 -0.406654)
			(stroke
				(width 0.1)
				(type default)
			)
			(layer "F.Fab")
		)
		(fp_line
			(start 0.8636 -0.4572)
			(end 0.8636 -0.406654)
			(stroke
				(width 0.1)
				(type default)
			)
			(layer "F.Fab")
		)
		(fp_line
			(start -0.8636 0.4572)
			(end -0.8636 0.4318)
			(stroke
				(width 0.1)
				(type default)
			)
			(layer "F.Fab")
		)
		(fp_line
			(start -0.8636 0.4318)
			(end -0.8636 0.4064)
			(stroke
				(width 0.1)
				(type default)
			)
			(layer "F.Fab")
		)
		(fp_line
			(start -0.8636 0.4064)
			(end -1.1938 0.4064)
			(stroke
				(width 0.1)
				(type default)
			)
			(layer "F.Fab")
		)
		(fp_line
			(start -0.8636 -0.406654)
			(end -0.8636 -0.4572)
			(stroke
				(width 0.1)
				(type default)
			)
			(layer "F.Fab")
		)
		(fp_line
			(start -0.8636 -0.4572)
			(end 0.8636 -0.4572)
			(stroke
				(width 0.1)
				(type default)
			)
			(layer "F.Fab")
		)
		(fp_line
			(start -1.1938 0.4064)
			(end -1.1938 -0.406654)
			(stroke
				(width 0.1)
				(type default)
			)
			(layer "F.Fab")
		)
		(fp_line
			(start -1.1938 -0.406654)
			(end -0.8636 -0.406654)
			(stroke
				(width 0.1)
				(type default)
			)
			(layer "F.Fab")
		)
		(pad "1" smd rect
			(at -0.7366 0 90)
			(size 0.7112 0.8128)
			(layers "F.Cu" "F.Mask" "F.Paste")
			(net "SYSTEM_FAULT_ID_LED_R2_N")
		)
		(pad "2" smd rect
			(at 0.7366 0 90)
			(size 0.7112 0.8128)
			(layers "F.Cu" "F.Mask" "F.Paste")
			(net "SYSTEM_FAULT_ID_LED_R1_N")
		)
	)
	(footprint ""
		(layer "F.Cu")
		(at 16.891 -9.4234)
		(property "Reference" "R1"
			(at -2.032 -0.07493 0)
			(unlocked yes)
			(layer "F.SilkS")
			(effects
				(font
					(size 0.7874 0.5842)
					(thickness 0.1524)
				)
			)
		)
		(property "Value" ""
			(at 0 0 0)
			(layer "F.Fab")
			(effects
				(font
					(size 1.27 1.27)
				)
			)
		)
		(duplicate_pad_numbers_are_jumpers no)
		(fp_line
			(start -1.2954 -0.5842)
			(end 1.2954 -0.5842)
			(stroke
				(width 0.1524)
				(type default)
			)
			(layer "F.SilkS")
		)
		(fp_line
			(start -1.2954 0.5842)
			(end -1.2954 -0.5842)
			(stroke
				(width 0.1524)
				(type default)
			)
			(layer "F.SilkS")
		)
		(fp_line
			(start 1.2954 -0.5842)
			(end 1.2954 0.5842)
			(stroke
				(width 0.1524)
				(type default)
			)
			(layer "F.SilkS")
		)
		(fp_line
			(start 1.2954 0.5842)
			(end -1.2954 0.5842)
			(stroke
				(width 0.1524)
				(type default)
			)
			(layer "F.SilkS")
		)
		(fp_line
			(start -1.1938 -0.406654)
			(end -0.8636 -0.406654)
			(stroke
				(width 0.1)
				(type default)
			)
			(layer "F.Fab")
		)
		(fp_line
			(start -1.1938 0.4064)
			(end -1.1938 -0.406654)
			(stroke
				(width 0.1)
				(type default)
			)
			(layer "F.Fab")
		)
		(fp_line
			(start -0.8636 -0.4572)
			(end 0.8636 -0.4572)
			(stroke
				(width 0.1)
				(type default)
			)
			(layer "F.Fab")
		)
		(fp_line
			(start -0.8636 -0.406654)
			(end -0.8636 -0.4572)
			(stroke
				(width 0.1)
				(type default)
			)
			(layer "F.Fab")
		)
		(fp_line
			(start -0.8636 0.4064)
			(end -1.1938 0.4064)
			(stroke
				(width 0.1)
				(type default)
			)
			(layer "F.Fab")
		)
		(fp_line
			(start -0.8636 0.4318)
			(end -0.8636 0.4064)
			(stroke
				(width 0.1)
				(type default)
			)
			(layer "F.Fab")
		)
		(fp_line
			(start -0.8636 0.4572)
			(end -0.8636 0.4318)
			(stroke
				(width 0.1)
				(type default)
			)
			(layer "F.Fab")
		)
		(fp_line
			(start 0.8636 -0.4572)
			(end 0.8636 -0.406654)
			(stroke
				(width 0.1)
				(type default)
			)
			(layer "F.Fab")
		)
		(fp_line
			(start 0.8636 -0.406654)
			(end 1.1938 -0.406654)
			(stroke
				(width 0.1)
				(type default)
			)
			(layer "F.Fab")
		)
		(fp_line
			(start 0.8636 0.4064)
			(end 0.8636 0.4572)
			(stroke
				(width 0.1)
				(type default)
			)
			(layer "F.Fab")
		)
		(fp_line
			(start 0.8636 0.4572)
			(end -0.8636 0.4572)
			(stroke
				(width 0.1)
				(type default)
			)
			(layer "F.Fab")
		)
		(fp_line
			(start 1.1938 -0.406654)
			(end 1.1938 0.4064)
			(stroke
				(width 0.1)
				(type default)
			)
			(layer "F.Fab")
		)
		(fp_line
			(start 1.1938 0.4064)
			(end 0.8636 0.4064)
			(stroke
				(width 0.1)
				(type default)
			)
			(layer "F.Fab")
		)
		(pad "1" smd rect
			(at -0.7366 0 270)
			(size 0.7112 0.8128)
			(layers "F.Cu" "F.Mask" "F.Paste")
			(net "P5V_STBY")
		)
		(pad "2" smd rect
			(at 0.7366 0 270)
			(size 0.7112 0.8128)
			(layers "F.Cu" "F.Mask" "F.Paste")
			(net "FM_PFR_LED_AMBER_R")
		)
	)
	(footprint ""
		(layer "F.Cu")
		(at 87.757 -109.601 90)
		(property "Reference" "J5"
			(at -4.46405 -0.74168 0)
			(unlocked yes)
			(layer "F.SilkS")
			(effects
				(font
					(size 0.7874 0.5842)
					(thickness 0.1524)
				)
				(justify left)
			)
		)
		(property "Value" ""
			(at 0 0 90)
			(layer "F.Fab")
			(effects
				(font
					(size 1.27 1.27)
				)
			)
		)
		(duplicate_pad_numbers_are_jumpers no)
		(fp_line
			(start 1.2192 -2.1082)
			(end 1.2192 2.1082)
			(stroke
				(width 0.1524)
				(type default)
			)
			(layer "F.SilkS")
		)
		(fp_line
			(start -1.2192 -2.1082)
			(end 1.2192 -2.1082)
			(stroke
				(width 0.1524)
				(type default)
			)
			(layer "F.SilkS")
		)
		(fp_line
			(start 1.2192 2.1082)
			(end -1.2192 2.1082)
			(stroke
				(width 0.1524)
				(type default)
			)
			(layer "F.SilkS")
		)
		(fp_line
			(start -1.2192 2.1082)
			(end -1.2192 -2.1082)
			(stroke
				(width 0.1524)
				(type default)
			)
			(layer "F.SilkS")
		)
		(pad "" np_thru_hole circle
			(at -2.8829 -1.27)
			(size 1.0414 1.0414)
			(drill 1.0414)
			(layers "*.Cu" "*.Mask")
			(clearance 0.381)
			(thermal_gap 0.381)
		)
		(pad "" np_thru_hole circle
			(at -2.8829 1.27)
			(size 1.0414 1.0414)
			(drill 1.0414)
			(layers "*.Cu" "*.Mask")
			(clearance 0.381)
			(thermal_gap 0.381)
		)
		(pad "" np_thru_hole circle
			(at 3.4671 -1.27)
			(size 1.0414 1.0414)
			(drill 1.0414)
			(layers "*.Cu" "*.Mask")
			(clearance 0.381)
			(thermal_gap 0.381)
		)
		(pad "" np_thru_hole circle
			(at 3.4671 1.27)
			(size 1.0414 1.0414)
			(drill 1.0414)
			(layers "*.Cu" "*.Mask")
			(clearance 0.381)
			(thermal_gap 0.381)
		)
		(pad "1" smd rect
			(at 0.8255 -0.249936)
			(size 0.3048 0.508)
			(layers "F.Cu" "F.Mask" "F.Paste")
			(net "DELTA_L_85_5INCH_TOP_DN")
		)
		(pad "2" smd rect
			(at 0.8255 0.249936)
			(size 0.3048 0.508)
			(layers "F.Cu" "F.Mask" "F.Paste")
			(net "DELTA_L_85_5INCH_TOP_DP")
		)
		(pad "3" smd circle
			(at 0 0 90)
			(size 0 0)
			(layers "F.Cu" "F.Mask" "F.Paste")
			(net "GND1")
		)
		(zone
			(layer "F.Cu")
			(hatch none 0.5)
			(connect_pads
				(clearance 0)
			)
			(min_thickness 0.25)
			(keepout
				(tracks not_allowed)
				(vias allowed)
				(pads allowed)
				(copperpour not_allowed)
				(footprints allowed)
			)
			(placement
				(enabled no)
				(sheetname "")
			)
			(fill
				(thermal_gap 0.5)
				(thermal_bridge_width 0.5)
				(island_removal_mode 0)
			)
			(polygon
				(pts
					(xy 87.20836 -110.7186) (xy 87.303864 -110.7186) (xy 87.303864 -110.1217) (xy 87.710264 -110.1217)
					(xy 87.710264 -110.7186) (xy 87.803736 -110.7186) (xy 87.803736 -110.1217) (xy 88.210136 -110.1217)
					(xy 88.210136 -110.7186) (xy 88.30564 -110.7186) (xy 88.30564 -110.0201) (xy 87.20836 -110.0201)
				)
			)
		)
		(zone
			(layers "F.Cu" "B.Cu" "In1.Cu" "In2.Cu")
			(hatch none 0.5)
			(connect_pads
				(clearance 0)
			)
			(min_thickness 0.25)
			(keepout
				(tracks not_allowed)
				(vias allowed)
				(pads allowed)
				(copperpour not_allowed)
				(footprints allowed)
			)
			(placement
				(enabled no)
				(sheetname "")
			)
			(fill
				(thermal_gap 0.5)
				(thermal_bridge_width 0.5)
				(island_removal_mode 0)
			)
			(polygon
				(pts
					(arc
						(start 87.4141 -113.0681)
						(mid 85.5599 -113.0681)
						(end 87.4141 -113.0681)
					)
				)
			)
		)
		(zone
			(layers "F.Cu" "B.Cu" "In1.Cu" "In2.Cu")
			(hatch none 0.5)
			(connect_pads
				(clearance 0)
			)
			(min_thickness 0.25)
			(keepout
				(tracks not_allowed)
				(vias allowed)
				(pads allowed)
				(copperpour not_allowed)
				(footprints allowed)
			)
			(placement
				(enabled no)
				(sheetname "")
			)
			(fill
				(thermal_gap 0.5)
				(thermal_bridge_width 0.5)
				(island_removal_mode 0)
			)
			(polygon
				(pts
					(arc
						(start 87.4141 -106.7181)
						(mid 85.5599 -106.7181)
						(end 87.4141 -106.7181)
					)
				)
			)
		)
		(zone
			(layers "F.Cu" "B.Cu" "In1.Cu" "In2.Cu")
			(hatch none 0.5)
			(connect_pads
				(clearance 0)
			)
			(min_thickness 0.25)
			(keepout
				(tracks not_allowed)
				(vias allowed)
				(pads allowed)
				(copperpour not_allowed)
				(footprints allowed)
			)
			(placement
				(enabled no)
				(sheetname "")
			)
			(fill
				(thermal_gap 0.5)
				(thermal_bridge_width 0.5)
				(island_removal_mode 0)
			)
			(polygon
				(pts
					(arc
						(start 89.9541 -113.0681)
						(mid 88.0999 -113.0681)
						(end 89.9541 -113.0681)
					)
				)
			)
		)
		(zone
			(layers "F.Cu" "B.Cu" "In1.Cu" "In2.Cu")
			(hatch none 0.5)
			(connect_pads
				(clearance 0)
			)
			(min_thickness 0.25)
			(keepout
				(tracks not_allowed)
				(vias allowed)
				(pads allowed)
				(copperpour not_allowed)
				(footprints allowed)
			)
			(placement
				(enabled no)
				(sheetname "")
			)
			(fill
				(thermal_gap 0.5)
				(thermal_bridge_width 0.5)
				(island_removal_mode 0)
			)
			(polygon
				(pts
					(arc
						(start 89.9541 -106.7181)
						(mid 88.0999 -106.7181)
						(end 89.9541 -106.7181)
					)
				)
			)
		)
	)
	(footprint ""
		(layer "F.Cu")
		(at 18.554954 -14.723618 180)
		(property "Reference" "U2"
			(at -1.384046 2.267712 0)
			(unlocked yes)
			(layer "F.SilkS")
			(effects
				(font
					(size 0.7874 0.5842)
					(thickness 0.1524)
				)
			)
		)
		(property "Value" ""
			(at 0 0 180)
			(layer "F.Fab")
			(effects
				(font
					(size 1.27 1.27)
				)
			)
		)
		(duplicate_pad_numbers_are_jumpers no)
		(fp_line
			(start 1.949958 1.610106)
			(end -1.949958 1.610106)
			(stroke
				(width 0.1524)
				(type default)
			)
			(layer "F.SilkS")
		)
		(fp_line
			(start 1.949958 -1.560068)
			(end 1.949958 1.610106)
			(stroke
				(width 0.1524)
				(type default)
			)
			(layer "F.SilkS")
		)
		(fp_line
			(start -1.949958 1.610106)
			(end -1.949958 -1.610106)
			(stroke
				(width 0.1524)
				(type default)
			)
			(layer "F.SilkS")
		)
		(fp_line
			(start -1.949958 -1.610106)
			(end 1.949958 -1.610106)
			(stroke
				(width 0.1524)
				(type default)
			)
			(layer "F.SilkS")
		)
		(fp_line
			(start 0.750062 1.560068)
			(end -0.750062 1.560068)
			(stroke
				(width 0.1)
				(type default)
			)
			(layer "F.Fab")
		)
		(fp_line
			(start 0.750062 -1.560068)
			(end 0.750062 1.560068)
			(stroke
				(width 0.1)
				(type default)
			)
			(layer "F.Fab")
		)
		(fp_line
			(start -0.750062 1.560068)
			(end -0.750062 -1.560068)
			(stroke
				(width 0.1)
				(type default)
			)
			(layer "F.Fab")
		)
		(fp_line
			(start -0.750062 -1.560068)
			(end 0.750062 -1.560068)
			(stroke
				(width 0.1)
				(type default)
			)
			(layer "F.Fab")
		)
		(pad "D" smd rect
			(at 1.100074 0 90)
			(size 1.016 1.4224)
			(layers "F.Cu" "F.Mask" "F.Paste")
			(net "FM_PFR_LED_BLUE_R")
		)
		(pad "G" smd rect
			(at -1.100074 -0.94996 90)
			(size 1.016 1.4224)
			(layers "F.Cu" "F.Mask" "F.Paste")
			(net "FM_PFR_LED_BLUE_R_N")
		)
		(pad "S" smd rect
			(at -1.100074 0.94996 90)
			(size 1.016 1.4224)
			(layers "F.Cu" "F.Mask" "F.Paste")
			(net "GND")
		)
	)
	(footprint ""
		(layer "F.Cu")
		(at 31.073852 -6.911594 180)
		(property "Reference" "C7"
			(at 0.720852 1.062736 0)
			(unlocked yes)
			(layer "F.SilkS")
			(effects
				(font
					(size 0.7874 0.5842)
					(thickness 0.1524)
				)
			)
		)
		(property "Value" ""
			(at 0 0 180)
			(layer "F.Fab")
			(effects
				(font
					(size 1.27 1.27)
				)
			)
		)
		(duplicate_pad_numbers_are_jumpers no)
		(fp_line
			(start 0.7874 0.4064)
			(end -0.7874 0.4064)
			(stroke
				(width 0.1524)
				(type default)
			)
			(layer "F.SilkS")
		)
		(fp_line
			(start 0.7874 -0.4064)
			(end 0.7874 0.4064)
			(stroke
				(width 0.1524)
				(type default)
			)
			(layer "F.SilkS")
		)
		(fp_line
			(start -0.7874 0.4064)
			(end -0.7874 -0.4064)
			(stroke
				(width 0.1524)
				(type default)
			)
			(layer "F.SilkS")
		)
		(fp_line
			(start -0.7874 -0.4064)
			(end 0.7874 -0.4064)
			(stroke
				(width 0.1524)
				(type default)
			)
			(layer "F.SilkS")
		)
		(fp_line
			(start 0.67945 0.3048)
			(end 0.120396 0.3048)
			(stroke
				(width 0.1)
				(type default)
			)
			(layer "F.Fab")
		)
		(fp_line
			(start 0.67945 -0.3048)
			(end 0.67945 0.3048)
			(stroke
				(width 0.1)
				(type default)
			)
			(layer "F.Fab")
		)
		(fp_line
			(start 0.12065 -0.2794)
			(end 0.12065 -0.3048)
			(stroke
				(width 0.1)
				(type default)
			)
			(layer "F.Fab")
		)
		(fp_line
			(start 0.12065 -0.3048)
			(end 0.67945 -0.3048)
			(stroke
				(width 0.1)
				(type default)
			)
			(layer "F.Fab")
		)
		(fp_line
			(start 0.120396 0.3048)
			(end 0.120396 0.2794)
			(stroke
				(width 0.1)
				(type default)
			)
			(layer "F.Fab")
		)
		(fp_line
			(start 0.120396 0.2794)
			(end -0.12065 0.2794)
			(stroke
				(width 0.1)
				(type default)
			)
			(layer "F.Fab")
		)
		(fp_line
			(start -0.12065 0.3048)
			(end -0.67945 0.3048)
			(stroke
				(width 0.1)
				(type default)
			)
			(layer "F.Fab")
		)
		(fp_line
			(start -0.12065 0.2794)
			(end -0.12065 0.3048)
			(stroke
				(width 0.1)
				(type default)
			)
			(layer "F.Fab")
		)
		(fp_line
			(start -0.12065 -0.2794)
			(end 0.12065 -0.2794)
			(stroke
				(width 0.1)
				(type default)
			)
			(layer "F.Fab")
		)
		(fp_line
			(start -0.12065 -0.305054)
			(end -0.12065 -0.2794)
			(stroke
				(width 0.1)
				(type default)
			)
			(layer "F.Fab")
		)
		(fp_line
			(start -0.67945 0.3048)
			(end -0.67945 -0.305054)
			(stroke
				(width 0.1)
				(type default)
			)
			(layer "F.Fab")
		)
		(fp_line
			(start -0.67945 -0.305054)
			(end -0.12065 -0.305054)
			(stroke
				(width 0.1)
				(type default)
			)
			(layer "F.Fab")
		)
		(pad "1" smd circle
			(at -0.40005 0 180)
			(size 0 0)
			(layers "F.Cu" "F.Mask" "F.Paste")
			(net "P3V3_STBY")
		)
		(pad "2" smd circle
			(at 0.40005 0 180)
			(size 0 0)
			(layers "F.Cu" "F.Mask" "F.Paste")
			(net "GND")
		)
	)
	(footprint ""
		(layer "F.Cu")
		(at 18.288 -67.437)
		(property "Reference" "C2"
			(at 1.778 -0.10033 0)
			(unlocked yes)
			(layer "F.SilkS")
			(effects
				(font
					(size 0.7874 0.5842)
					(thickness 0.1524)
				)
			)
		)
		(property "Value" ""
			(at 0 0 0)
			(layer "F.Fab")
			(effects
				(font
					(size 1.27 1.27)
				)
			)
		)
		(duplicate_pad_numbers_are_jumpers no)
		(fp_line
			(start -0.7874 -0.4064)
			(end 0.7874 -0.4064)
			(stroke
				(width 0.1524)
				(type default)
			)
			(layer "F.SilkS")
		)
		(fp_line
			(start -0.7874 0.4064)
			(end -0.7874 -0.4064)
			(stroke
				(width 0.1524)
				(type default)
			)
			(layer "F.SilkS")
		)
		(fp_line
			(start 0.7874 -0.4064)
			(end 0.7874 0.4064)
			(stroke
				(width 0.1524)
				(type default)
			)
			(layer "F.SilkS")
		)
		(fp_line
			(start 0.7874 0.4064)
			(end -0.7874 0.4064)
			(stroke
				(width 0.1524)
				(type default)
			)
			(layer "F.SilkS")
		)
		(fp_line
			(start -0.67945 -0.305054)
			(end -0.12065 -0.305054)
			(stroke
				(width 0.1)
				(type default)
			)
			(layer "F.Fab")
		)
		(fp_line
			(start -0.67945 0.3048)
			(end -0.67945 -0.305054)
			(stroke
				(width 0.1)
				(type default)
			)
			(layer "F.Fab")
		)
		(fp_line
			(start -0.12065 -0.305054)
			(end -0.12065 -0.2794)
			(stroke
				(width 0.1)
				(type default)
			)
			(layer "F.Fab")
		)
		(fp_line
			(start -0.12065 -0.2794)
			(end 0.12065 -0.2794)
			(stroke
				(width 0.1)
				(type default)
			)
			(layer "F.Fab")
		)
		(fp_line
			(start -0.12065 0.2794)
			(end -0.12065 0.3048)
			(stroke
				(width 0.1)
				(type default)
			)
			(layer "F.Fab")
		)
		(fp_line
			(start -0.12065 0.3048)
			(end -0.67945 0.3048)
			(stroke
				(width 0.1)
				(type default)
			)
			(layer "F.Fab")
		)
		(fp_line
			(start 0.120396 0.2794)
			(end -0.12065 0.2794)
			(stroke
				(width 0.1)
				(type default)
			)
			(layer "F.Fab")
		)
		(fp_line
			(start 0.120396 0.3048)
			(end 0.120396 0.2794)
			(stroke
				(width 0.1)
				(type default)
			)
			(layer "F.Fab")
		)
		(fp_line
			(start 0.12065 -0.3048)
			(end 0.67945 -0.3048)
			(stroke
				(width 0.1)
				(type default)
			)
			(layer "F.Fab")
		)
		(fp_line
			(start 0.12065 -0.2794)
			(end 0.12065 -0.3048)
			(stroke
				(width 0.1)
				(type default)
			)
			(layer "F.Fab")
		)
		(fp_line
			(start 0.67945 -0.3048)
			(end 0.67945 0.3048)
			(stroke
				(width 0.1)
				(type default)
			)
			(layer "F.Fab")
		)
		(fp_line
			(start 0.67945 0.3048)
			(end 0.120396 0.3048)
			(stroke
				(width 0.1)
				(type default)
			)
			(layer "F.Fab")
		)
		(pad "1" smd circle
			(at -0.40005 0)
			(size 0 0)
			(layers "F.Cu" "F.Mask" "F.Paste")
			(net "P3V3_STBY")
		)
		(pad "2" smd circle
			(at 0.40005 0)
			(size 0 0)
			(layers "F.Cu" "F.Mask" "F.Paste")
			(net "GND")
		)
	)
	(footprint ""
		(layer "F.Cu")
		(at 3.937 -47.752)
		(property "Reference" "R56"
			(at -2.413 0.15367 0)
			(unlocked yes)
			(layer "F.SilkS")
			(effects
				(font
					(size 0.7874 0.5842)
					(thickness 0.1524)
				)
			)
		)
		(property "Value" ""
			(at 0 0 0)
			(layer "F.Fab")
			(effects
				(font
					(size 1.27 1.27)
				)
			)
		)
		(duplicate_pad_numbers_are_jumpers no)
		(fp_line
			(start -0.7874 -0.4064)
			(end 0.7874 -0.4064)
			(stroke
				(width 0.1524)
				(type default)
			)
			(layer "F.SilkS")
		)
		(fp_line
			(start -0.7874 0.4064)
			(end -0.7874 -0.4064)
			(stroke
				(width 0.1524)
				(type default)
			)
			(layer "F.SilkS")
		)
		(fp_line
			(start 0.7874 -0.4064)
			(end 0.7874 0.4064)
			(stroke
				(width 0.1524)
				(type default)
			)
			(layer "F.SilkS")
		)
		(fp_line
			(start 0.7874 0.4064)
			(end -0.7874 0.4064)
			(stroke
				(width 0.1524)
				(type default)
			)
			(layer "F.SilkS")
		)
		(fp_line
			(start -0.67945 -0.305054)
			(end -0.12065 -0.305054)
			(stroke
				(width 0.1)
				(type default)
			)
			(layer "F.Fab")
		)
		(fp_line
			(start -0.67945 0.3048)
			(end -0.67945 -0.305054)
			(stroke
				(width 0.1)
				(type default)
			)
			(layer "F.Fab")
		)
		(fp_line
			(start -0.12065 -0.305054)
			(end -0.12065 -0.2794)
			(stroke
				(width 0.1)
				(type default)
			)
			(layer "F.Fab")
		)
		(fp_line
			(start -0.12065 -0.2794)
			(end 0.12065 -0.2794)
			(stroke
				(width 0.1)
				(type default)
			)
			(layer "F.Fab")
		)
		(fp_line
			(start -0.12065 0.2794)
			(end -0.12065 0.3048)
			(stroke
				(width 0.1)
				(type default)
			)
			(layer "F.Fab")
		)
		(fp_line
			(start -0.12065 0.3048)
			(end -0.67945 0.3048)
			(stroke
				(width 0.1)
				(type default)
			)
			(layer "F.Fab")
		)
		(fp_line
			(start 0.120396 0.2794)
			(end -0.12065 0.2794)
			(stroke
				(width 0.1)
				(type default)
			)
			(layer "F.Fab")
		)
		(fp_line
			(start 0.120396 0.3048)
			(end 0.120396 0.2794)
			(stroke
				(width 0.1)
				(type default)
			)
			(layer "F.Fab")
		)
		(fp_line
			(start 0.12065 -0.3048)
			(end 0.67945 -0.3048)
			(stroke
				(width 0.1)
				(type default)
			)
			(layer "F.Fab")
		)
		(fp_line
			(start 0.12065 -0.2794)
			(end 0.12065 -0.3048)
			(stroke
				(width 0.1)
				(type default)
			)
			(layer "F.Fab")
		)
		(fp_line
			(start 0.67945 -0.3048)
			(end 0.67945 0.3048)
			(stroke
				(width 0.1)
				(type default)
			)
			(layer "F.Fab")
		)
		(fp_line
			(start 0.67945 0.3048)
			(end 0.120396 0.3048)
			(stroke
				(width 0.1)
				(type default)
			)
			(layer "F.Fab")
		)
		(pad "1" smd circle
			(at -0.40005 0)
			(size 0 0)
			(layers "F.Cu" "F.Mask" "F.Paste")
			(net "P3V3_STBY")
		)
		(pad "2" smd circle
			(at 0.40005 0)
			(size 0 0)
			(layers "F.Cu" "F.Mask" "F.Paste")
			(net "PD_FRU_A2")
		)
	)
	(footprint ""
		(layer "F.Cu")
		(at 18.415 -60.833 180)
		(property "Reference" "R17"
			(at -3.81 -0.02667 0)
			(unlocked yes)
			(layer "F.SilkS")
			(effects
				(font
					(size 0.7874 0.5842)
					(thickness 0.1524)
				)
			)
		)
		(property "Value" ""
			(at 0 0 180)
			(layer "F.Fab")
			(effects
				(font
					(size 1.27 1.27)
				)
			)
		)
		(duplicate_pad_numbers_are_jumpers no)
		(fp_line
			(start 0.7874 0.4064)
			(end -0.7874 0.4064)
			(stroke
				(width 0.1524)
				(type default)
			)
			(layer "F.SilkS")
		)
		(fp_line
			(start 0.7874 -0.4064)
			(end 0.7874 0.4064)
			(stroke
				(width 0.1524)
				(type default)
			)
			(layer "F.SilkS")
		)
		(fp_line
			(start -0.7874 0.4064)
			(end -0.7874 -0.4064)
			(stroke
				(width 0.1524)
				(type default)
			)
			(layer "F.SilkS")
		)
		(fp_line
			(start -0.7874 -0.4064)
			(end 0.7874 -0.4064)
			(stroke
				(width 0.1524)
				(type default)
			)
			(layer "F.SilkS")
		)
		(fp_line
			(start 0.67945 0.3048)
			(end 0.120396 0.3048)
			(stroke
				(width 0.1)
				(type default)
			)
			(layer "F.Fab")
		)
		(fp_line
			(start 0.67945 -0.3048)
			(end 0.67945 0.3048)
			(stroke
				(width 0.1)
				(type default)
			)
			(layer "F.Fab")
		)
		(fp_line
			(start 0.12065 -0.2794)
			(end 0.12065 -0.3048)
			(stroke
				(width 0.1)
				(type default)
			)
			(layer "F.Fab")
		)
		(fp_line
			(start 0.12065 -0.3048)
			(end 0.67945 -0.3048)
			(stroke
				(width 0.1)
				(type default)
			)
			(layer "F.Fab")
		)
		(fp_line
			(start 0.120396 0.3048)
			(end 0.120396 0.2794)
			(stroke
				(width 0.1)
				(type default)
			)
			(layer "F.Fab")
		)
		(fp_line
			(start 0.120396 0.2794)
			(end -0.12065 0.2794)
			(stroke
				(width 0.1)
				(type default)
			)
			(layer "F.Fab")
		)
		(fp_line
			(start -0.12065 0.3048)
			(end -0.67945 0.3048)
			(stroke
				(width 0.1)
				(type default)
			)
			(layer "F.Fab")
		)
		(fp_line
			(start -0.12065 0.2794)
			(end -0.12065 0.3048)
			(stroke
				(width 0.1)
				(type default)
			)
			(layer "F.Fab")
		)
		(fp_line
			(start -0.12065 -0.2794)
			(end 0.12065 -0.2794)
			(stroke
				(width 0.1)
				(type default)
			)
			(layer "F.Fab")
		)
		(fp_line
			(start -0.12065 -0.305054)
			(end -0.12065 -0.2794)
			(stroke
				(width 0.1)
				(type default)
			)
			(layer "F.Fab")
		)
		(fp_line
			(start -0.67945 0.3048)
			(end -0.67945 -0.305054)
			(stroke
				(width 0.1)
				(type default)
			)
			(layer "F.Fab")
		)
		(fp_line
			(start -0.67945 -0.305054)
			(end -0.12065 -0.305054)
			(stroke
				(width 0.1)
				(type default)
			)
			(layer "F.Fab")
		)
		(pad "1" smd circle
			(at -0.40005 0 180)
			(size 0 0)
			(layers "F.Cu" "F.Mask" "F.Paste")
			(net "SMB_SDA")
		)
		(pad "2" smd circle
			(at 0.40005 0 180)
			(size 0 0)
			(layers "F.Cu" "F.Mask" "F.Paste")
			(net "SMB_EXP_SDA")
		)
	)
	(footprint ""
		(layer "F.Cu")
		(at 23.495 -30.48)
		(property "Reference" "R66"
			(at 0.381 -0.98933 0)
			(unlocked yes)
			(layer "F.SilkS")
			(effects
				(font
					(size 0.7874 0.5842)
					(thickness 0.1524)
				)
			)
		)
		(property "Value" ""
			(at 0 0 0)
			(layer "F.Fab")
			(effects
				(font
					(size 1.27 1.27)
				)
			)
		)
		(duplicate_pad_numbers_are_jumpers no)
		(fp_line
			(start -0.7874 -0.4064)
			(end 0.7874 -0.4064)
			(stroke
				(width 0.1524)
				(type default)
			)
			(layer "F.SilkS")
		)
		(fp_line
			(start -0.7874 0.4064)
			(end -0.7874 -0.4064)
			(stroke
				(width 0.1524)
				(type default)
			)
			(layer "F.SilkS")
		)
		(fp_line
			(start 0.7874 -0.4064)
			(end 0.7874 0.4064)
			(stroke
				(width 0.1524)
				(type default)
			)
			(layer "F.SilkS")
		)
		(fp_line
			(start 0.7874 0.4064)
			(end -0.7874 0.4064)
			(stroke
				(width 0.1524)
				(type default)
			)
			(layer "F.SilkS")
		)
		(fp_line
			(start -0.67945 -0.305054)
			(end -0.12065 -0.305054)
			(stroke
				(width 0.1)
				(type default)
			)
			(layer "F.Fab")
		)
		(fp_line
			(start -0.67945 0.3048)
			(end -0.67945 -0.305054)
			(stroke
				(width 0.1)
				(type default)
			)
			(layer "F.Fab")
		)
		(fp_line
			(start -0.12065 -0.305054)
			(end -0.12065 -0.2794)
			(stroke
				(width 0.1)
				(type default)
			)
			(layer "F.Fab")
		)
		(fp_line
			(start -0.12065 -0.2794)
			(end 0.12065 -0.2794)
			(stroke
				(width 0.1)
				(type default)
			)
			(layer "F.Fab")
		)
		(fp_line
			(start -0.12065 0.2794)
			(end -0.12065 0.3048)
			(stroke
				(width 0.1)
				(type default)
			)
			(layer "F.Fab")
		)
		(fp_line
			(start -0.12065 0.3048)
			(end -0.67945 0.3048)
			(stroke
				(width 0.1)
				(type default)
			)
			(layer "F.Fab")
		)
		(fp_line
			(start 0.120396 0.2794)
			(end -0.12065 0.2794)
			(stroke
				(width 0.1)
				(type default)
			)
			(layer "F.Fab")
		)
		(fp_line
			(start 0.120396 0.3048)
			(end 0.120396 0.2794)
			(stroke
				(width 0.1)
				(type default)
			)
			(layer "F.Fab")
		)
		(fp_line
			(start 0.12065 -0.3048)
			(end 0.67945 -0.3048)
			(stroke
				(width 0.1)
				(type default)
			)
			(layer "F.Fab")
		)
		(fp_line
			(start 0.12065 -0.2794)
			(end 0.12065 -0.3048)
			(stroke
				(width 0.1)
				(type default)
			)
			(layer "F.Fab")
		)
		(fp_line
			(start 0.67945 -0.3048)
			(end 0.67945 0.3048)
			(stroke
				(width 0.1)
				(type default)
			)
			(layer "F.Fab")
		)
		(fp_line
			(start 0.67945 0.3048)
			(end 0.120396 0.3048)
			(stroke
				(width 0.1)
				(type default)
			)
			(layer "F.Fab")
		)
		(pad "1" smd circle
			(at -0.40005 0)
			(size 0 0)
			(layers "F.Cu" "F.Mask" "F.Paste")
			(net "UART_DEBUG_R_RX")
		)
		(pad "2" smd circle
			(at 0.40005 0)
			(size 0 0)
			(layers "F.Cu" "F.Mask" "F.Paste")
			(net "UART_DEBUG_RX")
		)
	)
	(footprint ""
		(layer "F.Cu")
		(at 32.385 -34.163 180)
		(property "Reference" "C14"
			(at 1.016 7.33933 0)
			(unlocked yes)
			(layer "F.SilkS")
			(effects
				(font
					(size 0.7874 0.5842)
					(thickness 0.1524)
				)
				(justify left)
			)
		)
		(property "Value" ""
			(at 0 0 180)
			(layer "F.Fab")
			(effects
				(font
					(size 1.27 1.27)
				)
			)
		)
		(duplicate_pad_numbers_are_jumpers no)
		(fp_line
			(start 1.524 0.762)
			(end -1.524 0.762)
			(stroke
				(width 0.1524)
				(type default)
			)
			(layer "F.SilkS")
		)
		(fp_line
			(start 1.524 -0.762)
			(end 1.524 0.762)
			(stroke
				(width 0.1524)
				(type default)
			)
			(layer "F.SilkS")
		)
		(fp_line
			(start -1.524 0.762)
			(end -1.524 -0.762)
			(stroke
				(width 0.1524)
				(type default)
			)
			(layer "F.SilkS")
		)
		(fp_line
			(start -1.524 -0.762)
			(end 1.524 -0.762)
			(stroke
				(width 0.1524)
				(type default)
			)
			(layer "F.SilkS")
		)
		(fp_line
			(start 1.1049 0.724916)
			(end 1.1049 -0.724916)
			(stroke
				(width 0.1)
				(type default)
			)
			(layer "F.Fab")
		)
		(fp_line
			(start 1.1049 -0.724916)
			(end -1.1049 -0.724916)
			(stroke
				(width 0.1)
				(type default)
			)
			(layer "F.Fab")
		)
		(fp_line
			(start -1.1049 0.724916)
			(end 1.1049 0.724916)
			(stroke
				(width 0.1)
				(type default)
			)
			(layer "F.Fab")
		)
		(fp_line
			(start -1.1049 -0.724916)
			(end -1.1049 0.724916)
			(stroke
				(width 0.1)
				(type default)
			)
			(layer "F.Fab")
		)
		(pad "1" smd rect
			(at -0.889 0)
			(size 1.016 1.27)
			(layers "F.Cu" "F.Mask" "F.Paste")
			(net "P5V_STBY_DEBUG")
		)
		(pad "2" smd rect
			(at 0.889 0)
			(size 1.016 1.27)
			(layers "F.Cu" "F.Mask" "F.Paste")
			(net "GND")
		)
	)
	(footprint ""
		(layer "F.Cu")
		(at 15.875 -45.085 180)
		(property "Reference" "R54"
			(at -2.54 -0.02667 0)
			(unlocked yes)
			(layer "F.SilkS")
			(effects
				(font
					(size 0.7874 0.5842)
					(thickness 0.1524)
				)
			)
		)
		(property "Value" ""
			(at 0 0 180)
			(layer "F.Fab")
			(effects
				(font
					(size 1.27 1.27)
				)
			)
		)
		(duplicate_pad_numbers_are_jumpers no)
		(fp_line
			(start 0.7874 0.4064)
			(end -0.7874 0.4064)
			(stroke
				(width 0.1524)
				(type default)
			)
			(layer "F.SilkS")
		)
		(fp_line
			(start 0.7874 -0.4064)
			(end 0.7874 0.4064)
			(stroke
				(width 0.1524)
				(type default)
			)
			(layer "F.SilkS")
		)
		(fp_line
			(start -0.7874 0.4064)
			(end -0.7874 -0.4064)
			(stroke
				(width 0.1524)
				(type default)
			)
			(layer "F.SilkS")
		)
		(fp_line
			(start -0.7874 -0.4064)
			(end 0.7874 -0.4064)
			(stroke
				(width 0.1524)
				(type default)
			)
			(layer "F.SilkS")
		)
		(fp_line
			(start 0.67945 0.3048)
			(end 0.120396 0.3048)
			(stroke
				(width 0.1)
				(type default)
			)
			(layer "F.Fab")
		)
		(fp_line
			(start 0.67945 -0.3048)
			(end 0.67945 0.3048)
			(stroke
				(width 0.1)
				(type default)
			)
			(layer "F.Fab")
		)
		(fp_line
			(start 0.12065 -0.2794)
			(end 0.12065 -0.3048)
			(stroke
				(width 0.1)
				(type default)
			)
			(layer "F.Fab")
		)
		(fp_line
			(start 0.12065 -0.3048)
			(end 0.67945 -0.3048)
			(stroke
				(width 0.1)
				(type default)
			)
			(layer "F.Fab")
		)
		(fp_line
			(start 0.120396 0.3048)
			(end 0.120396 0.2794)
			(stroke
				(width 0.1)
				(type default)
			)
			(layer "F.Fab")
		)
		(fp_line
			(start 0.120396 0.2794)
			(end -0.12065 0.2794)
			(stroke
				(width 0.1)
				(type default)
			)
			(layer "F.Fab")
		)
		(fp_line
			(start -0.12065 0.3048)
			(end -0.67945 0.3048)
			(stroke
				(width 0.1)
				(type default)
			)
			(layer "F.Fab")
		)
		(fp_line
			(start -0.12065 0.2794)
			(end -0.12065 0.3048)
			(stroke
				(width 0.1)
				(type default)
			)
			(layer "F.Fab")
		)
		(fp_line
			(start -0.12065 -0.2794)
			(end 0.12065 -0.2794)
			(stroke
				(width 0.1)
				(type default)
			)
			(layer "F.Fab")
		)
		(fp_line
			(start -0.12065 -0.305054)
			(end -0.12065 -0.2794)
			(stroke
				(width 0.1)
				(type default)
			)
			(layer "F.Fab")
		)
		(fp_line
			(start -0.67945 0.3048)
			(end -0.67945 -0.305054)
			(stroke
				(width 0.1)
				(type default)
			)
			(layer "F.Fab")
		)
		(fp_line
			(start -0.67945 -0.305054)
			(end -0.12065 -0.305054)
			(stroke
				(width 0.1)
				(type default)
			)
			(layer "F.Fab")
		)
		(pad "1" smd circle
			(at -0.40005 0 180)
			(size 0 0)
			(layers "F.Cu" "F.Mask" "F.Paste")
			(net "P3V3_STBY")
		)
		(pad "2" smd circle
			(at 0.40005 0 180)
			(size 0 0)
			(layers "F.Cu" "F.Mask" "F.Paste")
			(net "SMB_FRU_SDA")
		)
	)
	(footprint ""
		(layer "F.Cu")
		(at 18.415 -59.817 180)
		(property "Reference" "R16"
			(at -3.81 -0.02667 0)
			(unlocked yes)
			(layer "F.SilkS")
			(effects
				(font
					(size 0.7874 0.5842)
					(thickness 0.1524)
				)
			)
		)
		(property "Value" ""
			(at 0 0 180)
			(layer "F.Fab")
			(effects
				(font
					(size 1.27 1.27)
				)
			)
		)
		(duplicate_pad_numbers_are_jumpers no)
		(fp_line
			(start 0.7874 0.4064)
			(end -0.7874 0.4064)
			(stroke
				(width 0.1524)
				(type default)
			)
			(layer "F.SilkS")
		)
		(fp_line
			(start 0.7874 -0.4064)
			(end 0.7874 0.4064)
			(stroke
				(width 0.1524)
				(type default)
			)
			(layer "F.SilkS")
		)
		(fp_line
			(start -0.7874 0.4064)
			(end -0.7874 -0.4064)
			(stroke
				(width 0.1524)
				(type default)
			)
			(layer "F.SilkS")
		)
		(fp_line
			(start -0.7874 -0.4064)
			(end 0.7874 -0.4064)
			(stroke
				(width 0.1524)
				(type default)
			)
			(layer "F.SilkS")
		)
		(fp_line
			(start 0.67945 0.3048)
			(end 0.120396 0.3048)
			(stroke
				(width 0.1)
				(type default)
			)
			(layer "F.Fab")
		)
		(fp_line
			(start 0.67945 -0.3048)
			(end 0.67945 0.3048)
			(stroke
				(width 0.1)
				(type default)
			)
			(layer "F.Fab")
		)
		(fp_line
			(start 0.12065 -0.2794)
			(end 0.12065 -0.3048)
			(stroke
				(width 0.1)
				(type default)
			)
			(layer "F.Fab")
		)
		(fp_line
			(start 0.12065 -0.3048)
			(end 0.67945 -0.3048)
			(stroke
				(width 0.1)
				(type default)
			)
			(layer "F.Fab")
		)
		(fp_line
			(start 0.120396 0.3048)
			(end 0.120396 0.2794)
			(stroke
				(width 0.1)
				(type default)
			)
			(layer "F.Fab")
		)
		(fp_line
			(start 0.120396 0.2794)
			(end -0.12065 0.2794)
			(stroke
				(width 0.1)
				(type default)
			)
			(layer "F.Fab")
		)
		(fp_line
			(start -0.12065 0.3048)
			(end -0.67945 0.3048)
			(stroke
				(width 0.1)
				(type default)
			)
			(layer "F.Fab")
		)
		(fp_line
			(start -0.12065 0.2794)
			(end -0.12065 0.3048)
			(stroke
				(width 0.1)
				(type default)
			)
			(layer "F.Fab")
		)
		(fp_line
			(start -0.12065 -0.2794)
			(end 0.12065 -0.2794)
			(stroke
				(width 0.1)
				(type default)
			)
			(layer "F.Fab")
		)
		(fp_line
			(start -0.12065 -0.305054)
			(end -0.12065 -0.2794)
			(stroke
				(width 0.1)
				(type default)
			)
			(layer "F.Fab")
		)
		(fp_line
			(start -0.67945 0.3048)
			(end -0.67945 -0.305054)
			(stroke
				(width 0.1)
				(type default)
			)
			(layer "F.Fab")
		)
		(fp_line
			(start -0.67945 -0.305054)
			(end -0.12065 -0.305054)
			(stroke
				(width 0.1)
				(type default)
			)
			(layer "F.Fab")
		)
		(pad "1" smd circle
			(at -0.40005 0 180)
			(size 0 0)
			(layers "F.Cu" "F.Mask" "F.Paste")
			(net "SMB_SCL")
		)
		(pad "2" smd circle
			(at 0.40005 0 180)
			(size 0 0)
			(layers "F.Cu" "F.Mask" "F.Paste")
			(net "SMB_EXP_SCL")
		)
	)
	(footprint ""
		(layer "F.Cu")
		(at 15.875 -50.165)
		(property "Reference" "R64"
			(at 2.54 0.02667 0)
			(unlocked yes)
			(layer "F.SilkS")
			(effects
				(font
					(size 0.7874 0.5842)
					(thickness 0.1524)
				)
			)
		)
		(property "Value" ""
			(at 0 0 0)
			(layer "F.Fab")
			(effects
				(font
					(size 1.27 1.27)
				)
			)
		)
		(duplicate_pad_numbers_are_jumpers no)
		(fp_line
			(start -0.7874 -0.4064)
			(end 0.7874 -0.4064)
			(stroke
				(width 0.1524)
				(type default)
			)
			(layer "F.SilkS")
		)
		(fp_line
			(start -0.7874 0.4064)
			(end -0.7874 -0.4064)
			(stroke
				(width 0.1524)
				(type default)
			)
			(layer "F.SilkS")
		)
		(fp_line
			(start 0.7874 -0.4064)
			(end 0.7874 0.4064)
			(stroke
				(width 0.1524)
				(type default)
			)
			(layer "F.SilkS")
		)
		(fp_line
			(start 0.7874 0.4064)
			(end -0.7874 0.4064)
			(stroke
				(width 0.1524)
				(type default)
			)
			(layer "F.SilkS")
		)
		(fp_line
			(start -0.67945 -0.305054)
			(end -0.12065 -0.305054)
			(stroke
				(width 0.1)
				(type default)
			)
			(layer "F.Fab")
		)
		(fp_line
			(start -0.67945 0.3048)
			(end -0.67945 -0.305054)
			(stroke
				(width 0.1)
				(type default)
			)
			(layer "F.Fab")
		)
		(fp_line
			(start -0.12065 -0.305054)
			(end -0.12065 -0.2794)
			(stroke
				(width 0.1)
				(type default)
			)
			(layer "F.Fab")
		)
		(fp_line
			(start -0.12065 -0.2794)
			(end 0.12065 -0.2794)
			(stroke
				(width 0.1)
				(type default)
			)
			(layer "F.Fab")
		)
		(fp_line
			(start -0.12065 0.2794)
			(end -0.12065 0.3048)
			(stroke
				(width 0.1)
				(type default)
			)
			(layer "F.Fab")
		)
		(fp_line
			(start -0.12065 0.3048)
			(end -0.67945 0.3048)
			(stroke
				(width 0.1)
				(type default)
			)
			(layer "F.Fab")
		)
		(fp_line
			(start 0.120396 0.2794)
			(end -0.12065 0.2794)
			(stroke
				(width 0.1)
				(type default)
			)
			(layer "F.Fab")
		)
		(fp_line
			(start 0.120396 0.3048)
			(end 0.120396 0.2794)
			(stroke
				(width 0.1)
				(type default)
			)
			(layer "F.Fab")
		)
		(fp_line
			(start 0.12065 -0.3048)
			(end 0.67945 -0.3048)
			(stroke
				(width 0.1)
				(type default)
			)
			(layer "F.Fab")
		)
		(fp_line
			(start 0.12065 -0.2794)
			(end 0.12065 -0.3048)
			(stroke
				(width 0.1)
				(type default)
			)
			(layer "F.Fab")
		)
		(fp_line
			(start 0.67945 -0.3048)
			(end 0.67945 0.3048)
			(stroke
				(width 0.1)
				(type default)
			)
			(layer "F.Fab")
		)
		(fp_line
			(start 0.67945 0.3048)
			(end 0.120396 0.3048)
			(stroke
				(width 0.1)
				(type default)
			)
			(layer "F.Fab")
		)
		(pad "1" smd circle
			(at -0.40005 0)
			(size 0 0)
			(layers "F.Cu" "F.Mask" "F.Paste")
			(net "PD_FRU_WP")
		)
		(pad "2" smd circle
			(at 0.40005 0)
			(size 0 0)
			(layers "F.Cu" "F.Mask" "F.Paste")
			(net "GND")
		)
	)
	(footprint ""
		(layer "F.Cu")
		(at 3.937 -50.8)
		(property "Reference" "R63"
			(at -2.413 0.15367 0)
			(unlocked yes)
			(layer "F.SilkS")
			(effects
				(font
					(size 0.7874 0.5842)
					(thickness 0.1524)
				)
			)
		)
		(property "Value" ""
			(at 0 0 0)
			(layer "F.Fab")
			(effects
				(font
					(size 1.27 1.27)
				)
			)
		)
		(duplicate_pad_numbers_are_jumpers no)
		(fp_line
			(start -0.7874 -0.4064)
			(end 0.7874 -0.4064)
			(stroke
				(width 0.1524)
				(type default)
			)
			(layer "F.SilkS")
		)
		(fp_line
			(start -0.7874 0.4064)
			(end -0.7874 -0.4064)
			(stroke
				(width 0.1524)
				(type default)
			)
			(layer "F.SilkS")
		)
		(fp_line
			(start 0.7874 -0.4064)
			(end 0.7874 0.4064)
			(stroke
				(width 0.1524)
				(type default)
			)
			(layer "F.SilkS")
		)
		(fp_line
			(start 0.7874 0.4064)
			(end -0.7874 0.4064)
			(stroke
				(width 0.1524)
				(type default)
			)
			(layer "F.SilkS")
		)
		(fp_line
			(start -0.67945 -0.305054)
			(end -0.12065 -0.305054)
			(stroke
				(width 0.1)
				(type default)
			)
			(layer "F.Fab")
		)
		(fp_line
			(start -0.67945 0.3048)
			(end -0.67945 -0.305054)
			(stroke
				(width 0.1)
				(type default)
			)
			(layer "F.Fab")
		)
		(fp_line
			(start -0.12065 -0.305054)
			(end -0.12065 -0.2794)
			(stroke
				(width 0.1)
				(type default)
			)
			(layer "F.Fab")
		)
		(fp_line
			(start -0.12065 -0.2794)
			(end 0.12065 -0.2794)
			(stroke
				(width 0.1)
				(type default)
			)
			(layer "F.Fab")
		)
		(fp_line
			(start -0.12065 0.2794)
			(end -0.12065 0.3048)
			(stroke
				(width 0.1)
				(type default)
			)
			(layer "F.Fab")
		)
		(fp_line
			(start -0.12065 0.3048)
			(end -0.67945 0.3048)
			(stroke
				(width 0.1)
				(type default)
			)
			(layer "F.Fab")
		)
		(fp_line
			(start 0.120396 0.2794)
			(end -0.12065 0.2794)
			(stroke
				(width 0.1)
				(type default)
			)
			(layer "F.Fab")
		)
		(fp_line
			(start 0.120396 0.3048)
			(end 0.120396 0.2794)
			(stroke
				(width 0.1)
				(type default)
			)
			(layer "F.Fab")
		)
		(fp_line
			(start 0.12065 -0.3048)
			(end 0.67945 -0.3048)
			(stroke
				(width 0.1)
				(type default)
			)
			(layer "F.Fab")
		)
		(fp_line
			(start 0.12065 -0.2794)
			(end 0.12065 -0.3048)
			(stroke
				(width 0.1)
				(type default)
			)
			(layer "F.Fab")
		)
		(fp_line
			(start 0.67945 -0.3048)
			(end 0.67945 0.3048)
			(stroke
				(width 0.1)
				(type default)
			)
			(layer "F.Fab")
		)
		(fp_line
			(start 0.67945 0.3048)
			(end 0.120396 0.3048)
			(stroke
				(width 0.1)
				(type default)
			)
			(layer "F.Fab")
		)
		(pad "1" smd circle
			(at -0.40005 0)
			(size 0 0)
			(layers "F.Cu" "F.Mask" "F.Paste")
			(net "GND")
		)
		(pad "2" smd circle
			(at 0.40005 0)
			(size 0 0)
			(layers "F.Cu" "F.Mask" "F.Paste")
			(net "PD_FRU_A0")
		)
	)
	(footprint ""
		(layer "F.Cu")
		(at 21.717 -63.373 -90)
		(property "Reference" "R67"
			(at -0.254 -2.31267 90)
			(unlocked yes)
			(layer "F.SilkS")
			(effects
				(font
					(size 0.7874 0.5842)
					(thickness 0.1524)
				)
			)
		)
		(property "Value" ""
			(at 0 0 270)
			(layer "F.Fab")
			(effects
				(font
					(size 1.27 1.27)
				)
			)
		)
		(duplicate_pad_numbers_are_jumpers no)
		(fp_line
			(start -0.7874 0.4064)
			(end -0.7874 -0.4064)
			(stroke
				(width 0.1524)
				(type default)
			)
			(layer "F.SilkS")
		)
		(fp_line
			(start 0.7874 0.4064)
			(end -0.7874 0.4064)
			(stroke
				(width 0.1524)
				(type default)
			)
			(layer "F.SilkS")
		)
		(fp_line
			(start -0.7874 -0.4064)
			(end 0.7874 -0.4064)
			(stroke
				(width 0.1524)
				(type default)
			)
			(layer "F.SilkS")
		)
		(fp_line
			(start 0.7874 -0.4064)
			(end 0.7874 0.4064)
			(stroke
				(width 0.1524)
				(type default)
			)
			(layer "F.SilkS")
		)
		(fp_line
			(start -0.67945 0.3048)
			(end -0.67945 -0.305054)
			(stroke
				(width 0.1)
				(type default)
			)
			(layer "F.Fab")
		)
		(fp_line
			(start -0.12065 0.3048)
			(end -0.67945 0.3048)
			(stroke
				(width 0.1)
				(type default)
			)
			(layer "F.Fab")
		)
		(fp_line
			(start 0.120396 0.3048)
			(end 0.120396 0.2794)
			(stroke
				(width 0.1)
				(type default)
			)
			(layer "F.Fab")
		)
		(fp_line
			(start 0.67945 0.3048)
			(end 0.120396 0.3048)
			(stroke
				(width 0.1)
				(type default)
			)
			(layer "F.Fab")
		)
		(fp_line
			(start -0.12065 0.2794)
			(end -0.12065 0.3048)
			(stroke
				(width 0.1)
				(type default)
			)
			(layer "F.Fab")
		)
		(fp_line
			(start 0.120396 0.2794)
			(end -0.12065 0.2794)
			(stroke
				(width 0.1)
				(type default)
			)
			(layer "F.Fab")
		)
		(fp_line
			(start -0.12065 -0.2794)
			(end 0.12065 -0.2794)
			(stroke
				(width 0.1)
				(type default)
			)
			(layer "F.Fab")
		)
		(fp_line
			(start 0.12065 -0.2794)
			(end 0.12065 -0.3048)
			(stroke
				(width 0.1)
				(type default)
			)
			(layer "F.Fab")
		)
		(fp_line
			(start 0.12065 -0.3048)
			(end 0.67945 -0.3048)
			(stroke
				(width 0.1)
				(type default)
			)
			(layer "F.Fab")
		)
		(fp_line
			(start 0.67945 -0.3048)
			(end 0.67945 0.3048)
			(stroke
				(width 0.1)
				(type default)
			)
			(layer "F.Fab")
		)
		(fp_line
			(start -0.67945 -0.305054)
			(end -0.12065 -0.305054)
			(stroke
				(width 0.1)
				(type default)
			)
			(layer "F.Fab")
		)
		(fp_line
			(start -0.12065 -0.305054)
			(end -0.12065 -0.2794)
			(stroke
				(width 0.1)
				(type default)
			)
			(layer "F.Fab")
		)
		(pad "1" smd circle
			(at -0.40005 0 270)
			(size 0 0)
			(layers "F.Cu" "F.Mask" "F.Paste")
			(net "SMB_SWB_SCL")
		)
		(pad "2" smd circle
			(at 0.40005 0 270)
			(size 0 0)
			(layers "F.Cu" "F.Mask" "F.Paste")
			(net "SMB_SCL")
		)
	)
	(footprint ""
		(layer "F.Cu")
		(at 36.703 -27.432 180)
		(property "Reference" "R41"
			(at 7.874 0.35433 0)
			(unlocked yes)
			(layer "F.SilkS")
			(effects
				(font
					(size 0.7874 0.5842)
					(thickness 0.1524)
				)
			)
		)
		(property "Value" ""
			(at 0 0 180)
			(layer "F.Fab")
			(effects
				(font
					(size 1.27 1.27)
				)
			)
		)
		(duplicate_pad_numbers_are_jumpers no)
		(fp_line
			(start 0.7874 0.4064)
			(end -0.7874 0.4064)
			(stroke
				(width 0.1524)
				(type default)
			)
			(layer "F.SilkS")
		)
		(fp_line
			(start 0.7874 -0.4064)
			(end 0.7874 0.4064)
			(stroke
				(width 0.1524)
				(type default)
			)
			(layer "F.SilkS")
		)
		(fp_line
			(start -0.7874 0.4064)
			(end -0.7874 -0.4064)
			(stroke
				(width 0.1524)
				(type default)
			)
			(layer "F.SilkS")
		)
		(fp_line
			(start -0.7874 -0.4064)
			(end 0.7874 -0.4064)
			(stroke
				(width 0.1524)
				(type default)
			)
			(layer "F.SilkS")
		)
		(fp_line
			(start 0.67945 0.3048)
			(end 0.120396 0.3048)
			(stroke
				(width 0.1)
				(type default)
			)
			(layer "F.Fab")
		)
		(fp_line
			(start 0.67945 -0.3048)
			(end 0.67945 0.3048)
			(stroke
				(width 0.1)
				(type default)
			)
			(layer "F.Fab")
		)
		(fp_line
			(start 0.12065 -0.2794)
			(end 0.12065 -0.3048)
			(stroke
				(width 0.1)
				(type default)
			)
			(layer "F.Fab")
		)
		(fp_line
			(start 0.12065 -0.3048)
			(end 0.67945 -0.3048)
			(stroke
				(width 0.1)
				(type default)
			)
			(layer "F.Fab")
		)
		(fp_line
			(start 0.120396 0.3048)
			(end 0.120396 0.2794)
			(stroke
				(width 0.1)
				(type default)
			)
			(layer "F.Fab")
		)
		(fp_line
			(start 0.120396 0.2794)
			(end -0.12065 0.2794)
			(stroke
				(width 0.1)
				(type default)
			)
			(layer "F.Fab")
		)
		(fp_line
			(start -0.12065 0.3048)
			(end -0.67945 0.3048)
			(stroke
				(width 0.1)
				(type default)
			)
			(layer "F.Fab")
		)
		(fp_line
			(start -0.12065 0.2794)
			(end -0.12065 0.3048)
			(stroke
				(width 0.1)
				(type default)
			)
			(layer "F.Fab")
		)
		(fp_line
			(start -0.12065 -0.2794)
			(end 0.12065 -0.2794)
			(stroke
				(width 0.1)
				(type default)
			)
			(layer "F.Fab")
		)
		(fp_line
			(start -0.12065 -0.305054)
			(end -0.12065 -0.2794)
			(stroke
				(width 0.1)
				(type default)
			)
			(layer "F.Fab")
		)
		(fp_line
			(start -0.67945 0.3048)
			(end -0.67945 -0.305054)
			(stroke
				(width 0.1)
				(type default)
			)
			(layer "F.Fab")
		)
		(fp_line
			(start -0.67945 -0.305054)
			(end -0.12065 -0.305054)
			(stroke
				(width 0.1)
				(type default)
			)
			(layer "F.Fab")
		)
		(pad "1" smd circle
			(at -0.40005 0 180)
			(size 0 0)
			(layers "F.Cu" "F.Mask" "F.Paste")
			(net "P3V3_STBY")
		)
		(pad "2" smd circle
			(at 0.40005 0 180)
			(size 0 0)
			(layers "F.Cu" "F.Mask" "F.Paste")
			(net "NCP380_FLT_N")
		)
	)
	(footprint ""
		(layer "F.Cu")
		(at 18.415 -55.753)
		(property "Reference" "R14"
			(at 3.81 0.02667 0)
			(unlocked yes)
			(layer "F.SilkS")
			(effects
				(font
					(size 0.7874 0.5842)
					(thickness 0.1524)
				)
			)
		)
		(property "Value" ""
			(at 0 0 0)
			(layer "F.Fab")
			(effects
				(font
					(size 1.27 1.27)
				)
			)
		)
		(duplicate_pad_numbers_are_jumpers no)
		(fp_line
			(start -0.7874 -0.4064)
			(end 0.7874 -0.4064)
			(stroke
				(width 0.1524)
				(type default)
			)
			(layer "F.SilkS")
		)
		(fp_line
			(start -0.7874 0.4064)
			(end -0.7874 -0.4064)
			(stroke
				(width 0.1524)
				(type default)
			)
			(layer "F.SilkS")
		)
		(fp_line
			(start 0.7874 -0.4064)
			(end 0.7874 0.4064)
			(stroke
				(width 0.1524)
				(type default)
			)
			(layer "F.SilkS")
		)
		(fp_line
			(start 0.7874 0.4064)
			(end -0.7874 0.4064)
			(stroke
				(width 0.1524)
				(type default)
			)
			(layer "F.SilkS")
		)
		(fp_line
			(start -0.67945 -0.305054)
			(end -0.12065 -0.305054)
			(stroke
				(width 0.1)
				(type default)
			)
			(layer "F.Fab")
		)
		(fp_line
			(start -0.67945 0.3048)
			(end -0.67945 -0.305054)
			(stroke
				(width 0.1)
				(type default)
			)
			(layer "F.Fab")
		)
		(fp_line
			(start -0.12065 -0.305054)
			(end -0.12065 -0.2794)
			(stroke
				(width 0.1)
				(type default)
			)
			(layer "F.Fab")
		)
		(fp_line
			(start -0.12065 -0.2794)
			(end 0.12065 -0.2794)
			(stroke
				(width 0.1)
				(type default)
			)
			(layer "F.Fab")
		)
		(fp_line
			(start -0.12065 0.2794)
			(end -0.12065 0.3048)
			(stroke
				(width 0.1)
				(type default)
			)
			(layer "F.Fab")
		)
		(fp_line
			(start -0.12065 0.3048)
			(end -0.67945 0.3048)
			(stroke
				(width 0.1)
				(type default)
			)
			(layer "F.Fab")
		)
		(fp_line
			(start 0.120396 0.2794)
			(end -0.12065 0.2794)
			(stroke
				(width 0.1)
				(type default)
			)
			(layer "F.Fab")
		)
		(fp_line
			(start 0.120396 0.3048)
			(end 0.120396 0.2794)
			(stroke
				(width 0.1)
				(type default)
			)
			(layer "F.Fab")
		)
		(fp_line
			(start 0.12065 -0.3048)
			(end 0.67945 -0.3048)
			(stroke
				(width 0.1)
				(type default)
			)
			(layer "F.Fab")
		)
		(fp_line
			(start 0.12065 -0.2794)
			(end 0.12065 -0.3048)
			(stroke
				(width 0.1)
				(type default)
			)
			(layer "F.Fab")
		)
		(fp_line
			(start 0.67945 -0.3048)
			(end 0.67945 0.3048)
			(stroke
				(width 0.1)
				(type default)
			)
			(layer "F.Fab")
		)
		(fp_line
			(start 0.67945 0.3048)
			(end 0.120396 0.3048)
			(stroke
				(width 0.1)
				(type default)
			)
			(layer "F.Fab")
		)
		(pad "1" smd circle
			(at -0.40005 0)
			(size 0 0)
			(layers "F.Cu" "F.Mask" "F.Paste")
			(net "SYSTEM_FAULT_ID_LED")
		)
		(pad "2" smd circle
			(at 0.40005 0)
			(size 0 0)
			(layers "F.Cu" "F.Mask" "F.Paste")
			(net "SYSTEM_FAULT_ID_LED_R1")
		)
	)
	(footprint ""
		(layer "F.Cu")
		(at 18.669 -66.294)
		(property "Reference" "C1"
			(at 0.635 1.42367 0)
			(unlocked yes)
			(layer "F.SilkS")
			(effects
				(font
					(size 0.7874 0.5842)
					(thickness 0.1524)
				)
			)
		)
		(property "Value" ""
			(at 0 0 0)
			(layer "F.Fab")
			(effects
				(font
					(size 1.27 1.27)
				)
			)
		)
		(duplicate_pad_numbers_are_jumpers no)
		(fp_line
			(start -1.2954 -0.5842)
			(end 1.2954 -0.5842)
			(stroke
				(width 0.1524)
				(type default)
			)
			(layer "F.SilkS")
		)
		(fp_line
			(start -1.2954 0.5842)
			(end -1.2954 -0.5842)
			(stroke
				(width 0.1524)
				(type default)
			)
			(layer "F.SilkS")
		)
		(fp_line
			(start 1.2954 -0.5842)
			(end 1.2954 0.5842)
			(stroke
				(width 0.1524)
				(type default)
			)
			(layer "F.SilkS")
		)
		(fp_line
			(start 1.2954 0.5842)
			(end -1.2954 0.5842)
			(stroke
				(width 0.1524)
				(type default)
			)
			(layer "F.SilkS")
		)
		(fp_line
			(start -1.1938 -0.4064)
			(end -0.8636 -0.4064)
			(stroke
				(width 0.1)
				(type default)
			)
			(layer "F.Fab")
		)
		(fp_line
			(start -1.1938 0.4064)
			(end -1.1938 -0.4064)
			(stroke
				(width 0.1)
				(type default)
			)
			(layer "F.Fab")
		)
		(fp_line
			(start -0.8636 -0.4572)
			(end 0.8636 -0.4572)
			(stroke
				(width 0.1)
				(type default)
			)
			(layer "F.Fab")
		)
		(fp_line
			(start -0.8636 -0.4064)
			(end -0.8636 -0.4572)
			(stroke
				(width 0.1)
				(type default)
			)
			(layer "F.Fab")
		)
		(fp_line
			(start -0.8636 0.4064)
			(end -1.1938 0.4064)
			(stroke
				(width 0.1)
				(type default)
			)
			(layer "F.Fab")
		)
		(fp_line
			(start -0.8636 0.4572)
			(end -0.8636 0.4064)
			(stroke
				(width 0.1)
				(type default)
			)
			(layer "F.Fab")
		)
		(fp_line
			(start 0.8636 -0.4572)
			(end 0.8636 -0.4064)
			(stroke
				(width 0.1)
				(type default)
			)
			(layer "F.Fab")
		)
		(fp_line
			(start 0.8636 -0.4064)
			(end 1.1938 -0.4064)
			(stroke
				(width 0.1)
				(type default)
			)
			(layer "F.Fab")
		)
		(fp_line
			(start 0.8636 0.4064)
			(end 0.8636 0.4572)
			(stroke
				(width 0.1)
				(type default)
			)
			(layer "F.Fab")
		)
		(fp_line
			(start 0.8636 0.4572)
			(end -0.8636 0.4572)
			(stroke
				(width 0.1)
				(type default)
			)
			(layer "F.Fab")
		)
		(fp_line
			(start 1.1938 -0.4064)
			(end 1.1938 0.4064)
			(stroke
				(width 0.1)
				(type default)
			)
			(layer "F.Fab")
		)
		(fp_line
			(start 1.1938 0.4064)
			(end 0.8636 0.4064)
			(stroke
				(width 0.1)
				(type default)
			)
			(layer "F.Fab")
		)
		(pad "1" smd rect
			(at -0.7366 0 270)
			(size 0.7112 0.8128)
			(layers "F.Cu" "F.Mask" "F.Paste")
			(net "P3V3_STBY")
		)
		(pad "2" smd rect
			(at 0.7366 0 270)
			(size 0.7112 0.8128)
			(layers "F.Cu" "F.Mask" "F.Paste")
			(net "GND")
		)
	)
	(footprint ""
		(layer "F.Cu")
		(at 15.875 -66.294 180)
		(property "Reference" "C3"
			(at 2.413 -0.02667 0)
			(unlocked yes)
			(layer "F.SilkS")
			(effects
				(font
					(size 0.7874 0.5842)
					(thickness 0.1524)
				)
			)
		)
		(property "Value" ""
			(at 0 0 180)
			(layer "F.Fab")
			(effects
				(font
					(size 1.27 1.27)
				)
			)
		)
		(duplicate_pad_numbers_are_jumpers no)
		(fp_line
			(start 1.2954 0.5842)
			(end -1.2954 0.5842)
			(stroke
				(width 0.1524)
				(type default)
			)
			(layer "F.SilkS")
		)
		(fp_line
			(start 1.2954 -0.5842)
			(end 1.2954 0.5842)
			(stroke
				(width 0.1524)
				(type default)
			)
			(layer "F.SilkS")
		)
		(fp_line
			(start -1.2954 0.5842)
			(end -1.2954 -0.5842)
			(stroke
				(width 0.1524)
				(type default)
			)
			(layer "F.SilkS")
		)
		(fp_line
			(start -1.2954 -0.5842)
			(end 1.2954 -0.5842)
			(stroke
				(width 0.1524)
				(type default)
			)
			(layer "F.SilkS")
		)
		(fp_line
			(start 1.1938 0.4064)
			(end 0.8636 0.4064)
			(stroke
				(width 0.1)
				(type default)
			)
			(layer "F.Fab")
		)
		(fp_line
			(start 1.1938 -0.4064)
			(end 1.1938 0.4064)
			(stroke
				(width 0.1)
				(type default)
			)
			(layer "F.Fab")
		)
		(fp_line
			(start 0.8636 0.4572)
			(end -0.8636 0.4572)
			(stroke
				(width 0.1)
				(type default)
			)
			(layer "F.Fab")
		)
		(fp_line
			(start 0.8636 0.4064)
			(end 0.8636 0.4572)
			(stroke
				(width 0.1)
				(type default)
			)
			(layer "F.Fab")
		)
		(fp_line
			(start 0.8636 -0.4064)
			(end 1.1938 -0.4064)
			(stroke
				(width 0.1)
				(type default)
			)
			(layer "F.Fab")
		)
		(fp_line
			(start 0.8636 -0.4572)
			(end 0.8636 -0.4064)
			(stroke
				(width 0.1)
				(type default)
			)
			(layer "F.Fab")
		)
		(fp_line
			(start -0.8636 0.4572)
			(end -0.8636 0.4064)
			(stroke
				(width 0.1)
				(type default)
			)
			(layer "F.Fab")
		)
		(fp_line
			(start -0.8636 0.4064)
			(end -1.1938 0.4064)
			(stroke
				(width 0.1)
				(type default)
			)
			(layer "F.Fab")
		)
		(fp_line
			(start -0.8636 -0.4064)
			(end -0.8636 -0.4572)
			(stroke
				(width 0.1)
				(type default)
			)
			(layer "F.Fab")
		)
		(fp_line
			(start -0.8636 -0.4572)
			(end 0.8636 -0.4572)
			(stroke
				(width 0.1)
				(type default)
			)
			(layer "F.Fab")
		)
		(fp_line
			(start -1.1938 0.4064)
			(end -1.1938 -0.4064)
			(stroke
				(width 0.1)
				(type default)
			)
			(layer "F.Fab")
		)
		(fp_line
			(start -1.1938 -0.4064)
			(end -0.8636 -0.4064)
			(stroke
				(width 0.1)
				(type default)
			)
			(layer "F.Fab")
		)
		(pad "1" smd rect
			(at -0.7366 0 90)
			(size 0.7112 0.8128)
			(layers "F.Cu" "F.Mask" "F.Paste")
			(net "P5V_STBY")
		)
		(pad "2" smd rect
			(at 0.7366 0 90)
			(size 0.7112 0.8128)
			(layers "F.Cu" "F.Mask" "F.Paste")
			(net "GND")
		)
	)
	(footprint ""
		(layer "F.Cu")
		(at 32.800036 -62.875922 180)
		(property "Reference" "H10"
			(at -3.267964 7.709408 0)
			(unlocked yes)
			(layer "F.SilkS")
			(effects
				(font
					(size 0.7874 0.5842)
					(thickness 0.1524)
				)
				(justify left)
			)
		)
		(property "Value" ""
			(at 0 0 180)
			(layer "F.Fab")
			(effects
				(font
					(size 1.27 1.27)
				)
			)
		)
		(duplicate_pad_numbers_are_jumpers no)
		(fp_arc
			(start 7.662418 -2.299462)
			(mid 1.162068 7.915133)
			(end -7.999984 0)
			(stroke
				(width 0.1524)
				(type default)
			)
			(layer "F.SilkS")
		)
		(fp_arc
			(start -7.999984 0)
			(mid -7.435749 -2.951077)
			(end -5.822696 -5.485892)
			(stroke
				(width 0.1524)
				(type default)
			)
			(layer "F.SilkS")
		)
		(fp_arc
			(start 6.784086 4.239768)
			(mid 5.411387 5.892142)
			(end 3.648456 7.11962)
			(stroke
				(width 0.1524)
				(type default)
			)
			(layer "B.SilkS")
		)
		(fp_arc
			(start -0.09271 -7.999476)
			(mid 2.72788 -7.520639)
			(end 5.199634 -6.079998)
			(stroke
				(width 0.1524)
				(type default)
			)
			(layer "B.SilkS")
		)
		(fp_arc
			(start -3.65887 7.114286)
			(mid -7.943333 0.95039)
			(end -5.233924 -6.05028)
			(stroke
				(width 0.1524)
				(type default)
			)
			(layer "B.SilkS")
		)
		(fp_arc
			(start -4.141978 -6.844284)
			(mid -2.811186 -7.489822)
			(end -1.3843 -7.879334)
			(stroke
				(width 0.1524)
				(type default)
			)
			(layer "B.SilkS")
		)
		(fp_circle
			(center 0 0)
			(end -7.999984 0)
			(stroke
				(width 0.1)
				(type default)
			)
			(fill no)
			(layer "B.Fab")
		)
		(fp_circle
			(center 0 0)
			(end -7.999984 0)
			(stroke
				(width 0.1)
				(type default)
			)
			(fill no)
			(layer "F.Fab")
		)
		(pad "" np_thru_hole circle
			(at 0 0 180)
			(size 4.0132 4.0132)
			(drill 4.0132)
			(layers "*.Cu" "*.Mask")
			(clearance 0.381)
			(thermal_gap 0.381)
		)
		(pad "2" thru_hole circle
			(at 3.758692 0 180)
			(size 0.762 0.762)
			(drill 0.5588)
			(layers "*.Cu" "*.Mask")
			(remove_unused_layers no)
			(net "GND")
			(clearance 0.1524)
			(thermal_gap 0.1524)
		)
		(pad "3" thru_hole circle
			(at 2.657602 -2.657602 180)
			(size 0.762 0.762)
			(drill 0.5588)
			(layers "*.Cu" "*.Mask")
			(remove_unused_layers no)
			(net "GND")
			(clearance 0.1524)
			(thermal_gap 0.1524)
		)
		(pad "4" thru_hole circle
			(at 0 -3.758692 180)
			(size 0.762 0.762)
			(drill 0.5588)
			(layers "*.Cu" "*.Mask")
			(remove_unused_layers no)
			(net "GND")
			(clearance 0.1524)
			(thermal_gap 0.1524)
		)
		(pad "5" thru_hole circle
			(at -2.657602 -2.657602 180)
			(size 0.762 0.762)
			(drill 0.5588)
			(layers "*.Cu" "*.Mask")
			(remove_unused_layers no)
			(net "GND")
			(clearance 0.1524)
			(thermal_gap 0.1524)
		)
		(pad "6" thru_hole circle
			(at -3.758692 0 180)
			(size 0.762 0.762)
			(drill 0.5588)
			(layers "*.Cu" "*.Mask")
			(remove_unused_layers no)
			(net "GND")
			(clearance 0.1524)
			(thermal_gap 0.1524)
		)
		(pad "7" thru_hole circle
			(at -2.657602 2.657602 180)
			(size 0.762 0.762)
			(drill 0.5588)
			(layers "*.Cu" "*.Mask")
			(remove_unused_layers no)
			(net "GND")
			(clearance 0.1524)
			(thermal_gap 0.1524)
		)
		(pad "8" thru_hole circle
			(at 0 3.758692 180)
			(size 0.762 0.762)
			(drill 0.5588)
			(layers "*.Cu" "*.Mask")
			(remove_unused_layers no)
			(net "GND")
			(clearance 0.1524)
			(thermal_gap 0.1524)
		)
		(pad "9" thru_hole circle
			(at 2.657602 2.657602 180)
			(size 0.762 0.762)
			(drill 0.5588)
			(layers "*.Cu" "*.Mask")
			(remove_unused_layers no)
			(net "GND")
			(clearance 0.1524)
			(thermal_gap 0.1524)
		)
		(zone
			(layer "F.Cu")
			(hatch none 0.5)
			(connect_pads
				(clearance 0)
			)
			(min_thickness 0.25)
			(keepout
				(tracks not_allowed)
				(vias allowed)
				(pads allowed)
				(copperpour not_allowed)
				(footprints allowed)
			)
			(placement
				(enabled no)
				(sheetname "")
			)
			(fill
				(thermal_gap 0.5)
				(thermal_bridge_width 0.5)
				(island_removal_mode 0)
			)
			(polygon
				(pts
					(arc
						(start 32.800036 -57.621932)
						(mid 27.546046 -62.875922)
						(end 32.800036 -68.129912)
					)
					(arc
						(start 32.800036 -67.901312)
						(mid 27.774646 -62.875922)
						(end 32.800036 -57.850532)
					)
				)
			)
		)
		(zone
			(layer "F.Cu")
			(hatch none 0.5)
			(connect_pads
				(clearance 0)
			)
			(min_thickness 0.25)
			(keepout
				(tracks not_allowed)
				(vias allowed)
				(pads allowed)
				(copperpour not_allowed)
				(footprints allowed)
			)
			(placement
				(enabled no)
				(sheetname "")
			)
			(fill
				(thermal_gap 0.5)
				(thermal_bridge_width 0.5)
				(island_removal_mode 0)
			)
			(polygon
				(pts
					(arc
						(start 32.800036 -57.621932)
						(mid 38.054026 -62.875922)
						(end 32.800036 -68.129912)
					)
					(arc
						(start 32.800036 -67.901312)
						(mid 37.825426 -62.875922)
						(end 32.800036 -57.850532)
					)
				)
			)
		)
		(zone
			(layer "F.Cu")
			(hatch none 0.5)
			(connect_pads
				(clearance 0)
			)
			(min_thickness 0.25)
			(keepout
				(tracks not_allowed)
				(vias allowed)
				(pads allowed)
				(copperpour not_allowed)
				(footprints allowed)
			)
			(placement
				(enabled no)
				(sheetname "")
			)
			(fill
				(thermal_gap 0.5)
				(thermal_bridge_width 0.5)
				(island_removal_mode 0)
			)
			(polygon
				(pts
					(arc
						(start 32.800036 -70.875906)
						(mid 24.800052 -62.875922)
						(end 32.800036 -54.875938)
					)
					(arc
						(start 32.800036 -57.621932)
						(mid 27.464766 -62.957202)
						(end 32.800036 -68.292218)
					)
				)
			)
		)
		(zone
			(layer "F.Cu")
			(hatch none 0.5)
			(connect_pads
				(clearance 0)
			)
			(min_thickness 0.25)
			(keepout
				(tracks not_allowed)
				(vias allowed)
				(pads allowed)
				(copperpour not_allowed)
				(footprints allowed)
			)
			(placement
				(enabled no)
				(sheetname "")
			)
			(fill
				(thermal_gap 0.5)
				(thermal_bridge_width 0.5)
				(island_removal_mode 0)
			)
			(polygon
				(pts
					(arc
						(start 32.800036 -70.875906)
						(mid 40.80002 -62.875922)
						(end 32.800036 -54.875938)
					)
					(arc
						(start 32.800036 -57.621932)
						(mid 38.135306 -62.957202)
						(end 32.800036 -68.292218)
					)
				)
			)
		)
		(zone
			(layers "F.Cu" "B.Cu" "In1.Cu" "In2.Cu")
			(hatch none 0.5)
			(connect_pads
				(clearance 0)
			)
			(min_thickness 0.25)
			(keepout
				(tracks not_allowed)
				(vias allowed)
				(pads allowed)
				(copperpour not_allowed)
				(footprints allowed)
			)
			(placement
				(enabled no)
				(sheetname "")
			)
			(fill
				(thermal_gap 0.5)
				(thermal_bridge_width 0.5)
				(island_removal_mode 0)
			)
			(polygon
				(pts
					(arc
						(start 35.314636 -62.875922)
						(mid 30.285436 -62.875922)
						(end 35.314636 -62.875922)
					)
				)
			)
		)
		(zone
			(layer "B.Cu")
			(hatch none 0.5)
			(connect_pads
				(clearance 0)
			)
			(min_thickness 0.25)
			(keepout
				(tracks not_allowed)
				(vias allowed)
				(pads allowed)
				(copperpour not_allowed)
				(footprints allowed)
			)
			(placement
				(enabled no)
				(sheetname "")
			)
			(fill
				(thermal_gap 0.5)
				(thermal_bridge_width 0.5)
				(island_removal_mode 0)
			)
			(polygon
				(pts
					(arc
						(start 27.292046 -66.376042)
						(mid 28.905299 -70.270779)
						(end 32.800036 -71.884032)
					)
					(arc
						(start 32.800036 -71.401432)
						(mid 29.246549 -69.929529)
						(end 27.774646 -66.376042)
					)
					(arc
						(start 27.774646 -62.875922)
						(mid 29.246549 -59.322435)
						(end 32.800036 -57.850532)
					)
					(arc
						(start 32.800036 -57.367932)
						(mid 28.905299 -58.981185)
						(end 27.292046 -62.875922)
					)
				)
			)
		)
		(zone
			(layer "B.Cu")
			(hatch none 0.5)
			(connect_pads
				(clearance 0)
			)
			(min_thickness 0.25)
			(keepout
				(tracks not_allowed)
				(vias allowed)
				(pads allowed)
				(copperpour not_allowed)
				(footprints allowed)
			)
			(placement
				(enabled no)
				(sheetname "")
			)
			(fill
				(thermal_gap 0.5)
				(thermal_bridge_width 0.5)
				(island_removal_mode 0)
			)
			(polygon
				(pts
					(arc
						(start 38.308026 -66.376042)
						(mid 36.694773 -70.270779)
						(end 32.800036 -71.884032)
					)
					(arc
						(start 32.800036 -71.401432)
						(mid 36.353523 -69.929529)
						(end 37.825426 -66.376042)
					)
					(arc
						(start 37.825426 -62.875922)
						(mid 36.353523 -59.322435)
						(end 32.800036 -57.850532)
					)
					(arc
						(start 32.800036 -57.367932)
						(mid 36.694773 -58.981185)
						(end 38.308026 -62.875922)
					)
				)
			)
		)
	)
	(footprint ""
		(layer "F.Cu")
		(at 31.18485 -23.797768 -90)
		(property "Reference" "R51"
			(at 0.937768 1.05918 90)
			(unlocked yes)
			(layer "F.SilkS")
			(effects
				(font
					(size 0.7874 0.5842)
					(thickness 0.1524)
				)
				(justify left)
			)
		)
		(property "Value" ""
			(at 0 0 270)
			(layer "F.Fab")
			(effects
				(font
					(size 1.27 1.27)
				)
			)
		)
		(duplicate_pad_numbers_are_jumpers no)
		(fp_line
			(start -0.7874 0.4064)
			(end -0.7874 -0.4064)
			(stroke
				(width 0.1524)
				(type default)
			)
			(layer "F.SilkS")
		)
		(fp_line
			(start 0.7874 0.4064)
			(end -0.7874 0.4064)
			(stroke
				(width 0.1524)
				(type default)
			)
			(layer "F.SilkS")
		)
		(fp_line
			(start -0.7874 -0.4064)
			(end 0.7874 -0.4064)
			(stroke
				(width 0.1524)
				(type default)
			)
			(layer "F.SilkS")
		)
		(fp_line
			(start 0.7874 -0.4064)
			(end 0.7874 0.4064)
			(stroke
				(width 0.1524)
				(type default)
			)
			(layer "F.SilkS")
		)
		(fp_line
			(start -0.67945 0.3048)
			(end -0.67945 -0.305054)
			(stroke
				(width 0.1)
				(type default)
			)
			(layer "F.Fab")
		)
		(fp_line
			(start -0.12065 0.3048)
			(end -0.67945 0.3048)
			(stroke
				(width 0.1)
				(type default)
			)
			(layer "F.Fab")
		)
		(fp_line
			(start 0.120396 0.3048)
			(end 0.120396 0.2794)
			(stroke
				(width 0.1)
				(type default)
			)
			(layer "F.Fab")
		)
		(fp_line
			(start 0.67945 0.3048)
			(end 0.120396 0.3048)
			(stroke
				(width 0.1)
				(type default)
			)
			(layer "F.Fab")
		)
		(fp_line
			(start -0.12065 0.2794)
			(end -0.12065 0.3048)
			(stroke
				(width 0.1)
				(type default)
			)
			(layer "F.Fab")
		)
		(fp_line
			(start 0.120396 0.2794)
			(end -0.12065 0.2794)
			(stroke
				(width 0.1)
				(type default)
			)
			(layer "F.Fab")
		)
		(fp_line
			(start -0.12065 -0.2794)
			(end 0.12065 -0.2794)
			(stroke
				(width 0.1)
				(type default)
			)
			(layer "F.Fab")
		)
		(fp_line
			(start 0.12065 -0.2794)
			(end 0.12065 -0.3048)
			(stroke
				(width 0.1)
				(type default)
			)
			(layer "F.Fab")
		)
		(fp_line
			(start 0.12065 -0.3048)
			(end 0.67945 -0.3048)
			(stroke
				(width 0.1)
				(type default)
			)
			(layer "F.Fab")
		)
		(fp_line
			(start 0.67945 -0.3048)
			(end 0.67945 0.3048)
			(stroke
				(width 0.1)
				(type default)
			)
			(layer "F.Fab")
		)
		(fp_line
			(start -0.67945 -0.305054)
			(end -0.12065 -0.305054)
			(stroke
				(width 0.1)
				(type default)
			)
			(layer "F.Fab")
		)
		(fp_line
			(start -0.12065 -0.305054)
			(end -0.12065 -0.2794)
			(stroke
				(width 0.1)
				(type default)
			)
			(layer "F.Fab")
		)
		(pad "1" smd rect
			(at -0.40005 0 90)
			(size 0.4572 0.508)
			(layers "F.Cu" "F.Mask" "F.Paste")
			(net "USB2_DN")
		)
		(pad "2" smd rect
			(at 0.40005 0 90)
			(size 0.4572 0.508)
			(layers "F.Cu" "F.Mask" "F.Paste")
			(net "USB2_DEBUG_DN")
		)
	)
	(footprint ""
		(layer "F.Cu")
		(at 5.969 -58.293 180)
		(property "Reference" "R28"
			(at 2.794 -0.40767 0)
			(unlocked yes)
			(layer "F.SilkS")
			(effects
				(font
					(size 0.7874 0.5842)
					(thickness 0.1524)
				)
			)
		)
		(property "Value" ""
			(at 0 0 180)
			(layer "F.Fab")
			(effects
				(font
					(size 1.27 1.27)
				)
			)
		)
		(duplicate_pad_numbers_are_jumpers no)
		(fp_line
			(start 0.7874 0.4064)
			(end -0.7874 0.4064)
			(stroke
				(width 0.1524)
				(type default)
			)
			(layer "F.SilkS")
		)
		(fp_line
			(start 0.7874 -0.4064)
			(end 0.7874 0.4064)
			(stroke
				(width 0.1524)
				(type default)
			)
			(layer "F.SilkS")
		)
		(fp_line
			(start -0.7874 0.4064)
			(end -0.7874 -0.4064)
			(stroke
				(width 0.1524)
				(type default)
			)
			(layer "F.SilkS")
		)
		(fp_line
			(start -0.7874 -0.4064)
			(end 0.7874 -0.4064)
			(stroke
				(width 0.1524)
				(type default)
			)
			(layer "F.SilkS")
		)
		(fp_line
			(start 0.67945 0.3048)
			(end 0.120396 0.3048)
			(stroke
				(width 0.1)
				(type default)
			)
			(layer "F.Fab")
		)
		(fp_line
			(start 0.67945 -0.3048)
			(end 0.67945 0.3048)
			(stroke
				(width 0.1)
				(type default)
			)
			(layer "F.Fab")
		)
		(fp_line
			(start 0.12065 -0.2794)
			(end 0.12065 -0.3048)
			(stroke
				(width 0.1)
				(type default)
			)
			(layer "F.Fab")
		)
		(fp_line
			(start 0.12065 -0.3048)
			(end 0.67945 -0.3048)
			(stroke
				(width 0.1)
				(type default)
			)
			(layer "F.Fab")
		)
		(fp_line
			(start 0.120396 0.3048)
			(end 0.120396 0.2794)
			(stroke
				(width 0.1)
				(type default)
			)
			(layer "F.Fab")
		)
		(fp_line
			(start 0.120396 0.2794)
			(end -0.12065 0.2794)
			(stroke
				(width 0.1)
				(type default)
			)
			(layer "F.Fab")
		)
		(fp_line
			(start -0.12065 0.3048)
			(end -0.67945 0.3048)
			(stroke
				(width 0.1)
				(type default)
			)
			(layer "F.Fab")
		)
		(fp_line
			(start -0.12065 0.2794)
			(end -0.12065 0.3048)
			(stroke
				(width 0.1)
				(type default)
			)
			(layer "F.Fab")
		)
		(fp_line
			(start -0.12065 -0.2794)
			(end 0.12065 -0.2794)
			(stroke
				(width 0.1)
				(type default)
			)
			(layer "F.Fab")
		)
		(fp_line
			(start -0.12065 -0.305054)
			(end -0.12065 -0.2794)
			(stroke
				(width 0.1)
				(type default)
			)
			(layer "F.Fab")
		)
		(fp_line
			(start -0.67945 0.3048)
			(end -0.67945 -0.305054)
			(stroke
				(width 0.1)
				(type default)
			)
			(layer "F.Fab")
		)
		(fp_line
			(start -0.67945 -0.305054)
			(end -0.12065 -0.305054)
			(stroke
				(width 0.1)
				(type default)
			)
			(layer "F.Fab")
		)
		(pad "1" smd circle
			(at -0.40005 0 180)
			(size 0 0)
			(layers "F.Cu" "F.Mask" "F.Paste")
			(net "REV_ID<2>")
		)
		(pad "2" smd circle
			(at 0.40005 0 180)
			(size 0 0)
			(layers "F.Cu" "F.Mask" "F.Paste")
			(net "GND")
		)
	)
	(footprint ""
		(layer "F.Cu")
		(at 33.887664 -3.610864)
		(property "Reference" "U6"
			(at -4.931664 1.732534 0)
			(unlocked yes)
			(layer "F.SilkS")
			(effects
				(font
					(size 0.7874 0.5842)
					(thickness 0.1524)
				)
				(justify left)
			)
		)
		(property "Value" ""
			(at 0 0 0)
			(layer "F.Fab")
			(effects
				(font
					(size 1.27 1.27)
				)
			)
		)
		(duplicate_pad_numbers_are_jumpers no)
		(fp_line
			(start -3.447796 -2.500122)
			(end -3.447796 2.500122)
			(stroke
				(width 0.1524)
				(type default)
			)
			(layer "F.SilkS")
		)
		(fp_line
			(start -3.447796 2.500122)
			(end 3.447796 2.500122)
			(stroke
				(width 0.1524)
				(type default)
			)
			(layer "F.SilkS")
		)
		(fp_line
			(start -1.484122 -2.500122)
			(end -3.447796 -2.500122)
			(stroke
				(width 0.1524)
				(type default)
			)
			(layer "F.SilkS")
		)
		(fp_line
			(start 0 -1.016)
			(end -1.484122 -2.500122)
			(stroke
				(width 0.1524)
				(type default)
			)
			(layer "F.SilkS")
		)
		(fp_line
			(start 1.484122 -2.500122)
			(end 0 -1.016)
			(stroke
				(width 0.1524)
				(type default)
			)
			(layer "F.SilkS")
		)
		(fp_line
			(start 3.447796 -2.500122)
			(end 1.484122 -2.500122)
			(stroke
				(width 0.1524)
				(type default)
			)
			(layer "F.SilkS")
		)
		(fp_line
			(start 3.447796 2.500122)
			(end 3.447796 -2.500122)
			(stroke
				(width 0.1524)
				(type default)
			)
			(layer "F.SilkS")
		)
		(fp_poly
			(pts
				(xy -4.5974 -2.413) (xy -4.5974 -1.397) (xy -3.5814 -1.905)
			)
			(stroke
				(width 0)
				(type default)
			)
			(fill yes)
			(layer "F.SilkS")
		)
		(fp_line
			(start -1.999996 -2.500122)
			(end -1.999996 2.500122)
			(stroke
				(width 0.1)
				(type default)
			)
			(layer "F.Fab")
		)
		(fp_line
			(start -1.999996 2.500122)
			(end 1.999996 2.500122)
			(stroke
				(width 0.1)
				(type default)
			)
			(layer "F.Fab")
		)
		(fp_line
			(start 1.999996 -2.500122)
			(end -1.999996 -2.500122)
			(stroke
				(width 0.1)
				(type default)
			)
			(layer "F.Fab")
		)
		(fp_line
			(start 1.999996 2.500122)
			(end 1.999996 -2.500122)
			(stroke
				(width 0.1)
				(type default)
			)
			(layer "F.Fab")
		)
		(fp_poly
			(pts
				(xy -4.5974 -2.413) (xy -4.5974 -1.397) (xy -3.5814 -1.905)
			)
			(stroke
				(width 0)
				(type default)
			)
			(fill yes)
			(layer "F.Fab")
		)
		(pad "1" smd rect
			(at -2.649982 -1.905 270)
			(size 0.6096 1.3208)
			(layers "F.Cu" "F.Mask" "F.Paste")
			(net "SMB_TMP75_SDA")
		)
		(pad "2" smd rect
			(at -2.649982 -0.635 270)
			(size 0.6096 1.3208)
			(layers "F.Cu" "F.Mask" "F.Paste")
			(net "SMB_TMP75_SCL")
		)
		(pad "3" smd rect
			(at -2.649982 0.635 270)
			(size 0.6096 1.3208)
			(layers "F.Cu" "F.Mask" "F.Paste")
			(net "THERMAL_OS")
		)
		(pad "4" smd rect
			(at -2.649982 1.905 270)
			(size 0.6096 1.3208)
			(layers "F.Cu" "F.Mask" "F.Paste")
			(net "GND")
		)
		(pad "5" smd rect
			(at 2.649982 1.905 270)
			(size 0.6096 1.3208)
			(layers "F.Cu" "F.Mask" "F.Paste")
			(net "THERMAL_ADDR_A2")
		)
		(pad "6" smd rect
			(at 2.649982 0.635 270)
			(size 0.6096 1.3208)
			(layers "F.Cu" "F.Mask" "F.Paste")
			(net "THERMAL_ADDR_A1")
		)
		(pad "7" smd rect
			(at 2.649982 -0.635 270)
			(size 0.6096 1.3208)
			(layers "F.Cu" "F.Mask" "F.Paste")
			(net "THERMAL_ADDR_A0")
		)
		(pad "8" smd rect
			(at 2.649982 -1.905 270)
			(size 0.6096 1.3208)
			(layers "F.Cu" "F.Mask" "F.Paste")
			(net "P3V3_STBY")
		)
	)
	(footprint ""
		(layer "F.Cu")
		(at 19.558 -24.13)
		(property "Reference" "R35"
			(at 0.381 -4.16433 0)
			(unlocked yes)
			(layer "F.SilkS")
			(effects
				(font
					(size 0.7874 0.5842)
					(thickness 0.1524)
				)
			)
		)
		(property "Value" ""
			(at 0 0 0)
			(layer "F.Fab")
			(effects
				(font
					(size 1.27 1.27)
				)
			)
		)
		(duplicate_pad_numbers_are_jumpers no)
		(fp_line
			(start -0.7874 -0.4064)
			(end 0.7874 -0.4064)
			(stroke
				(width 0.1524)
				(type default)
			)
			(layer "F.SilkS")
		)
		(fp_line
			(start -0.7874 0.4064)
			(end -0.7874 -0.4064)
			(stroke
				(width 0.1524)
				(type default)
			)
			(layer "F.SilkS")
		)
		(fp_line
			(start 0.7874 -0.4064)
			(end 0.7874 0.4064)
			(stroke
				(width 0.1524)
				(type default)
			)
			(layer "F.SilkS")
		)
		(fp_line
			(start 0.7874 0.4064)
			(end -0.7874 0.4064)
			(stroke
				(width 0.1524)
				(type default)
			)
			(layer "F.SilkS")
		)
		(fp_line
			(start -0.67945 -0.305054)
			(end -0.12065 -0.305054)
			(stroke
				(width 0.1)
				(type default)
			)
			(layer "F.Fab")
		)
		(fp_line
			(start -0.67945 0.3048)
			(end -0.67945 -0.305054)
			(stroke
				(width 0.1)
				(type default)
			)
			(layer "F.Fab")
		)
		(fp_line
			(start -0.12065 -0.305054)
			(end -0.12065 -0.2794)
			(stroke
				(width 0.1)
				(type default)
			)
			(layer "F.Fab")
		)
		(fp_line
			(start -0.12065 -0.2794)
			(end 0.12065 -0.2794)
			(stroke
				(width 0.1)
				(type default)
			)
			(layer "F.Fab")
		)
		(fp_line
			(start -0.12065 0.2794)
			(end -0.12065 0.3048)
			(stroke
				(width 0.1)
				(type default)
			)
			(layer "F.Fab")
		)
		(fp_line
			(start -0.12065 0.3048)
			(end -0.67945 0.3048)
			(stroke
				(width 0.1)
				(type default)
			)
			(layer "F.Fab")
		)
		(fp_line
			(start 0.120396 0.2794)
			(end -0.12065 0.2794)
			(stroke
				(width 0.1)
				(type default)
			)
			(layer "F.Fab")
		)
		(fp_line
			(start 0.120396 0.3048)
			(end 0.120396 0.2794)
			(stroke
				(width 0.1)
				(type default)
			)
			(layer "F.Fab")
		)
		(fp_line
			(start 0.12065 -0.3048)
			(end 0.67945 -0.3048)
			(stroke
				(width 0.1)
				(type default)
			)
			(layer "F.Fab")
		)
		(fp_line
			(start 0.12065 -0.2794)
			(end 0.12065 -0.3048)
			(stroke
				(width 0.1)
				(type default)
			)
			(layer "F.Fab")
		)
		(fp_line
			(start 0.67945 -0.3048)
			(end 0.67945 0.3048)
			(stroke
				(width 0.1)
				(type default)
			)
			(layer "F.Fab")
		)
		(fp_line
			(start 0.67945 0.3048)
			(end 0.120396 0.3048)
			(stroke
				(width 0.1)
				(type default)
			)
			(layer "F.Fab")
		)
		(pad "1" smd circle
			(at -0.40005 0)
			(size 0 0)
			(layers "F.Cu" "F.Mask" "F.Paste")
			(net "SMB_SDA")
		)
		(pad "2" smd circle
			(at 0.40005 0)
			(size 0 0)
			(layers "F.Cu" "F.Mask" "F.Paste")
			(net "SMB_TMP75_SDA")
		)
	)
	(footprint ""
		(layer "F.Cu")
		(at 36.703 -25.4 180)
		(property "Reference" "R40"
			(at 7.874 0.35433 0)
			(unlocked yes)
			(layer "F.SilkS")
			(effects
				(font
					(size 0.7874 0.5842)
					(thickness 0.1524)
				)
			)
		)
		(property "Value" ""
			(at 0 0 180)
			(layer "F.Fab")
			(effects
				(font
					(size 1.27 1.27)
				)
			)
		)
		(duplicate_pad_numbers_are_jumpers no)
		(fp_line
			(start 0.7874 0.4064)
			(end -0.7874 0.4064)
			(stroke
				(width 0.1524)
				(type default)
			)
			(layer "F.SilkS")
		)
		(fp_line
			(start 0.7874 -0.4064)
			(end 0.7874 0.4064)
			(stroke
				(width 0.1524)
				(type default)
			)
			(layer "F.SilkS")
		)
		(fp_line
			(start -0.7874 0.4064)
			(end -0.7874 -0.4064)
			(stroke
				(width 0.1524)
				(type default)
			)
			(layer "F.SilkS")
		)
		(fp_line
			(start -0.7874 -0.4064)
			(end 0.7874 -0.4064)
			(stroke
				(width 0.1524)
				(type default)
			)
			(layer "F.SilkS")
		)
		(fp_line
			(start 0.67945 0.3048)
			(end 0.120396 0.3048)
			(stroke
				(width 0.1)
				(type default)
			)
			(layer "F.Fab")
		)
		(fp_line
			(start 0.67945 -0.3048)
			(end 0.67945 0.3048)
			(stroke
				(width 0.1)
				(type default)
			)
			(layer "F.Fab")
		)
		(fp_line
			(start 0.12065 -0.2794)
			(end 0.12065 -0.3048)
			(stroke
				(width 0.1)
				(type default)
			)
			(layer "F.Fab")
		)
		(fp_line
			(start 0.12065 -0.3048)
			(end 0.67945 -0.3048)
			(stroke
				(width 0.1)
				(type default)
			)
			(layer "F.Fab")
		)
		(fp_line
			(start 0.120396 0.3048)
			(end 0.120396 0.2794)
			(stroke
				(width 0.1)
				(type default)
			)
			(layer "F.Fab")
		)
		(fp_line
			(start 0.120396 0.2794)
			(end -0.12065 0.2794)
			(stroke
				(width 0.1)
				(type default)
			)
			(layer "F.Fab")
		)
		(fp_line
			(start -0.12065 0.3048)
			(end -0.67945 0.3048)
			(stroke
				(width 0.1)
				(type default)
			)
			(layer "F.Fab")
		)
		(fp_line
			(start -0.12065 0.2794)
			(end -0.12065 0.3048)
			(stroke
				(width 0.1)
				(type default)
			)
			(layer "F.Fab")
		)
		(fp_line
			(start -0.12065 -0.2794)
			(end 0.12065 -0.2794)
			(stroke
				(width 0.1)
				(type default)
			)
			(layer "F.Fab")
		)
		(fp_line
			(start -0.12065 -0.305054)
			(end -0.12065 -0.2794)
			(stroke
				(width 0.1)
				(type default)
			)
			(layer "F.Fab")
		)
		(fp_line
			(start -0.67945 0.3048)
			(end -0.67945 -0.305054)
			(stroke
				(width 0.1)
				(type default)
			)
			(layer "F.Fab")
		)
		(fp_line
			(start -0.67945 -0.305054)
			(end -0.12065 -0.305054)
			(stroke
				(width 0.1)
				(type default)
			)
			(layer "F.Fab")
		)
		(pad "1" smd circle
			(at -0.40005 0 180)
			(size 0 0)
			(layers "F.Cu" "F.Mask" "F.Paste")
			(net "P3V3_STBY")
		)
		(pad "2" smd circle
			(at 0.40005 0 180)
			(size 0 0)
			(layers "F.Cu" "F.Mask" "F.Paste")
			(net "NCO380_EN")
		)
	)
	(footprint ""
		(layer "F.Cu")
		(at 15.113 -25.146 -90)
		(property "Reference" "R45"
			(at -2.159 -0.02667 90)
			(unlocked yes)
			(layer "F.SilkS")
			(effects
				(font
					(size 0.7874 0.5842)
					(thickness 0.1524)
				)
			)
		)
		(property "Value" ""
			(at 0 0 270)
			(layer "F.Fab")
			(effects
				(font
					(size 1.27 1.27)
				)
			)
		)
		(duplicate_pad_numbers_are_jumpers no)
		(fp_line
			(start -0.7874 0.4064)
			(end -0.7874 -0.4064)
			(stroke
				(width 0.1524)
				(type default)
			)
			(layer "F.SilkS")
		)
		(fp_line
			(start 0.7874 0.4064)
			(end -0.7874 0.4064)
			(stroke
				(width 0.1524)
				(type default)
			)
			(layer "F.SilkS")
		)
		(fp_line
			(start -0.7874 -0.4064)
			(end 0.7874 -0.4064)
			(stroke
				(width 0.1524)
				(type default)
			)
			(layer "F.SilkS")
		)
		(fp_line
			(start 0.7874 -0.4064)
			(end 0.7874 0.4064)
			(stroke
				(width 0.1524)
				(type default)
			)
			(layer "F.SilkS")
		)
		(fp_line
			(start -0.67945 0.3048)
			(end -0.67945 -0.305054)
			(stroke
				(width 0.1)
				(type default)
			)
			(layer "F.Fab")
		)
		(fp_line
			(start -0.12065 0.3048)
			(end -0.67945 0.3048)
			(stroke
				(width 0.1)
				(type default)
			)
			(layer "F.Fab")
		)
		(fp_line
			(start 0.120396 0.3048)
			(end 0.120396 0.2794)
			(stroke
				(width 0.1)
				(type default)
			)
			(layer "F.Fab")
		)
		(fp_line
			(start 0.67945 0.3048)
			(end 0.120396 0.3048)
			(stroke
				(width 0.1)
				(type default)
			)
			(layer "F.Fab")
		)
		(fp_line
			(start -0.12065 0.2794)
			(end -0.12065 0.3048)
			(stroke
				(width 0.1)
				(type default)
			)
			(layer "F.Fab")
		)
		(fp_line
			(start 0.120396 0.2794)
			(end -0.12065 0.2794)
			(stroke
				(width 0.1)
				(type default)
			)
			(layer "F.Fab")
		)
		(fp_line
			(start -0.12065 -0.2794)
			(end 0.12065 -0.2794)
			(stroke
				(width 0.1)
				(type default)
			)
			(layer "F.Fab")
		)
		(fp_line
			(start 0.12065 -0.2794)
			(end 0.12065 -0.3048)
			(stroke
				(width 0.1)
				(type default)
			)
			(layer "F.Fab")
		)
		(fp_line
			(start 0.12065 -0.3048)
			(end 0.67945 -0.3048)
			(stroke
				(width 0.1)
				(type default)
			)
			(layer "F.Fab")
		)
		(fp_line
			(start 0.67945 -0.3048)
			(end 0.67945 0.3048)
			(stroke
				(width 0.1)
				(type default)
			)
			(layer "F.Fab")
		)
		(fp_line
			(start -0.67945 -0.305054)
			(end -0.12065 -0.305054)
			(stroke
				(width 0.1)
				(type default)
			)
			(layer "F.Fab")
		)
		(fp_line
			(start -0.12065 -0.305054)
			(end -0.12065 -0.2794)
			(stroke
				(width 0.1)
				(type default)
			)
			(layer "F.Fab")
		)
		(pad "1" smd circle
			(at -0.40005 0 270)
			(size 0 0)
			(layers "F.Cu" "F.Mask" "F.Paste")
			(net "P3V3_STBY")
		)
		(pad "2" smd circle
			(at 0.40005 0 270)
			(size 0 0)
			(layers "F.Cu" "F.Mask" "F.Paste")
			(net "PRSNT_DBV2_SLIMSAS")
		)
	)
	(footprint ""
		(layer "F.Cu")
		(at 15.621 -67.437 180)
		(property "Reference" "C4"
			(at 2.159 -0.02667 0)
			(unlocked yes)
			(layer "F.SilkS")
			(effects
				(font
					(size 0.7874 0.5842)
					(thickness 0.1524)
				)
			)
		)
		(property "Value" ""
			(at 0 0 180)
			(layer "F.Fab")
			(effects
				(font
					(size 1.27 1.27)
				)
			)
		)
		(duplicate_pad_numbers_are_jumpers no)
		(fp_line
			(start 0.7874 0.4064)
			(end -0.7874 0.4064)
			(stroke
				(width 0.1524)
				(type default)
			)
			(layer "F.SilkS")
		)
		(fp_line
			(start 0.7874 -0.4064)
			(end 0.7874 0.4064)
			(stroke
				(width 0.1524)
				(type default)
			)
			(layer "F.SilkS")
		)
		(fp_line
			(start -0.7874 0.4064)
			(end -0.7874 -0.4064)
			(stroke
				(width 0.1524)
				(type default)
			)
			(layer "F.SilkS")
		)
		(fp_line
			(start -0.7874 -0.4064)
			(end 0.7874 -0.4064)
			(stroke
				(width 0.1524)
				(type default)
			)
			(layer "F.SilkS")
		)
		(fp_line
			(start 0.67945 0.3048)
			(end 0.120396 0.3048)
			(stroke
				(width 0.1)
				(type default)
			)
			(layer "F.Fab")
		)
		(fp_line
			(start 0.67945 -0.3048)
			(end 0.67945 0.3048)
			(stroke
				(width 0.1)
				(type default)
			)
			(layer "F.Fab")
		)
		(fp_line
			(start 0.12065 -0.2794)
			(end 0.12065 -0.3048)
			(stroke
				(width 0.1)
				(type default)
			)
			(layer "F.Fab")
		)
		(fp_line
			(start 0.12065 -0.3048)
			(end 0.67945 -0.3048)
			(stroke
				(width 0.1)
				(type default)
			)
			(layer "F.Fab")
		)
		(fp_line
			(start 0.120396 0.3048)
			(end 0.120396 0.2794)
			(stroke
				(width 0.1)
				(type default)
			)
			(layer "F.Fab")
		)
		(fp_line
			(start 0.120396 0.2794)
			(end -0.12065 0.2794)
			(stroke
				(width 0.1)
				(type default)
			)
			(layer "F.Fab")
		)
		(fp_line
			(start -0.12065 0.3048)
			(end -0.67945 0.3048)
			(stroke
				(width 0.1)
				(type default)
			)
			(layer "F.Fab")
		)
		(fp_line
			(start -0.12065 0.2794)
			(end -0.12065 0.3048)
			(stroke
				(width 0.1)
				(type default)
			)
			(layer "F.Fab")
		)
		(fp_line
			(start -0.12065 -0.2794)
			(end 0.12065 -0.2794)
			(stroke
				(width 0.1)
				(type default)
			)
			(layer "F.Fab")
		)
		(fp_line
			(start -0.12065 -0.305054)
			(end -0.12065 -0.2794)
			(stroke
				(width 0.1)
				(type default)
			)
			(layer "F.Fab")
		)
		(fp_line
			(start -0.67945 0.3048)
			(end -0.67945 -0.305054)
			(stroke
				(width 0.1)
				(type default)
			)
			(layer "F.Fab")
		)
		(fp_line
			(start -0.67945 -0.305054)
			(end -0.12065 -0.305054)
			(stroke
				(width 0.1)
				(type default)
			)
			(layer "F.Fab")
		)
		(pad "1" smd circle
			(at -0.40005 0 180)
			(size 0 0)
			(layers "F.Cu" "F.Mask" "F.Paste")
			(net "P5V_STBY")
		)
		(pad "2" smd circle
			(at 0.40005 0 180)
			(size 0 0)
			(layers "F.Cu" "F.Mask" "F.Paste")
			(net "GND")
		)
	)
	(footprint ""
		(layer "F.Cu")
		(at 18.415 -56.769)
		(property "Reference" "R15"
			(at 3.81 0.02667 0)
			(unlocked yes)
			(layer "F.SilkS")
			(effects
				(font
					(size 0.7874 0.5842)
					(thickness 0.1524)
				)
			)
		)
		(property "Value" ""
			(at 0 0 0)
			(layer "F.Fab")
			(effects
				(font
					(size 1.27 1.27)
				)
			)
		)
		(duplicate_pad_numbers_are_jumpers no)
		(fp_line
			(start -0.7874 -0.4064)
			(end 0.7874 -0.4064)
			(stroke
				(width 0.1524)
				(type default)
			)
			(layer "F.SilkS")
		)
		(fp_line
			(start -0.7874 0.4064)
			(end -0.7874 -0.4064)
			(stroke
				(width 0.1524)
				(type default)
			)
			(layer "F.SilkS")
		)
		(fp_line
			(start 0.7874 -0.4064)
			(end 0.7874 0.4064)
			(stroke
				(width 0.1524)
				(type default)
			)
			(layer "F.SilkS")
		)
		(fp_line
			(start 0.7874 0.4064)
			(end -0.7874 0.4064)
			(stroke
				(width 0.1524)
				(type default)
			)
			(layer "F.SilkS")
		)
		(fp_line
			(start -0.67945 -0.305054)
			(end -0.12065 -0.305054)
			(stroke
				(width 0.1)
				(type default)
			)
			(layer "F.Fab")
		)
		(fp_line
			(start -0.67945 0.3048)
			(end -0.67945 -0.305054)
			(stroke
				(width 0.1)
				(type default)
			)
			(layer "F.Fab")
		)
		(fp_line
			(start -0.12065 -0.305054)
			(end -0.12065 -0.2794)
			(stroke
				(width 0.1)
				(type default)
			)
			(layer "F.Fab")
		)
		(fp_line
			(start -0.12065 -0.2794)
			(end 0.12065 -0.2794)
			(stroke
				(width 0.1)
				(type default)
			)
			(layer "F.Fab")
		)
		(fp_line
			(start -0.12065 0.2794)
			(end -0.12065 0.3048)
			(stroke
				(width 0.1)
				(type default)
			)
			(layer "F.Fab")
		)
		(fp_line
			(start -0.12065 0.3048)
			(end -0.67945 0.3048)
			(stroke
				(width 0.1)
				(type default)
			)
			(layer "F.Fab")
		)
		(fp_line
			(start 0.120396 0.2794)
			(end -0.12065 0.2794)
			(stroke
				(width 0.1)
				(type default)
			)
			(layer "F.Fab")
		)
		(fp_line
			(start 0.120396 0.3048)
			(end 0.120396 0.2794)
			(stroke
				(width 0.1)
				(type default)
			)
			(layer "F.Fab")
		)
		(fp_line
			(start 0.12065 -0.3048)
			(end 0.67945 -0.3048)
			(stroke
				(width 0.1)
				(type default)
			)
			(layer "F.Fab")
		)
		(fp_line
			(start 0.12065 -0.2794)
			(end 0.12065 -0.3048)
			(stroke
				(width 0.1)
				(type default)
			)
			(layer "F.Fab")
		)
		(fp_line
			(start 0.67945 -0.3048)
			(end 0.67945 0.3048)
			(stroke
				(width 0.1)
				(type default)
			)
			(layer "F.Fab")
		)
		(fp_line
			(start 0.67945 0.3048)
			(end 0.120396 0.3048)
			(stroke
				(width 0.1)
				(type default)
			)
			(layer "F.Fab")
		)
		(pad "1" smd circle
			(at -0.40005 0)
			(size 0 0)
			(layers "F.Cu" "F.Mask" "F.Paste")
			(net "PWR_LED")
		)
		(pad "2" smd circle
			(at 0.40005 0)
			(size 0 0)
			(layers "F.Cu" "F.Mask" "F.Paste")
			(net "PWR_LED_R1")
		)
	)
	(footprint ""
		(layer "F.Cu")
		(at 19.558 -25.146)
		(property "Reference" "R31"
			(at 0.381 -4.16433 0)
			(unlocked yes)
			(layer "F.SilkS")
			(effects
				(font
					(size 0.7874 0.5842)
					(thickness 0.1524)
				)
			)
		)
		(property "Value" ""
			(at 0 0 0)
			(layer "F.Fab")
			(effects
				(font
					(size 1.27 1.27)
				)
			)
		)
		(duplicate_pad_numbers_are_jumpers no)
		(fp_line
			(start -0.7874 -0.4064)
			(end 0.7874 -0.4064)
			(stroke
				(width 0.1524)
				(type default)
			)
			(layer "F.SilkS")
		)
		(fp_line
			(start -0.7874 0.4064)
			(end -0.7874 -0.4064)
			(stroke
				(width 0.1524)
				(type default)
			)
			(layer "F.SilkS")
		)
		(fp_line
			(start 0.7874 -0.4064)
			(end 0.7874 0.4064)
			(stroke
				(width 0.1524)
				(type default)
			)
			(layer "F.SilkS")
		)
		(fp_line
			(start 0.7874 0.4064)
			(end -0.7874 0.4064)
			(stroke
				(width 0.1524)
				(type default)
			)
			(layer "F.SilkS")
		)
		(fp_line
			(start -0.67945 -0.305054)
			(end -0.12065 -0.305054)
			(stroke
				(width 0.1)
				(type default)
			)
			(layer "F.Fab")
		)
		(fp_line
			(start -0.67945 0.3048)
			(end -0.67945 -0.305054)
			(stroke
				(width 0.1)
				(type default)
			)
			(layer "F.Fab")
		)
		(fp_line
			(start -0.12065 -0.305054)
			(end -0.12065 -0.2794)
			(stroke
				(width 0.1)
				(type default)
			)
			(layer "F.Fab")
		)
		(fp_line
			(start -0.12065 -0.2794)
			(end 0.12065 -0.2794)
			(stroke
				(width 0.1)
				(type default)
			)
			(layer "F.Fab")
		)
		(fp_line
			(start -0.12065 0.2794)
			(end -0.12065 0.3048)
			(stroke
				(width 0.1)
				(type default)
			)
			(layer "F.Fab")
		)
		(fp_line
			(start -0.12065 0.3048)
			(end -0.67945 0.3048)
			(stroke
				(width 0.1)
				(type default)
			)
			(layer "F.Fab")
		)
		(fp_line
			(start 0.120396 0.2794)
			(end -0.12065 0.2794)
			(stroke
				(width 0.1)
				(type default)
			)
			(layer "F.Fab")
		)
		(fp_line
			(start 0.120396 0.3048)
			(end 0.120396 0.2794)
			(stroke
				(width 0.1)
				(type default)
			)
			(layer "F.Fab")
		)
		(fp_line
			(start 0.12065 -0.3048)
			(end 0.67945 -0.3048)
			(stroke
				(width 0.1)
				(type default)
			)
			(layer "F.Fab")
		)
		(fp_line
			(start 0.12065 -0.2794)
			(end 0.12065 -0.3048)
			(stroke
				(width 0.1)
				(type default)
			)
			(layer "F.Fab")
		)
		(fp_line
			(start 0.67945 -0.3048)
			(end 0.67945 0.3048)
			(stroke
				(width 0.1)
				(type default)
			)
			(layer "F.Fab")
		)
		(fp_line
			(start 0.67945 0.3048)
			(end 0.120396 0.3048)
			(stroke
				(width 0.1)
				(type default)
			)
			(layer "F.Fab")
		)
		(pad "1" smd circle
			(at -0.40005 0)
			(size 0 0)
			(layers "F.Cu" "F.Mask" "F.Paste")
			(net "P3V3_STBY")
		)
		(pad "2" smd circle
			(at 0.40005 0)
			(size 0 0)
			(layers "F.Cu" "F.Mask" "F.Paste")
			(net "SMB_TMP75_SDA")
		)
	)
	(footprint ""
		(layer "F.Cu")
		(at 6.599936 -70.980046 180)
		(property "Reference" "H12"
			(at -3.052064 7.098284 0)
			(unlocked yes)
			(layer "F.SilkS")
			(effects
				(font
					(size 0.7874 0.5842)
					(thickness 0.1524)
				)
				(justify left)
			)
		)
		(property "Value" ""
			(at 0 0 180)
			(layer "F.Fab")
			(effects
				(font
					(size 1.27 1.27)
				)
			)
		)
		(duplicate_pad_numbers_are_jumpers no)
		(fp_line
			(start 4.126992 0)
			(end 4.126992 3.50012)
			(stroke
				(width 0.1524)
				(type default)
			)
			(layer "F.SilkS")
		)
		(fp_line
			(start -4.126992 3.50012)
			(end -4.126992 0)
			(stroke
				(width 0.1524)
				(type default)
			)
			(layer "F.SilkS")
		)
		(fp_arc
			(start 4.126992 3.50012)
			(mid 0 7.627112)
			(end -4.126992 3.50012)
			(stroke
				(width 0.1524)
				(type default)
			)
			(layer "F.SilkS")
		)
		(fp_arc
			(start -4.126992 0)
			(mid 0 -4.126992)
			(end 4.126992 0)
			(stroke
				(width 0.1524)
				(type default)
			)
			(layer "F.SilkS")
		)
		(fp_line
			(start 4.126992 0)
			(end 4.126992 3.50012)
			(stroke
				(width 0.1524)
				(type default)
			)
			(layer "B.SilkS")
		)
		(fp_line
			(start -4.126992 3.50012)
			(end -4.126992 0)
			(stroke
				(width 0.1524)
				(type default)
			)
			(layer "B.SilkS")
		)
		(fp_arc
			(start 4.126992 3.50012)
			(mid 0 7.627112)
			(end -4.126992 3.50012)
			(stroke
				(width 0.1524)
				(type default)
			)
			(layer "B.SilkS")
		)
		(fp_arc
			(start -4.126992 0)
			(mid 0 -4.126992)
			(end 4.126992 0)
			(stroke
				(width 0.1524)
				(type default)
			)
			(layer "B.SilkS")
		)
		(fp_line
			(start 4.126992 0)
			(end 4.126992 3.50012)
			(stroke
				(width 0.1)
				(type default)
			)
			(layer "B.Fab")
		)
		(fp_line
			(start -4.126992 3.50012)
			(end -4.126992 0)
			(stroke
				(width 0.1)
				(type default)
			)
			(layer "B.Fab")
		)
		(fp_arc
			(start 4.126992 3.50012)
			(mid 0 7.627112)
			(end -4.126992 3.50012)
			(stroke
				(width 0.1)
				(type default)
			)
			(layer "B.Fab")
		)
		(fp_arc
			(start -4.126992 0)
			(mid 0 -4.126992)
			(end 4.126992 0)
			(stroke
				(width 0.1)
				(type default)
			)
			(layer "B.Fab")
		)
		(fp_line
			(start 4.126992 0)
			(end 4.126992 3.50012)
			(stroke
				(width 0.1)
				(type default)
			)
			(layer "F.Fab")
		)
		(fp_line
			(start -4.126992 3.50012)
			(end -4.126992 0)
			(stroke
				(width 0.1)
				(type default)
			)
			(layer "F.Fab")
		)
		(fp_arc
			(start 4.126992 3.50012)
			(mid 0 7.627112)
			(end -4.126992 3.50012)
			(stroke
				(width 0.1)
				(type default)
			)
			(layer "F.Fab")
		)
		(fp_arc
			(start -4.126992 0)
			(mid 0 -4.126992)
			(end 4.126992 0)
			(stroke
				(width 0.1)
				(type default)
			)
			(layer "F.Fab")
		)
		(pad "" np_thru_hole circle
			(at 0 0 180)
			(size 3.0226 3.0226)
			(drill 3.0226)
			(layers "*.Cu" "*.Mask")
			(clearance 0.381)
			(thermal_gap 0.381)
		)
		(zone
			(layers "F.Cu" "B.Cu" "In1.Cu" "In2.Cu")
			(hatch none 0.5)
			(connect_pads
				(clearance 0)
			)
			(min_thickness 0.25)
			(keepout
				(tracks not_allowed)
				(vias allowed)
				(pads allowed)
				(copperpour not_allowed)
				(footprints allowed)
			)
			(placement
				(enabled no)
				(sheetname "")
			)
			(fill
				(thermal_gap 0.5)
				(thermal_bridge_width 0.5)
				(island_removal_mode 0)
			)
			(polygon
				(pts
					(arc
						(start 4.260342 -72.58939)
						(mid 6.599936 -77.487864)
						(end 8.93953 -72.58939)
					)
					(arc
						(start 8.93953 -72.58939)
						(mid 8.693357 -72.148942)
						(end 8.60806 -71.651622)
					)
					(arc
						(start 8.60806 -70.980046)
						(mid 6.599936 -68.971922)
						(end 4.591812 -70.980046)
					)
					(arc
						(start 4.591812 -71.651622)
						(mid 4.506506 -72.148935)
						(end 4.260342 -72.58939)
					)
				)
			)
		)
	)
	(footprint ""
		(layer "F.Cu")
		(at 5.969 -62.357 180)
		(property "Reference" "R24"
			(at 2.667 -0.40767 0)
			(unlocked yes)
			(layer "F.SilkS")
			(effects
				(font
					(size 0.7874 0.5842)
					(thickness 0.1524)
				)
			)
		)
		(property "Value" ""
			(at 0 0 180)
			(layer "F.Fab")
			(effects
				(font
					(size 1.27 1.27)
				)
			)
		)
		(duplicate_pad_numbers_are_jumpers no)
		(fp_line
			(start 0.7874 0.4064)
			(end -0.7874 0.4064)
			(stroke
				(width 0.1524)
				(type default)
			)
			(layer "F.SilkS")
		)
		(fp_line
			(start 0.7874 -0.4064)
			(end 0.7874 0.4064)
			(stroke
				(width 0.1524)
				(type default)
			)
			(layer "F.SilkS")
		)
		(fp_line
			(start -0.7874 0.4064)
			(end -0.7874 -0.4064)
			(stroke
				(width 0.1524)
				(type default)
			)
			(layer "F.SilkS")
		)
		(fp_line
			(start -0.7874 -0.4064)
			(end 0.7874 -0.4064)
			(stroke
				(width 0.1524)
				(type default)
			)
			(layer "F.SilkS")
		)
		(fp_line
			(start 0.67945 0.3048)
			(end 0.120396 0.3048)
			(stroke
				(width 0.1)
				(type default)
			)
			(layer "F.Fab")
		)
		(fp_line
			(start 0.67945 -0.3048)
			(end 0.67945 0.3048)
			(stroke
				(width 0.1)
				(type default)
			)
			(layer "F.Fab")
		)
		(fp_line
			(start 0.12065 -0.2794)
			(end 0.12065 -0.3048)
			(stroke
				(width 0.1)
				(type default)
			)
			(layer "F.Fab")
		)
		(fp_line
			(start 0.12065 -0.3048)
			(end 0.67945 -0.3048)
			(stroke
				(width 0.1)
				(type default)
			)
			(layer "F.Fab")
		)
		(fp_line
			(start 0.120396 0.3048)
			(end 0.120396 0.2794)
			(stroke
				(width 0.1)
				(type default)
			)
			(layer "F.Fab")
		)
		(fp_line
			(start 0.120396 0.2794)
			(end -0.12065 0.2794)
			(stroke
				(width 0.1)
				(type default)
			)
			(layer "F.Fab")
		)
		(fp_line
			(start -0.12065 0.3048)
			(end -0.67945 0.3048)
			(stroke
				(width 0.1)
				(type default)
			)
			(layer "F.Fab")
		)
		(fp_line
			(start -0.12065 0.2794)
			(end -0.12065 0.3048)
			(stroke
				(width 0.1)
				(type default)
			)
			(layer "F.Fab")
		)
		(fp_line
			(start -0.12065 -0.2794)
			(end 0.12065 -0.2794)
			(stroke
				(width 0.1)
				(type default)
			)
			(layer "F.Fab")
		)
		(fp_line
			(start -0.12065 -0.305054)
			(end -0.12065 -0.2794)
			(stroke
				(width 0.1)
				(type default)
			)
			(layer "F.Fab")
		)
		(fp_line
			(start -0.67945 0.3048)
			(end -0.67945 -0.305054)
			(stroke
				(width 0.1)
				(type default)
			)
			(layer "F.Fab")
		)
		(fp_line
			(start -0.67945 -0.305054)
			(end -0.12065 -0.305054)
			(stroke
				(width 0.1)
				(type default)
			)
			(layer "F.Fab")
		)
		(pad "1" smd circle
			(at -0.40005 0 180)
			(size 0 0)
			(layers "F.Cu" "F.Mask" "F.Paste")
			(net "PCA9539_A1")
		)
		(pad "2" smd circle
			(at 0.40005 0 180)
			(size 0 0)
			(layers "F.Cu" "F.Mask" "F.Paste")
			(net "GND")
		)
	)
	(footprint ""
		(layer "F.Cu")
		(at 3.937 -51.816)
		(property "Reference" "R58"
			(at -2.413 0.15367 0)
			(unlocked yes)
			(layer "F.SilkS")
			(effects
				(font
					(size 0.7874 0.5842)
					(thickness 0.1524)
				)
			)
		)
		(property "Value" ""
			(at 0 0 0)
			(layer "F.Fab")
			(effects
				(font
					(size 1.27 1.27)
				)
			)
		)
		(duplicate_pad_numbers_are_jumpers no)
		(fp_line
			(start -0.7874 -0.4064)
			(end 0.7874 -0.4064)
			(stroke
				(width 0.1524)
				(type default)
			)
			(layer "F.SilkS")
		)
		(fp_line
			(start -0.7874 0.4064)
			(end -0.7874 -0.4064)
			(stroke
				(width 0.1524)
				(type default)
			)
			(layer "F.SilkS")
		)
		(fp_line
			(start 0.7874 -0.4064)
			(end 0.7874 0.4064)
			(stroke
				(width 0.1524)
				(type default)
			)
			(layer "F.SilkS")
		)
		(fp_line
			(start 0.7874 0.4064)
			(end -0.7874 0.4064)
			(stroke
				(width 0.1524)
				(type default)
			)
			(layer "F.SilkS")
		)
		(fp_line
			(start -0.67945 -0.305054)
			(end -0.12065 -0.305054)
			(stroke
				(width 0.1)
				(type default)
			)
			(layer "F.Fab")
		)
		(fp_line
			(start -0.67945 0.3048)
			(end -0.67945 -0.305054)
			(stroke
				(width 0.1)
				(type default)
			)
			(layer "F.Fab")
		)
		(fp_line
			(start -0.12065 -0.305054)
			(end -0.12065 -0.2794)
			(stroke
				(width 0.1)
				(type default)
			)
			(layer "F.Fab")
		)
		(fp_line
			(start -0.12065 -0.2794)
			(end 0.12065 -0.2794)
			(stroke
				(width 0.1)
				(type default)
			)
			(layer "F.Fab")
		)
		(fp_line
			(start -0.12065 0.2794)
			(end -0.12065 0.3048)
			(stroke
				(width 0.1)
				(type default)
			)
			(layer "F.Fab")
		)
		(fp_line
			(start -0.12065 0.3048)
			(end -0.67945 0.3048)
			(stroke
				(width 0.1)
				(type default)
			)
			(layer "F.Fab")
		)
		(fp_line
			(start 0.120396 0.2794)
			(end -0.12065 0.2794)
			(stroke
				(width 0.1)
				(type default)
			)
			(layer "F.Fab")
		)
		(fp_line
			(start 0.120396 0.3048)
			(end 0.120396 0.2794)
			(stroke
				(width 0.1)
				(type default)
			)
			(layer "F.Fab")
		)
		(fp_line
			(start 0.12065 -0.3048)
			(end 0.67945 -0.3048)
			(stroke
				(width 0.1)
				(type default)
			)
			(layer "F.Fab")
		)
		(fp_line
			(start 0.12065 -0.2794)
			(end 0.12065 -0.3048)
			(stroke
				(width 0.1)
				(type default)
			)
			(layer "F.Fab")
		)
		(fp_line
			(start 0.67945 -0.3048)
			(end 0.67945 0.3048)
			(stroke
				(width 0.1)
				(type default)
			)
			(layer "F.Fab")
		)
		(fp_line
			(start 0.67945 0.3048)
			(end 0.120396 0.3048)
			(stroke
				(width 0.1)
				(type default)
			)
			(layer "F.Fab")
		)
		(pad "1" smd circle
			(at -0.40005 0)
			(size 0 0)
			(layers "F.Cu" "F.Mask" "F.Paste")
			(net "P3V3_STBY")
		)
		(pad "2" smd circle
			(at 0.40005 0)
			(size 0 0)
			(layers "F.Cu" "F.Mask" "F.Paste")
			(net "PD_FRU_A0")
		)
	)
	(footprint ""
		(layer "F.Cu")
		(at 13.462 -21.209)
		(property "Reference" "R43"
			(at 0.635 1.42367 0)
			(unlocked yes)
			(layer "F.SilkS")
			(effects
				(font
					(size 0.7874 0.5842)
					(thickness 0.1524)
				)
			)
		)
		(property "Value" ""
			(at 0 0 0)
			(layer "F.Fab")
			(effects
				(font
					(size 1.27 1.27)
				)
			)
		)
		(duplicate_pad_numbers_are_jumpers no)
		(fp_line
			(start -0.7874 -0.4064)
			(end 0.7874 -0.4064)
			(stroke
				(width 0.1524)
				(type default)
			)
			(layer "F.SilkS")
		)
		(fp_line
			(start -0.7874 0.4064)
			(end -0.7874 -0.4064)
			(stroke
				(width 0.1524)
				(type default)
			)
			(layer "F.SilkS")
		)
		(fp_line
			(start 0.7874 -0.4064)
			(end 0.7874 0.4064)
			(stroke
				(width 0.1524)
				(type default)
			)
			(layer "F.SilkS")
		)
		(fp_line
			(start 0.7874 0.4064)
			(end -0.7874 0.4064)
			(stroke
				(width 0.1524)
				(type default)
			)
			(layer "F.SilkS")
		)
		(fp_line
			(start -0.67945 -0.305054)
			(end -0.12065 -0.305054)
			(stroke
				(width 0.1)
				(type default)
			)
			(layer "F.Fab")
		)
		(fp_line
			(start -0.67945 0.3048)
			(end -0.67945 -0.305054)
			(stroke
				(width 0.1)
				(type default)
			)
			(layer "F.Fab")
		)
		(fp_line
			(start -0.12065 -0.305054)
			(end -0.12065 -0.2794)
			(stroke
				(width 0.1)
				(type default)
			)
			(layer "F.Fab")
		)
		(fp_line
			(start -0.12065 -0.2794)
			(end 0.12065 -0.2794)
			(stroke
				(width 0.1)
				(type default)
			)
			(layer "F.Fab")
		)
		(fp_line
			(start -0.12065 0.2794)
			(end -0.12065 0.3048)
			(stroke
				(width 0.1)
				(type default)
			)
			(layer "F.Fab")
		)
		(fp_line
			(start -0.12065 0.3048)
			(end -0.67945 0.3048)
			(stroke
				(width 0.1)
				(type default)
			)
			(layer "F.Fab")
		)
		(fp_line
			(start 0.120396 0.2794)
			(end -0.12065 0.2794)
			(stroke
				(width 0.1)
				(type default)
			)
			(layer "F.Fab")
		)
		(fp_line
			(start 0.120396 0.3048)
			(end 0.120396 0.2794)
			(stroke
				(width 0.1)
				(type default)
			)
			(layer "F.Fab")
		)
		(fp_line
			(start 0.12065 -0.3048)
			(end 0.67945 -0.3048)
			(stroke
				(width 0.1)
				(type default)
			)
			(layer "F.Fab")
		)
		(fp_line
			(start 0.12065 -0.2794)
			(end 0.12065 -0.3048)
			(stroke
				(width 0.1)
				(type default)
			)
			(layer "F.Fab")
		)
		(fp_line
			(start 0.67945 -0.3048)
			(end 0.67945 0.3048)
			(stroke
				(width 0.1)
				(type default)
			)
			(layer "F.Fab")
		)
		(fp_line
			(start 0.67945 0.3048)
			(end 0.120396 0.3048)
			(stroke
				(width 0.1)
				(type default)
			)
			(layer "F.Fab")
		)
		(pad "1" smd circle
			(at -0.40005 0)
			(size 0 0)
			(layers "F.Cu" "F.Mask" "F.Paste")
			(net "P5V_STBY")
		)
		(pad "2" smd circle
			(at 0.40005 0)
			(size 0 0)
			(layers "F.Cu" "F.Mask" "F.Paste")
			(net "PRSNT_DBV2_USB")
		)
	)
	(footprint ""
		(layer "F.Cu")
		(at 5.969 -57.277)
		(property "Reference" "R23"
			(at -2.794 0.40767 0)
			(unlocked yes)
			(layer "F.SilkS")
			(effects
				(font
					(size 0.7874 0.5842)
					(thickness 0.1524)
				)
			)
		)
		(property "Value" ""
			(at 0 0 0)
			(layer "F.Fab")
			(effects
				(font
					(size 1.27 1.27)
				)
			)
		)
		(duplicate_pad_numbers_are_jumpers no)
		(fp_line
			(start -0.7874 -0.4064)
			(end 0.7874 -0.4064)
			(stroke
				(width 0.1524)
				(type default)
			)
			(layer "F.SilkS")
		)
		(fp_line
			(start -0.7874 0.4064)
			(end -0.7874 -0.4064)
			(stroke
				(width 0.1524)
				(type default)
			)
			(layer "F.SilkS")
		)
		(fp_line
			(start 0.7874 -0.4064)
			(end 0.7874 0.4064)
			(stroke
				(width 0.1524)
				(type default)
			)
			(layer "F.SilkS")
		)
		(fp_line
			(start 0.7874 0.4064)
			(end -0.7874 0.4064)
			(stroke
				(width 0.1524)
				(type default)
			)
			(layer "F.SilkS")
		)
		(fp_line
			(start -0.67945 -0.305054)
			(end -0.12065 -0.305054)
			(stroke
				(width 0.1)
				(type default)
			)
			(layer "F.Fab")
		)
		(fp_line
			(start -0.67945 0.3048)
			(end -0.67945 -0.305054)
			(stroke
				(width 0.1)
				(type default)
			)
			(layer "F.Fab")
		)
		(fp_line
			(start -0.12065 -0.305054)
			(end -0.12065 -0.2794)
			(stroke
				(width 0.1)
				(type default)
			)
			(layer "F.Fab")
		)
		(fp_line
			(start -0.12065 -0.2794)
			(end 0.12065 -0.2794)
			(stroke
				(width 0.1)
				(type default)
			)
			(layer "F.Fab")
		)
		(fp_line
			(start -0.12065 0.2794)
			(end -0.12065 0.3048)
			(stroke
				(width 0.1)
				(type default)
			)
			(layer "F.Fab")
		)
		(fp_line
			(start -0.12065 0.3048)
			(end -0.67945 0.3048)
			(stroke
				(width 0.1)
				(type default)
			)
			(layer "F.Fab")
		)
		(fp_line
			(start 0.120396 0.2794)
			(end -0.12065 0.2794)
			(stroke
				(width 0.1)
				(type default)
			)
			(layer "F.Fab")
		)
		(fp_line
			(start 0.120396 0.3048)
			(end 0.120396 0.2794)
			(stroke
				(width 0.1)
				(type default)
			)
			(layer "F.Fab")
		)
		(fp_line
			(start 0.12065 -0.3048)
			(end 0.67945 -0.3048)
			(stroke
				(width 0.1)
				(type default)
			)
			(layer "F.Fab")
		)
		(fp_line
			(start 0.12065 -0.2794)
			(end 0.12065 -0.3048)
			(stroke
				(width 0.1)
				(type default)
			)
			(layer "F.Fab")
		)
		(fp_line
			(start 0.67945 -0.3048)
			(end 0.67945 0.3048)
			(stroke
				(width 0.1)
				(type default)
			)
			(layer "F.Fab")
		)
		(fp_line
			(start 0.67945 0.3048)
			(end 0.120396 0.3048)
			(stroke
				(width 0.1)
				(type default)
			)
			(layer "F.Fab")
		)
		(pad "1" smd circle
			(at -0.40005 0)
			(size 0 0)
			(layers "F.Cu" "F.Mask" "F.Paste")
			(net "P3V3_STBY")
		)
		(pad "2" smd circle
			(at 0.40005 0)
			(size 0 0)
			(layers "F.Cu" "F.Mask" "F.Paste")
			(net "REV_ID<2>")
		)
	)
	(footprint ""
		(layer "F.Cu")
		(at 15.875 -46.101 180)
		(property "Reference" "R60"
			(at -2.54 -0.02667 0)
			(unlocked yes)
			(layer "F.SilkS")
			(effects
				(font
					(size 0.7874 0.5842)
					(thickness 0.1524)
				)
			)
		)
		(property "Value" ""
			(at 0 0 180)
			(layer "F.Fab")
			(effects
				(font
					(size 1.27 1.27)
				)
			)
		)
		(duplicate_pad_numbers_are_jumpers no)
		(fp_line
			(start 0.7874 0.4064)
			(end -0.7874 0.4064)
			(stroke
				(width 0.1524)
				(type default)
			)
			(layer "F.SilkS")
		)
		(fp_line
			(start 0.7874 -0.4064)
			(end 0.7874 0.4064)
			(stroke
				(width 0.1524)
				(type default)
			)
			(layer "F.SilkS")
		)
		(fp_line
			(start -0.7874 0.4064)
			(end -0.7874 -0.4064)
			(stroke
				(width 0.1524)
				(type default)
			)
			(layer "F.SilkS")
		)
		(fp_line
			(start -0.7874 -0.4064)
			(end 0.7874 -0.4064)
			(stroke
				(width 0.1524)
				(type default)
			)
			(layer "F.SilkS")
		)
		(fp_line
			(start 0.67945 0.3048)
			(end 0.120396 0.3048)
			(stroke
				(width 0.1)
				(type default)
			)
			(layer "F.Fab")
		)
		(fp_line
			(start 0.67945 -0.3048)
			(end 0.67945 0.3048)
			(stroke
				(width 0.1)
				(type default)
			)
			(layer "F.Fab")
		)
		(fp_line
			(start 0.12065 -0.2794)
			(end 0.12065 -0.3048)
			(stroke
				(width 0.1)
				(type default)
			)
			(layer "F.Fab")
		)
		(fp_line
			(start 0.12065 -0.3048)
			(end 0.67945 -0.3048)
			(stroke
				(width 0.1)
				(type default)
			)
			(layer "F.Fab")
		)
		(fp_line
			(start 0.120396 0.3048)
			(end 0.120396 0.2794)
			(stroke
				(width 0.1)
				(type default)
			)
			(layer "F.Fab")
		)
		(fp_line
			(start 0.120396 0.2794)
			(end -0.12065 0.2794)
			(stroke
				(width 0.1)
				(type default)
			)
			(layer "F.Fab")
		)
		(fp_line
			(start -0.12065 0.3048)
			(end -0.67945 0.3048)
			(stroke
				(width 0.1)
				(type default)
			)
			(layer "F.Fab")
		)
		(fp_line
			(start -0.12065 0.2794)
			(end -0.12065 0.3048)
			(stroke
				(width 0.1)
				(type default)
			)
			(layer "F.Fab")
		)
		(fp_line
			(start -0.12065 -0.2794)
			(end 0.12065 -0.2794)
			(stroke
				(width 0.1)
				(type default)
			)
			(layer "F.Fab")
		)
		(fp_line
			(start -0.12065 -0.305054)
			(end -0.12065 -0.2794)
			(stroke
				(width 0.1)
				(type default)
			)
			(layer "F.Fab")
		)
		(fp_line
			(start -0.67945 0.3048)
			(end -0.67945 -0.305054)
			(stroke
				(width 0.1)
				(type default)
			)
			(layer "F.Fab")
		)
		(fp_line
			(start -0.67945 -0.305054)
			(end -0.12065 -0.305054)
			(stroke
				(width 0.1)
				(type default)
			)
			(layer "F.Fab")
		)
		(pad "1" smd circle
			(at -0.40005 0 180)
			(size 0 0)
			(layers "F.Cu" "F.Mask" "F.Paste")
			(net "SMB_SDA")
		)
		(pad "2" smd circle
			(at 0.40005 0 180)
			(size 0 0)
			(layers "F.Cu" "F.Mask" "F.Paste")
			(net "SMB_FRU_SDA")
		)
	)
	(footprint ""
		(layer "F.Cu")
		(at 3.937 -48.768 180)
		(property "Reference" "R62"
			(at 2.413 -0.15367 0)
			(unlocked yes)
			(layer "F.SilkS")
			(effects
				(font
					(size 0.7874 0.5842)
					(thickness 0.1524)
				)
			)
		)
		(property "Value" ""
			(at 0 0 180)
			(layer "F.Fab")
			(effects
				(font
					(size 1.27 1.27)
				)
			)
		)
		(duplicate_pad_numbers_are_jumpers no)
		(fp_line
			(start 0.7874 0.4064)
			(end -0.7874 0.4064)
			(stroke
				(width 0.1524)
				(type default)
			)
			(layer "F.SilkS")
		)
		(fp_line
			(start 0.7874 -0.4064)
			(end 0.7874 0.4064)
			(stroke
				(width 0.1524)
				(type default)
			)
			(layer "F.SilkS")
		)
		(fp_line
			(start -0.7874 0.4064)
			(end -0.7874 -0.4064)
			(stroke
				(width 0.1524)
				(type default)
			)
			(layer "F.SilkS")
		)
		(fp_line
			(start -0.7874 -0.4064)
			(end 0.7874 -0.4064)
			(stroke
				(width 0.1524)
				(type default)
			)
			(layer "F.SilkS")
		)
		(fp_line
			(start 0.67945 0.3048)
			(end 0.120396 0.3048)
			(stroke
				(width 0.1)
				(type default)
			)
			(layer "F.Fab")
		)
		(fp_line
			(start 0.67945 -0.3048)
			(end 0.67945 0.3048)
			(stroke
				(width 0.1)
				(type default)
			)
			(layer "F.Fab")
		)
		(fp_line
			(start 0.12065 -0.2794)
			(end 0.12065 -0.3048)
			(stroke
				(width 0.1)
				(type default)
			)
			(layer "F.Fab")
		)
		(fp_line
			(start 0.12065 -0.3048)
			(end 0.67945 -0.3048)
			(stroke
				(width 0.1)
				(type default)
			)
			(layer "F.Fab")
		)
		(fp_line
			(start 0.120396 0.3048)
			(end 0.120396 0.2794)
			(stroke
				(width 0.1)
				(type default)
			)
			(layer "F.Fab")
		)
		(fp_line
			(start 0.120396 0.2794)
			(end -0.12065 0.2794)
			(stroke
				(width 0.1)
				(type default)
			)
			(layer "F.Fab")
		)
		(fp_line
			(start -0.12065 0.3048)
			(end -0.67945 0.3048)
			(stroke
				(width 0.1)
				(type default)
			)
			(layer "F.Fab")
		)
		(fp_line
			(start -0.12065 0.2794)
			(end -0.12065 0.3048)
			(stroke
				(width 0.1)
				(type default)
			)
			(layer "F.Fab")
		)
		(fp_line
			(start -0.12065 -0.2794)
			(end 0.12065 -0.2794)
			(stroke
				(width 0.1)
				(type default)
			)
			(layer "F.Fab")
		)
		(fp_line
			(start -0.12065 -0.305054)
			(end -0.12065 -0.2794)
			(stroke
				(width 0.1)
				(type default)
			)
			(layer "F.Fab")
		)
		(fp_line
			(start -0.67945 0.3048)
			(end -0.67945 -0.305054)
			(stroke
				(width 0.1)
				(type default)
			)
			(layer "F.Fab")
		)
		(fp_line
			(start -0.67945 -0.305054)
			(end -0.12065 -0.305054)
			(stroke
				(width 0.1)
				(type default)
			)
			(layer "F.Fab")
		)
		(pad "1" smd circle
			(at -0.40005 0 180)
			(size 0 0)
			(layers "F.Cu" "F.Mask" "F.Paste")
			(net "PD_FRU_A1")
		)
		(pad "2" smd circle
			(at 0.40005 0 180)
			(size 0 0)
			(layers "F.Cu" "F.Mask" "F.Paste")
			(net "GND")
		)
	)
	(footprint ""
		(layer "F.Cu")
		(at 35.941 -30.607)
		(property "Reference" "C10"
			(at 0.762 -6.19633 0)
			(unlocked yes)
			(layer "F.SilkS")
			(effects
				(font
					(size 0.7874 0.5842)
					(thickness 0.1524)
				)
				(justify left)
			)
		)
		(property "Value" ""
			(at 0 0 0)
			(layer "F.Fab")
			(effects
				(font
					(size 1.27 1.27)
				)
			)
		)
		(duplicate_pad_numbers_are_jumpers no)
		(fp_line
			(start -1.524 -0.762)
			(end 1.524 -0.762)
			(stroke
				(width 0.1524)
				(type default)
			)
			(layer "F.SilkS")
		)
		(fp_line
			(start -1.524 0.762)
			(end -1.524 -0.762)
			(stroke
				(width 0.1524)
				(type default)
			)
			(layer "F.SilkS")
		)
		(fp_line
			(start 1.524 -0.762)
			(end 1.524 0.762)
			(stroke
				(width 0.1524)
				(type default)
			)
			(layer "F.SilkS")
		)
		(fp_line
			(start 1.524 0.762)
			(end -1.524 0.762)
			(stroke
				(width 0.1524)
				(type default)
			)
			(layer "F.SilkS")
		)
		(fp_line
			(start -1.1049 -0.724916)
			(end -1.1049 0.724916)
			(stroke
				(width 0.1)
				(type default)
			)
			(layer "F.Fab")
		)
		(fp_line
			(start -1.1049 0.724916)
			(end 1.1049 0.724916)
			(stroke
				(width 0.1)
				(type default)
			)
			(layer "F.Fab")
		)
		(fp_line
			(start 1.1049 -0.724916)
			(end -1.1049 -0.724916)
			(stroke
				(width 0.1)
				(type default)
			)
			(layer "F.Fab")
		)
		(fp_line
			(start 1.1049 0.724916)
			(end 1.1049 -0.724916)
			(stroke
				(width 0.1)
				(type default)
			)
			(layer "F.Fab")
		)
		(pad "1" smd rect
			(at -0.889 0 180)
			(size 1.016 1.27)
			(layers "F.Cu" "F.Mask" "F.Paste")
			(net "P5V_STBY_DEBUG")
		)
		(pad "2" smd rect
			(at 0.889 0 180)
			(size 1.016 1.27)
			(layers "F.Cu" "F.Mask" "F.Paste")
			(net "GND")
		)
	)
	(footprint ""
		(layer "F.Cu")
		(at 5.969 -54.229 180)
		(property "Reference" "R26"
			(at 2.794 -0.40767 0)
			(unlocked yes)
			(layer "F.SilkS")
			(effects
				(font
					(size 0.7874 0.5842)
					(thickness 0.1524)
				)
			)
		)
		(property "Value" ""
			(at 0 0 180)
			(layer "F.Fab")
			(effects
				(font
					(size 1.27 1.27)
				)
			)
		)
		(duplicate_pad_numbers_are_jumpers no)
		(fp_line
			(start 0.7874 0.4064)
			(end -0.7874 0.4064)
			(stroke
				(width 0.1524)
				(type default)
			)
			(layer "F.SilkS")
		)
		(fp_line
			(start 0.7874 -0.4064)
			(end 0.7874 0.4064)
			(stroke
				(width 0.1524)
				(type default)
			)
			(layer "F.SilkS")
		)
		(fp_line
			(start -0.7874 0.4064)
			(end -0.7874 -0.4064)
			(stroke
				(width 0.1524)
				(type default)
			)
			(layer "F.SilkS")
		)
		(fp_line
			(start -0.7874 -0.4064)
			(end 0.7874 -0.4064)
			(stroke
				(width 0.1524)
				(type default)
			)
			(layer "F.SilkS")
		)
		(fp_line
			(start 0.67945 0.3048)
			(end 0.120396 0.3048)
			(stroke
				(width 0.1)
				(type default)
			)
			(layer "F.Fab")
		)
		(fp_line
			(start 0.67945 -0.3048)
			(end 0.67945 0.3048)
			(stroke
				(width 0.1)
				(type default)
			)
			(layer "F.Fab")
		)
		(fp_line
			(start 0.12065 -0.2794)
			(end 0.12065 -0.3048)
			(stroke
				(width 0.1)
				(type default)
			)
			(layer "F.Fab")
		)
		(fp_line
			(start 0.12065 -0.3048)
			(end 0.67945 -0.3048)
			(stroke
				(width 0.1)
				(type default)
			)
			(layer "F.Fab")
		)
		(fp_line
			(start 0.120396 0.3048)
			(end 0.120396 0.2794)
			(stroke
				(width 0.1)
				(type default)
			)
			(layer "F.Fab")
		)
		(fp_line
			(start 0.120396 0.2794)
			(end -0.12065 0.2794)
			(stroke
				(width 0.1)
				(type default)
			)
			(layer "F.Fab")
		)
		(fp_line
			(start -0.12065 0.3048)
			(end -0.67945 0.3048)
			(stroke
				(width 0.1)
				(type default)
			)
			(layer "F.Fab")
		)
		(fp_line
			(start -0.12065 0.2794)
			(end -0.12065 0.3048)
			(stroke
				(width 0.1)
				(type default)
			)
			(layer "F.Fab")
		)
		(fp_line
			(start -0.12065 -0.2794)
			(end 0.12065 -0.2794)
			(stroke
				(width 0.1)
				(type default)
			)
			(layer "F.Fab")
		)
		(fp_line
			(start -0.12065 -0.305054)
			(end -0.12065 -0.2794)
			(stroke
				(width 0.1)
				(type default)
			)
			(layer "F.Fab")
		)
		(fp_line
			(start -0.67945 0.3048)
			(end -0.67945 -0.305054)
			(stroke
				(width 0.1)
				(type default)
			)
			(layer "F.Fab")
		)
		(fp_line
			(start -0.67945 -0.305054)
			(end -0.12065 -0.305054)
			(stroke
				(width 0.1)
				(type default)
			)
			(layer "F.Fab")
		)
		(pad "1" smd circle
			(at -0.40005 0 180)
			(size 0 0)
			(layers "F.Cu" "F.Mask" "F.Paste")
			(net "REV_ID<0>")
		)
		(pad "2" smd circle
			(at 0.40005 0 180)
			(size 0 0)
			(layers "F.Cu" "F.Mask" "F.Paste")
			(net "GND")
		)
	)
	(footprint ""
		(layer "F.Cu")
		(at 32.034734 -23.797768 -90)
		(property "Reference" "R52"
			(at 0.937768 -1.011936 90)
			(unlocked yes)
			(layer "F.SilkS")
			(effects
				(font
					(size 0.7874 0.5842)
					(thickness 0.1524)
				)
				(justify left)
			)
		)
		(property "Value" ""
			(at 0 0 270)
			(layer "F.Fab")
			(effects
				(font
					(size 1.27 1.27)
				)
			)
		)
		(duplicate_pad_numbers_are_jumpers no)
		(fp_line
			(start -0.7874 0.4064)
			(end -0.7874 -0.4064)
			(stroke
				(width 0.1524)
				(type default)
			)
			(layer "F.SilkS")
		)
		(fp_line
			(start 0.7874 0.4064)
			(end -0.7874 0.4064)
			(stroke
				(width 0.1524)
				(type default)
			)
			(layer "F.SilkS")
		)
		(fp_line
			(start -0.7874 -0.4064)
			(end 0.7874 -0.4064)
			(stroke
				(width 0.1524)
				(type default)
			)
			(layer "F.SilkS")
		)
		(fp_line
			(start 0.7874 -0.4064)
			(end 0.7874 0.4064)
			(stroke
				(width 0.1524)
				(type default)
			)
			(layer "F.SilkS")
		)
		(fp_line
			(start -0.67945 0.3048)
			(end -0.67945 -0.305054)
			(stroke
				(width 0.1)
				(type default)
			)
			(layer "F.Fab")
		)
		(fp_line
			(start -0.12065 0.3048)
			(end -0.67945 0.3048)
			(stroke
				(width 0.1)
				(type default)
			)
			(layer "F.Fab")
		)
		(fp_line
			(start 0.120396 0.3048)
			(end 0.120396 0.2794)
			(stroke
				(width 0.1)
				(type default)
			)
			(layer "F.Fab")
		)
		(fp_line
			(start 0.67945 0.3048)
			(end 0.120396 0.3048)
			(stroke
				(width 0.1)
				(type default)
			)
			(layer "F.Fab")
		)
		(fp_line
			(start -0.12065 0.2794)
			(end -0.12065 0.3048)
			(stroke
				(width 0.1)
				(type default)
			)
			(layer "F.Fab")
		)
		(fp_line
			(start 0.120396 0.2794)
			(end -0.12065 0.2794)
			(stroke
				(width 0.1)
				(type default)
			)
			(layer "F.Fab")
		)
		(fp_line
			(start -0.12065 -0.2794)
			(end 0.12065 -0.2794)
			(stroke
				(width 0.1)
				(type default)
			)
			(layer "F.Fab")
		)
		(fp_line
			(start 0.12065 -0.2794)
			(end 0.12065 -0.3048)
			(stroke
				(width 0.1)
				(type default)
			)
			(layer "F.Fab")
		)
		(fp_line
			(start 0.12065 -0.3048)
			(end 0.67945 -0.3048)
			(stroke
				(width 0.1)
				(type default)
			)
			(layer "F.Fab")
		)
		(fp_line
			(start 0.67945 -0.3048)
			(end 0.67945 0.3048)
			(stroke
				(width 0.1)
				(type default)
			)
			(layer "F.Fab")
		)
		(fp_line
			(start -0.67945 -0.305054)
			(end -0.12065 -0.305054)
			(stroke
				(width 0.1)
				(type default)
			)
			(layer "F.Fab")
		)
		(fp_line
			(start -0.12065 -0.305054)
			(end -0.12065 -0.2794)
			(stroke
				(width 0.1)
				(type default)
			)
			(layer "F.Fab")
		)
		(pad "1" smd rect
			(at -0.40005 0 90)
			(size 0.4572 0.508)
			(layers "F.Cu" "F.Mask" "F.Paste")
			(net "USB2_DP")
		)
		(pad "2" smd rect
			(at 0.40005 0 90)
			(size 0.4572 0.508)
			(layers "F.Cu" "F.Mask" "F.Paste")
			(net "USB2_DEBUG_DP")
		)
	)
	(footprint ""
		(layer "F.Cu")
		(at 18.923 -19.431 -90)
		(property "Reference" "U11"
			(at -0.508 -1.93167 90)
			(unlocked yes)
			(layer "F.SilkS")
			(effects
				(font
					(size 0.7874 0.5842)
					(thickness 0.1524)
				)
				(justify left)
			)
		)
		(property "Value" ""
			(at 0 0 270)
			(layer "F.Fab")
			(effects
				(font
					(size 1.27 1.27)
				)
			)
		)
		(duplicate_pad_numbers_are_jumpers no)
		(fp_line
			(start -0.517398 1.500124)
			(end -0.517398 -1.500124)
			(stroke
				(width 0.1524)
				(type default)
			)
			(layer "F.SilkS")
		)
		(fp_line
			(start 0.517398 1.500124)
			(end -0.517398 1.500124)
			(stroke
				(width 0.1524)
				(type default)
			)
			(layer "F.SilkS")
		)
		(fp_line
			(start -0.517398 -1.500124)
			(end 0.517398 -1.500124)
			(stroke
				(width 0.1524)
				(type default)
			)
			(layer "F.SilkS")
		)
		(fp_line
			(start 0.517398 -1.500124)
			(end 0.517398 1.500124)
			(stroke
				(width 0.1524)
				(type default)
			)
			(layer "F.SilkS")
		)
		(fp_poly
			(pts
				(xy -1.5113 -0.750062) (xy -2.1463 -1.067562) (xy -2.1463 -0.432562)
			)
			(stroke
				(width 0)
				(type default)
			)
			(fill yes)
			(layer "F.SilkS")
		)
		(fp_line
			(start -0.700024 1.500124)
			(end -0.700024 -1.500124)
			(stroke
				(width 0.1)
				(type default)
			)
			(layer "F.Fab")
		)
		(fp_line
			(start 0.700024 1.500124)
			(end -0.700024 1.500124)
			(stroke
				(width 0.1)
				(type default)
			)
			(layer "F.Fab")
		)
		(fp_line
			(start -0.700024 -1.500124)
			(end 0.700024 -1.500124)
			(stroke
				(width 0.1)
				(type default)
			)
			(layer "F.Fab")
		)
		(fp_line
			(start 0.700024 -1.500124)
			(end 0.700024 1.500124)
			(stroke
				(width 0.1)
				(type default)
			)
			(layer "F.Fab")
		)
		(fp_poly
			(pts
				(xy -1.5113 -0.750062) (xy -2.1463 -1.067562) (xy -2.1463 -0.432562)
			)
			(stroke
				(width 0)
				(type default)
			)
			(fill yes)
			(layer "F.Fab")
		)
		(pad "1" smd rect
			(at -0.999998 -0.750062 270)
			(size 0.7112 1.016)
			(layers "F.Cu" "F.Mask" "F.Paste")
			(net "GND")
		)
		(pad "2" smd rect
			(at -0.999998 0.94996 180)
			(size 0.6096 0.7112)
			(layers "F.Cu" "F.Mask" "F.Paste")
			(net "SMB_IO_DEBUG_CARD_SCL")
		)
		(pad "3" smd rect
			(at 0.999998 0.94996 180)
			(size 0.6096 0.7112)
			(layers "F.Cu" "F.Mask" "F.Paste")
			(net "SMB_IO_DEBUG_CARD_SDA")
		)
		(pad "4" smd rect
			(at 0.999998 -0.94996 180)
			(size 0.6096 0.7112)
			(layers "F.Cu" "F.Mask" "F.Paste")
			(net "P5V_STBY_DEBUG")
		)
	)
	(footprint ""
		(layer "F.Cu")
		(at 17.526 -22.098 180)
		(property "Reference" "R47"
			(at 0.127 4.16433 0)
			(unlocked yes)
			(layer "F.SilkS")
			(effects
				(font
					(size 0.7874 0.5842)
					(thickness 0.1524)
				)
			)
		)
		(property "Value" ""
			(at 0 0 180)
			(layer "F.Fab")
			(effects
				(font
					(size 1.27 1.27)
				)
			)
		)
		(duplicate_pad_numbers_are_jumpers no)
		(fp_line
			(start 0.7874 0.4064)
			(end -0.7874 0.4064)
			(stroke
				(width 0.1524)
				(type default)
			)
			(layer "F.SilkS")
		)
		(fp_line
			(start 0.7874 -0.4064)
			(end 0.7874 0.4064)
			(stroke
				(width 0.1524)
				(type default)
			)
			(layer "F.SilkS")
		)
		(fp_line
			(start -0.7874 0.4064)
			(end -0.7874 -0.4064)
			(stroke
				(width 0.1524)
				(type default)
			)
			(layer "F.SilkS")
		)
		(fp_line
			(start -0.7874 -0.4064)
			(end 0.7874 -0.4064)
			(stroke
				(width 0.1524)
				(type default)
			)
			(layer "F.SilkS")
		)
		(fp_line
			(start 0.67945 0.3048)
			(end 0.120396 0.3048)
			(stroke
				(width 0.1)
				(type default)
			)
			(layer "F.Fab")
		)
		(fp_line
			(start 0.67945 -0.3048)
			(end 0.67945 0.3048)
			(stroke
				(width 0.1)
				(type default)
			)
			(layer "F.Fab")
		)
		(fp_line
			(start 0.12065 -0.2794)
			(end 0.12065 -0.3048)
			(stroke
				(width 0.1)
				(type default)
			)
			(layer "F.Fab")
		)
		(fp_line
			(start 0.12065 -0.3048)
			(end 0.67945 -0.3048)
			(stroke
				(width 0.1)
				(type default)
			)
			(layer "F.Fab")
		)
		(fp_line
			(start 0.120396 0.3048)
			(end 0.120396 0.2794)
			(stroke
				(width 0.1)
				(type default)
			)
			(layer "F.Fab")
		)
		(fp_line
			(start 0.120396 0.2794)
			(end -0.12065 0.2794)
			(stroke
				(width 0.1)
				(type default)
			)
			(layer "F.Fab")
		)
		(fp_line
			(start -0.12065 0.3048)
			(end -0.67945 0.3048)
			(stroke
				(width 0.1)
				(type default)
			)
			(layer "F.Fab")
		)
		(fp_line
			(start -0.12065 0.2794)
			(end -0.12065 0.3048)
			(stroke
				(width 0.1)
				(type default)
			)
			(layer "F.Fab")
		)
		(fp_line
			(start -0.12065 -0.2794)
			(end 0.12065 -0.2794)
			(stroke
				(width 0.1)
				(type default)
			)
			(layer "F.Fab")
		)
		(fp_line
			(start -0.12065 -0.305054)
			(end -0.12065 -0.2794)
			(stroke
				(width 0.1)
				(type default)
			)
			(layer "F.Fab")
		)
		(fp_line
			(start -0.67945 0.3048)
			(end -0.67945 -0.305054)
			(stroke
				(width 0.1)
				(type default)
			)
			(layer "F.Fab")
		)
		(fp_line
			(start -0.67945 -0.305054)
			(end -0.12065 -0.305054)
			(stroke
				(width 0.1)
				(type default)
			)
			(layer "F.Fab")
		)
		(pad "1" smd circle
			(at -0.40005 0 180)
			(size 0 0)
			(layers "F.Cu" "F.Mask" "F.Paste")
			(net "P3V3_STBY")
		)
		(pad "2" smd circle
			(at 0.40005 0 180)
			(size 0 0)
			(layers "F.Cu" "F.Mask" "F.Paste")
			(net "SMB_IO_DEBUG_CARD_SCL")
		)
	)
	(footprint ""
		(layer "F.Cu")
		(at 5.969 -53.213)
		(property "Reference" "R21"
			(at -2.794 0.40767 0)
			(unlocked yes)
			(layer "F.SilkS")
			(effects
				(font
					(size 0.7874 0.5842)
					(thickness 0.1524)
				)
			)
		)
		(property "Value" ""
			(at 0 0 0)
			(layer "F.Fab")
			(effects
				(font
					(size 1.27 1.27)
				)
			)
		)
		(duplicate_pad_numbers_are_jumpers no)
		(fp_line
			(start -0.7874 -0.4064)
			(end 0.7874 -0.4064)
			(stroke
				(width 0.1524)
				(type default)
			)
			(layer "F.SilkS")
		)
		(fp_line
			(start -0.7874 0.4064)
			(end -0.7874 -0.4064)
			(stroke
				(width 0.1524)
				(type default)
			)
			(layer "F.SilkS")
		)
		(fp_line
			(start 0.7874 -0.4064)
			(end 0.7874 0.4064)
			(stroke
				(width 0.1524)
				(type default)
			)
			(layer "F.SilkS")
		)
		(fp_line
			(start 0.7874 0.4064)
			(end -0.7874 0.4064)
			(stroke
				(width 0.1524)
				(type default)
			)
			(layer "F.SilkS")
		)
		(fp_line
			(start -0.67945 -0.305054)
			(end -0.12065 -0.305054)
			(stroke
				(width 0.1)
				(type default)
			)
			(layer "F.Fab")
		)
		(fp_line
			(start -0.67945 0.3048)
			(end -0.67945 -0.305054)
			(stroke
				(width 0.1)
				(type default)
			)
			(layer "F.Fab")
		)
		(fp_line
			(start -0.12065 -0.305054)
			(end -0.12065 -0.2794)
			(stroke
				(width 0.1)
				(type default)
			)
			(layer "F.Fab")
		)
		(fp_line
			(start -0.12065 -0.2794)
			(end 0.12065 -0.2794)
			(stroke
				(width 0.1)
				(type default)
			)
			(layer "F.Fab")
		)
		(fp_line
			(start -0.12065 0.2794)
			(end -0.12065 0.3048)
			(stroke
				(width 0.1)
				(type default)
			)
			(layer "F.Fab")
		)
		(fp_line
			(start -0.12065 0.3048)
			(end -0.67945 0.3048)
			(stroke
				(width 0.1)
				(type default)
			)
			(layer "F.Fab")
		)
		(fp_line
			(start 0.120396 0.2794)
			(end -0.12065 0.2794)
			(stroke
				(width 0.1)
				(type default)
			)
			(layer "F.Fab")
		)
		(fp_line
			(start 0.120396 0.3048)
			(end 0.120396 0.2794)
			(stroke
				(width 0.1)
				(type default)
			)
			(layer "F.Fab")
		)
		(fp_line
			(start 0.12065 -0.3048)
			(end 0.67945 -0.3048)
			(stroke
				(width 0.1)
				(type default)
			)
			(layer "F.Fab")
		)
		(fp_line
			(start 0.12065 -0.2794)
			(end 0.12065 -0.3048)
			(stroke
				(width 0.1)
				(type default)
			)
			(layer "F.Fab")
		)
		(fp_line
			(start 0.67945 -0.3048)
			(end 0.67945 0.3048)
			(stroke
				(width 0.1)
				(type default)
			)
			(layer "F.Fab")
		)
		(fp_line
			(start 0.67945 0.3048)
			(end 0.120396 0.3048)
			(stroke
				(width 0.1)
				(type default)
			)
			(layer "F.Fab")
		)
		(pad "1" smd circle
			(at -0.40005 0)
			(size 0 0)
			(layers "F.Cu" "F.Mask" "F.Paste")
			(net "P3V3_STBY")
		)
		(pad "2" smd circle
			(at 0.40005 0)
			(size 0 0)
			(layers "F.Cu" "F.Mask" "F.Paste")
			(net "REV_ID<0>")
		)
	)
	(footprint ""
		(layer "F.Cu")
		(at 10.033 -27.813)
		(property "Reference" "R11"
			(at -0.254 -2.38633 0)
			(unlocked yes)
			(layer "F.SilkS")
			(effects
				(font
					(size 0.7874 0.5842)
					(thickness 0.1524)
				)
			)
		)
		(property "Value" ""
			(at 0 0 0)
			(layer "F.Fab")
			(effects
				(font
					(size 1.27 1.27)
				)
			)
		)
		(duplicate_pad_numbers_are_jumpers no)
		(fp_line
			(start -1.2954 -0.5842)
			(end 1.2954 -0.5842)
			(stroke
				(width 0.1524)
				(type default)
			)
			(layer "F.SilkS")
		)
		(fp_line
			(start -1.2954 0.5842)
			(end -1.2954 -0.5842)
			(stroke
				(width 0.1524)
				(type default)
			)
			(layer "F.SilkS")
		)
		(fp_line
			(start 1.2954 -0.5842)
			(end 1.2954 0.5842)
			(stroke
				(width 0.1524)
				(type default)
			)
			(layer "F.SilkS")
		)
		(fp_line
			(start 1.2954 0.5842)
			(end -1.2954 0.5842)
			(stroke
				(width 0.1524)
				(type default)
			)
			(layer "F.SilkS")
		)
		(fp_line
			(start -1.1938 -0.406654)
			(end -0.8636 -0.406654)
			(stroke
				(width 0.1)
				(type default)
			)
			(layer "F.Fab")
		)
		(fp_line
			(start -1.1938 0.4064)
			(end -1.1938 -0.406654)
			(stroke
				(width 0.1)
				(type default)
			)
			(layer "F.Fab")
		)
		(fp_line
			(start -0.8636 -0.4572)
			(end 0.8636 -0.4572)
			(stroke
				(width 0.1)
				(type default)
			)
			(layer "F.Fab")
		)
		(fp_line
			(start -0.8636 -0.406654)
			(end -0.8636 -0.4572)
			(stroke
				(width 0.1)
				(type default)
			)
			(layer "F.Fab")
		)
		(fp_line
			(start -0.8636 0.4064)
			(end -1.1938 0.4064)
			(stroke
				(width 0.1)
				(type default)
			)
			(layer "F.Fab")
		)
		(fp_line
			(start -0.8636 0.4318)
			(end -0.8636 0.4064)
			(stroke
				(width 0.1)
				(type default)
			)
			(layer "F.Fab")
		)
		(fp_line
			(start -0.8636 0.4572)
			(end -0.8636 0.4318)
			(stroke
				(width 0.1)
				(type default)
			)
			(layer "F.Fab")
		)
		(fp_line
			(start 0.8636 -0.4572)
			(end 0.8636 -0.406654)
			(stroke
				(width 0.1)
				(type default)
			)
			(layer "F.Fab")
		)
		(fp_line
			(start 0.8636 -0.406654)
			(end 1.1938 -0.406654)
			(stroke
				(width 0.1)
				(type default)
			)
			(layer "F.Fab")
		)
		(fp_line
			(start 0.8636 0.4064)
			(end 0.8636 0.4572)
			(stroke
				(width 0.1)
				(type default)
			)
			(layer "F.Fab")
		)
		(fp_line
			(start 0.8636 0.4572)
			(end -0.8636 0.4572)
			(stroke
				(width 0.1)
				(type default)
			)
			(layer "F.Fab")
		)
		(fp_line
			(start 1.1938 -0.406654)
			(end 1.1938 0.4064)
			(stroke
				(width 0.1)
				(type default)
			)
			(layer "F.Fab")
		)
		(fp_line
			(start 1.1938 0.4064)
			(end 0.8636 0.4064)
			(stroke
				(width 0.1)
				(type default)
			)
			(layer "F.Fab")
		)
		(pad "1" smd rect
			(at -0.7366 0 270)
			(size 0.7112 0.8128)
			(layers "F.Cu" "F.Mask" "F.Paste")
			(net "PWR_LED_R1_N")
		)
		(pad "2" smd rect
			(at 0.7366 0 270)
			(size 0.7112 0.8128)
			(layers "F.Cu" "F.Mask" "F.Paste")
			(net "PWR_LED_R2_N")
		)
	)
	(footprint ""
		(layer "F.Cu")
		(at 31.609792 -23.855934)
		(property "Reference" "L1"
			(at -2.145792 1.784604 0)
			(unlocked yes)
			(layer "F.SilkS")
			(effects
				(font
					(size 0.7874 0.5842)
					(thickness 0.1524)
				)
				(justify left)
			)
		)
		(property "Value" ""
			(at 0 0 0)
			(layer "F.Fab")
			(effects
				(font
					(size 1.27 1.27)
				)
			)
		)
		(duplicate_pad_numbers_are_jumpers no)
		(fp_line
			(start -0.8636 -1.524)
			(end 0.8636 -1.524)
			(stroke
				(width 0.1524)
				(type default)
			)
			(layer "F.SilkS")
		)
		(fp_line
			(start -0.8636 1.524)
			(end -0.8636 -1.524)
			(stroke
				(width 0.1524)
				(type default)
			)
			(layer "F.SilkS")
		)
		(fp_line
			(start 0.8636 -1.524)
			(end 0.8636 1.524)
			(stroke
				(width 0.1524)
				(type default)
			)
			(layer "F.SilkS")
		)
		(fp_line
			(start 0.8636 1.524)
			(end -0.8636 1.524)
			(stroke
				(width 0.1524)
				(type default)
			)
			(layer "F.SilkS")
		)
		(fp_poly
			(pts
				(xy -1.11633 -1.448816) (xy -1.62433 -1.194816) (xy -1.62433 -1.702816)
			)
			(stroke
				(width 0)
				(type default)
			)
			(fill yes)
			(layer "F.SilkS")
		)
		(fp_line
			(start -0.700024 -1.100074)
			(end 0.700024 -1.100074)
			(stroke
				(width 0.1)
				(type default)
			)
			(layer "F.Fab")
		)
		(fp_line
			(start -0.700024 1.100074)
			(end -0.700024 -1.100074)
			(stroke
				(width 0.1)
				(type default)
			)
			(layer "F.Fab")
		)
		(fp_line
			(start 0.700024 -1.100074)
			(end 0.700024 1.100074)
			(stroke
				(width 0.1)
				(type default)
			)
			(layer "F.Fab")
		)
		(fp_line
			(start 0.700024 1.100074)
			(end -0.700024 1.100074)
			(stroke
				(width 0.1)
				(type default)
			)
			(layer "F.Fab")
		)
		(fp_poly
			(pts
				(xy -0.4572 -1.6256) (xy -0.7112 -2.1336) (xy -0.2032 -2.1336)
			)
			(stroke
				(width 0)
				(type default)
			)
			(fill yes)
			(layer "F.Fab")
		)
		(pad "1" smd rect
			(at -0.424942 -0.849884)
			(size 0.3556 0.9144)
			(layers "F.Cu" "F.Mask" "F.Paste")
			(net "USB2_DN")
		)
		(pad "2" smd rect
			(at -0.424942 0.849884)
			(size 0.3556 0.9144)
			(layers "F.Cu" "F.Mask" "F.Paste")
			(net "USB2_DEBUG_DN")
		)
		(pad "3" smd rect
			(at 0.424942 0.849884)
			(size 0.3556 0.9144)
			(layers "F.Cu" "F.Mask" "F.Paste")
			(net "USB2_DEBUG_DP")
		)
		(pad "4" smd rect
			(at 0.424942 -0.849884)
			(size 0.3556 0.9144)
			(layers "F.Cu" "F.Mask" "F.Paste")
			(net "USB2_DP")
		)
	)
	(footprint ""
		(layer "F.Cu")
		(at 2.918206 -21.814282)
		(property "Reference" ""
			(at 0 0 0)
			(layer "F.SilkS")
			(hide yes)
			(effects
				(font
					(size 1.27 1.27)
				)
			)
		)
		(property "Value" ""
			(at 0 0 0)
			(layer "F.Fab")
			(effects
				(font
					(size 1.27 1.27)
				)
			)
		)
		(duplicate_pad_numbers_are_jumpers no)
		(pad "1" smd circle
			(at 0 0)
			(size 0.9906 0.9906)
			(layers "F.Cu" "F.Mask" "F.Paste")
			(net "Net_12")
		)
		(zone
			(layer "F.Cu")
			(hatch none 0.5)
			(connect_pads
				(clearance 0)
			)
			(min_thickness 0.25)
			(keepout
				(tracks not_allowed)
				(vias allowed)
				(pads allowed)
				(copperpour not_allowed)
				(footprints allowed)
			)
			(placement
				(enabled no)
				(sheetname "")
			)
			(fill
				(thermal_gap 0.5)
				(thermal_bridge_width 0.5)
				(island_removal_mode 0)
			)
			(polygon
				(pts
					(arc
						(start 4.543806 -21.814282)
						(mid 1.292606 -21.814282)
						(end 4.543806 -21.814282)
					)
				)
			)
		)
	)
	(footprint ""
		(layer "F.Cu")
		(at 5.969 -59.309 180)
		(property "Reference" "R18"
			(at 2.794 -0.40767 0)
			(unlocked yes)
			(layer "F.SilkS")
			(effects
				(font
					(size 0.7874 0.5842)
					(thickness 0.1524)
				)
			)
		)
		(property "Value" ""
			(at 0 0 180)
			(layer "F.Fab")
			(effects
				(font
					(size 1.27 1.27)
				)
			)
		)
		(duplicate_pad_numbers_are_jumpers no)
		(fp_line
			(start 0.7874 0.4064)
			(end -0.7874 0.4064)
			(stroke
				(width 0.1524)
				(type default)
			)
			(layer "F.SilkS")
		)
		(fp_line
			(start 0.7874 -0.4064)
			(end 0.7874 0.4064)
			(stroke
				(width 0.1524)
				(type default)
			)
			(layer "F.SilkS")
		)
		(fp_line
			(start -0.7874 0.4064)
			(end -0.7874 -0.4064)
			(stroke
				(width 0.1524)
				(type default)
			)
			(layer "F.SilkS")
		)
		(fp_line
			(start -0.7874 -0.4064)
			(end 0.7874 -0.4064)
			(stroke
				(width 0.1524)
				(type default)
			)
			(layer "F.SilkS")
		)
		(fp_line
			(start 0.67945 0.3048)
			(end 0.120396 0.3048)
			(stroke
				(width 0.1)
				(type default)
			)
			(layer "F.Fab")
		)
		(fp_line
			(start 0.67945 -0.3048)
			(end 0.67945 0.3048)
			(stroke
				(width 0.1)
				(type default)
			)
			(layer "F.Fab")
		)
		(fp_line
			(start 0.12065 -0.2794)
			(end 0.12065 -0.3048)
			(stroke
				(width 0.1)
				(type default)
			)
			(layer "F.Fab")
		)
		(fp_line
			(start 0.12065 -0.3048)
			(end 0.67945 -0.3048)
			(stroke
				(width 0.1)
				(type default)
			)
			(layer "F.Fab")
		)
		(fp_line
			(start 0.120396 0.3048)
			(end 0.120396 0.2794)
			(stroke
				(width 0.1)
				(type default)
			)
			(layer "F.Fab")
		)
		(fp_line
			(start 0.120396 0.2794)
			(end -0.12065 0.2794)
			(stroke
				(width 0.1)
				(type default)
			)
			(layer "F.Fab")
		)
		(fp_line
			(start -0.12065 0.3048)
			(end -0.67945 0.3048)
			(stroke
				(width 0.1)
				(type default)
			)
			(layer "F.Fab")
		)
		(fp_line
			(start -0.12065 0.2794)
			(end -0.12065 0.3048)
			(stroke
				(width 0.1)
				(type default)
			)
			(layer "F.Fab")
		)
		(fp_line
			(start -0.12065 -0.2794)
			(end 0.12065 -0.2794)
			(stroke
				(width 0.1)
				(type default)
			)
			(layer "F.Fab")
		)
		(fp_line
			(start -0.12065 -0.305054)
			(end -0.12065 -0.2794)
			(stroke
				(width 0.1)
				(type default)
			)
			(layer "F.Fab")
		)
		(fp_line
			(start -0.67945 0.3048)
			(end -0.67945 -0.305054)
			(stroke
				(width 0.1)
				(type default)
			)
			(layer "F.Fab")
		)
		(fp_line
			(start -0.67945 -0.305054)
			(end -0.12065 -0.305054)
			(stroke
				(width 0.1)
				(type default)
			)
			(layer "F.Fab")
		)
		(pad "1" smd circle
			(at -0.40005 0 180)
			(size 0 0)
			(layers "F.Cu" "F.Mask" "F.Paste")
			(net "RST_SMB_R_N")
		)
		(pad "2" smd circle
			(at 0.40005 0 180)
			(size 0 0)
			(layers "F.Cu" "F.Mask" "F.Paste")
			(net "P3V3_STBY")
		)
	)
	(footprint ""
		(layer "F.Cu")
		(at 36.703 -19.304 180)
		(property "Reference" "R32"
			(at 2.032 -0.02667 0)
			(unlocked yes)
			(layer "F.SilkS")
			(effects
				(font
					(size 0.7874 0.5842)
					(thickness 0.1524)
				)
			)
		)
		(property "Value" ""
			(at 0 0 180)
			(layer "F.Fab")
			(effects
				(font
					(size 1.27 1.27)
				)
			)
		)
		(duplicate_pad_numbers_are_jumpers no)
		(fp_line
			(start 0.7874 0.4064)
			(end -0.7874 0.4064)
			(stroke
				(width 0.1524)
				(type default)
			)
			(layer "F.SilkS")
		)
		(fp_line
			(start 0.7874 -0.4064)
			(end 0.7874 0.4064)
			(stroke
				(width 0.1524)
				(type default)
			)
			(layer "F.SilkS")
		)
		(fp_line
			(start -0.7874 0.4064)
			(end -0.7874 -0.4064)
			(stroke
				(width 0.1524)
				(type default)
			)
			(layer "F.SilkS")
		)
		(fp_line
			(start -0.7874 -0.4064)
			(end 0.7874 -0.4064)
			(stroke
				(width 0.1524)
				(type default)
			)
			(layer "F.SilkS")
		)
		(fp_line
			(start 0.67945 0.3048)
			(end 0.120396 0.3048)
			(stroke
				(width 0.1)
				(type default)
			)
			(layer "F.Fab")
		)
		(fp_line
			(start 0.67945 -0.3048)
			(end 0.67945 0.3048)
			(stroke
				(width 0.1)
				(type default)
			)
			(layer "F.Fab")
		)
		(fp_line
			(start 0.12065 -0.2794)
			(end 0.12065 -0.3048)
			(stroke
				(width 0.1)
				(type default)
			)
			(layer "F.Fab")
		)
		(fp_line
			(start 0.12065 -0.3048)
			(end 0.67945 -0.3048)
			(stroke
				(width 0.1)
				(type default)
			)
			(layer "F.Fab")
		)
		(fp_line
			(start 0.120396 0.3048)
			(end 0.120396 0.2794)
			(stroke
				(width 0.1)
				(type default)
			)
			(layer "F.Fab")
		)
		(fp_line
			(start 0.120396 0.2794)
			(end -0.12065 0.2794)
			(stroke
				(width 0.1)
				(type default)
			)
			(layer "F.Fab")
		)
		(fp_line
			(start -0.12065 0.3048)
			(end -0.67945 0.3048)
			(stroke
				(width 0.1)
				(type default)
			)
			(layer "F.Fab")
		)
		(fp_line
			(start -0.12065 0.2794)
			(end -0.12065 0.3048)
			(stroke
				(width 0.1)
				(type default)
			)
			(layer "F.Fab")
		)
		(fp_line
			(start -0.12065 -0.2794)
			(end 0.12065 -0.2794)
			(stroke
				(width 0.1)
				(type default)
			)
			(layer "F.Fab")
		)
		(fp_line
			(start -0.12065 -0.305054)
			(end -0.12065 -0.2794)
			(stroke
				(width 0.1)
				(type default)
			)
			(layer "F.Fab")
		)
		(fp_line
			(start -0.67945 0.3048)
			(end -0.67945 -0.305054)
			(stroke
				(width 0.1)
				(type default)
			)
			(layer "F.Fab")
		)
		(fp_line
			(start -0.67945 -0.305054)
			(end -0.12065 -0.305054)
			(stroke
				(width 0.1)
				(type default)
			)
			(layer "F.Fab")
		)
		(pad "1" smd circle
			(at -0.40005 0 180)
			(size 0 0)
			(layers "F.Cu" "F.Mask" "F.Paste")
			(net "P3V3_STBY")
		)
		(pad "2" smd circle
			(at 0.40005 0 180)
			(size 0 0)
			(layers "F.Cu" "F.Mask" "F.Paste")
			(net "THERMAL_ADDR_A0")
		)
	)
	(footprint ""
		(layer "F.Cu")
		(at 19.67992 -6.679946)
		(property "Reference" "D1"
			(at -7.48792 -0.659384 0)
			(unlocked yes)
			(layer "F.SilkS")
			(effects
				(font
					(size 0.7874 0.5842)
					(thickness 0.1524)
				)
				(justify left)
			)
		)
		(property "Value" ""
			(at 0 0 0)
			(layer "F.Fab")
			(effects
				(font
					(size 1.27 1.27)
				)
			)
		)
		(duplicate_pad_numbers_are_jumpers no)
		(fp_line
			(start -6.04012 -1.27)
			(end 0.96012 -1.27)
			(stroke
				(width 0.1524)
				(type default)
			)
			(layer "F.SilkS")
		)
		(fp_line
			(start -6.04012 5.08)
			(end -6.04012 -1.27)
			(stroke
				(width 0.1524)
				(type default)
			)
			(layer "F.SilkS")
		)
		(fp_line
			(start -4.089908 5.08)
			(end -6.04012 5.08)
			(stroke
				(width 0.1524)
				(type default)
			)
			(layer "F.SilkS")
		)
		(fp_line
			(start -4.089908 6.230112)
			(end -4.089908 5.08)
			(stroke
				(width 0.1524)
				(type default)
			)
			(layer "F.SilkS")
		)
		(fp_line
			(start -0.990092 5.08)
			(end -0.990092 6.230112)
			(stroke
				(width 0.1524)
				(type default)
			)
			(layer "F.SilkS")
		)
		(fp_line
			(start 0.96012 -1.27)
			(end 0.96012 5.08)
			(stroke
				(width 0.1524)
				(type default)
			)
			(layer "F.SilkS")
		)
		(fp_line
			(start 0.96012 5.08)
			(end -0.990092 5.08)
			(stroke
				(width 0.1524)
				(type default)
			)
			(layer "F.SilkS")
		)
		(fp_arc
			(start -2.54 7.78002)
			(mid -3.63595 7.326062)
			(end -4.089908 6.230112)
			(stroke
				(width 0.1524)
				(type default)
			)
			(layer "F.SilkS")
		)
		(fp_arc
			(start -0.990092 6.230112)
			(mid -1.44405 7.326062)
			(end -2.54 7.78002)
			(stroke
				(width 0.1524)
				(type default)
			)
			(layer "F.SilkS")
		)
		(fp_line
			(start -6.04012 -1.27)
			(end 0.96012 -1.27)
			(stroke
				(width 0.1)
				(type default)
			)
			(layer "F.Fab")
		)
		(fp_line
			(start -6.04012 5.08)
			(end -6.04012 -1.27)
			(stroke
				(width 0.1)
				(type default)
			)
			(layer "F.Fab")
		)
		(fp_line
			(start -4.089908 5.08)
			(end -6.04012 5.08)
			(stroke
				(width 0.1)
				(type default)
			)
			(layer "F.Fab")
		)
		(fp_line
			(start -4.089908 6.230112)
			(end -4.089908 5.08)
			(stroke
				(width 0.1)
				(type default)
			)
			(layer "F.Fab")
		)
		(fp_line
			(start -0.990092 5.08)
			(end -0.990092 6.230112)
			(stroke
				(width 0.1)
				(type default)
			)
			(layer "F.Fab")
		)
		(fp_line
			(start 0.96012 -1.27)
			(end 0.96012 5.08)
			(stroke
				(width 0.1)
				(type default)
			)
			(layer "F.Fab")
		)
		(fp_line
			(start 0.96012 5.08)
			(end -0.990092 5.08)
			(stroke
				(width 0.1)
				(type default)
			)
			(layer "F.Fab")
		)
		(fp_arc
			(start -2.54 7.78002)
			(mid -3.63595 7.326062)
			(end -4.089908 6.230112)
			(stroke
				(width 0.1)
				(type default)
			)
			(layer "F.Fab")
		)
		(fp_arc
			(start -0.990092 6.230112)
			(mid -1.44405 7.326062)
			(end -2.54 7.78002)
			(stroke
				(width 0.1)
				(type default)
			)
			(layer "F.Fab")
		)
		(pad "1" thru_hole rect
			(at 0 0)
			(size 1.3716 1.3716)
			(drill 0.9652)
			(layers "*.Cu" "*.Mask")
			(remove_unused_layers no)
			(net "FM_PFR_LED_BLUE_R")
			(clearance 0.0508)
			(thermal_gap 0.0508)
			(padstack
				(mode front_inner_back)
				(layer "Inner"
					(shape circle)
					(size 1.3716 1.3716)
					(clearance 0.0508)
				)
				(layer "B.Cu"
					(shape rect)
					(size 1.3716 1.3716)
					(clearance 0.0508)
				)
			)
		)
		(pad "2" thru_hole circle
			(at -2.54 0)
			(size 1.3716 1.3716)
			(drill 0.9652)
			(layers "*.Cu" "*.Mask")
			(remove_unused_layers no)
			(net "GND")
			(clearance 0.0508)
			(thermal_gap 0.0508)
		)
		(pad "3" thru_hole circle
			(at -5.08 0)
			(size 1.3716 1.3716)
			(drill 0.9652)
			(layers "*.Cu" "*.Mask")
			(remove_unused_layers no)
			(net "FM_PFR_LED_AMBER_R")
			(clearance 0.0508)
			(thermal_gap 0.0508)
		)
	)
	(footprint ""
		(layer "F.Cu")
		(at 17.526 -23.114)
		(property "Reference" "R48"
			(at -0.127 -4.16433 0)
			(unlocked yes)
			(layer "F.SilkS")
			(effects
				(font
					(size 0.7874 0.5842)
					(thickness 0.1524)
				)
			)
		)
		(property "Value" ""
			(at 0 0 0)
			(layer "F.Fab")
			(effects
				(font
					(size 1.27 1.27)
				)
			)
		)
		(duplicate_pad_numbers_are_jumpers no)
		(fp_line
			(start -0.7874 -0.4064)
			(end 0.7874 -0.4064)
			(stroke
				(width 0.1524)
				(type default)
			)
			(layer "F.SilkS")
		)
		(fp_line
			(start -0.7874 0.4064)
			(end -0.7874 -0.4064)
			(stroke
				(width 0.1524)
				(type default)
			)
			(layer "F.SilkS")
		)
		(fp_line
			(start 0.7874 -0.4064)
			(end 0.7874 0.4064)
			(stroke
				(width 0.1524)
				(type default)
			)
			(layer "F.SilkS")
		)
		(fp_line
			(start 0.7874 0.4064)
			(end -0.7874 0.4064)
			(stroke
				(width 0.1524)
				(type default)
			)
			(layer "F.SilkS")
		)
		(fp_line
			(start -0.67945 -0.305054)
			(end -0.12065 -0.305054)
			(stroke
				(width 0.1)
				(type default)
			)
			(layer "F.Fab")
		)
		(fp_line
			(start -0.67945 0.3048)
			(end -0.67945 -0.305054)
			(stroke
				(width 0.1)
				(type default)
			)
			(layer "F.Fab")
		)
		(fp_line
			(start -0.12065 -0.305054)
			(end -0.12065 -0.2794)
			(stroke
				(width 0.1)
				(type default)
			)
			(layer "F.Fab")
		)
		(fp_line
			(start -0.12065 -0.2794)
			(end 0.12065 -0.2794)
			(stroke
				(width 0.1)
				(type default)
			)
			(layer "F.Fab")
		)
		(fp_line
			(start -0.12065 0.2794)
			(end -0.12065 0.3048)
			(stroke
				(width 0.1)
				(type default)
			)
			(layer "F.Fab")
		)
		(fp_line
			(start -0.12065 0.3048)
			(end -0.67945 0.3048)
			(stroke
				(width 0.1)
				(type default)
			)
			(layer "F.Fab")
		)
		(fp_line
			(start 0.120396 0.2794)
			(end -0.12065 0.2794)
			(stroke
				(width 0.1)
				(type default)
			)
			(layer "F.Fab")
		)
		(fp_line
			(start 0.120396 0.3048)
			(end 0.120396 0.2794)
			(stroke
				(width 0.1)
				(type default)
			)
			(layer "F.Fab")
		)
		(fp_line
			(start 0.12065 -0.3048)
			(end 0.67945 -0.3048)
			(stroke
				(width 0.1)
				(type default)
			)
			(layer "F.Fab")
		)
		(fp_line
			(start 0.12065 -0.2794)
			(end 0.12065 -0.3048)
			(stroke
				(width 0.1)
				(type default)
			)
			(layer "F.Fab")
		)
		(fp_line
			(start 0.67945 -0.3048)
			(end 0.67945 0.3048)
			(stroke
				(width 0.1)
				(type default)
			)
			(layer "F.Fab")
		)
		(fp_line
			(start 0.67945 0.3048)
			(end 0.120396 0.3048)
			(stroke
				(width 0.1)
				(type default)
			)
			(layer "F.Fab")
		)
		(pad "1" smd circle
			(at -0.40005 0)
			(size 0 0)
			(layers "F.Cu" "F.Mask" "F.Paste")
			(net "SMB_IO_DEBUG_CARD_SCL")
		)
		(pad "2" smd circle
			(at 0.40005 0)
			(size 0 0)
			(layers "F.Cu" "F.Mask" "F.Paste")
			(net "SMB_SCL")
		)
	)
	(footprint ""
		(layer "F.Cu")
		(at 29.972 -71.247)
		(property "Reference" "ME5"
			(at 0 0 0)
			(layer "F.SilkS")
			(hide yes)
			(effects
				(font
					(size 1.27 1.27)
				)
			)
		)
		(property "Value" ""
			(at 0 0 0)
			(layer "F.Fab")
			(effects
				(font
					(size 1.27 1.27)
				)
			)
		)
		(duplicate_pad_numbers_are_jumpers no)
		(fp_line
			(start 0 -6.999986)
			(end 0 -5.475986)
			(stroke
				(width 0.1524)
				(type default)
			)
			(layer "F.SilkS")
		)
		(fp_line
			(start 0 -1.524)
			(end 0 0)
			(stroke
				(width 0.1524)
				(type default)
			)
			(layer "F.SilkS")
		)
		(fp_line
			(start 0 0)
			(end 1.524 0)
			(stroke
				(width 0.1524)
				(type default)
			)
			(layer "F.SilkS")
		)
		(fp_line
			(start 1.524 -6.999986)
			(end 0 -6.999986)
			(stroke
				(width 0.1524)
				(type default)
			)
			(layer "F.SilkS")
		)
		(fp_line
			(start 5.475986 -6.999986)
			(end 6.999986 -6.999986)
			(stroke
				(width 0.1524)
				(type default)
			)
			(layer "F.SilkS")
		)
		(fp_line
			(start 6.999986 -6.999986)
			(end 6.999986 -5.475986)
			(stroke
				(width 0.1524)
				(type default)
			)
			(layer "F.SilkS")
		)
		(fp_line
			(start 6.999986 -1.524)
			(end 6.999986 0)
			(stroke
				(width 0.1524)
				(type default)
			)
			(layer "F.SilkS")
		)
		(fp_line
			(start 6.999986 0)
			(end 5.475986 0)
			(stroke
				(width 0.1524)
				(type default)
			)
			(layer "F.SilkS")
		)
		(fp_text user "S/N"
			(at 0.843788 -3.065526 0)
			(unlocked yes)
			(layer "F.SilkS")
			(effects
				(font
					(size 1.905 1.4224)
					(thickness 0.1524)
				)
				(justify left)
			)
		)
	)
	(footprint ""
		(layer "F.Cu")
		(at 15.113 -14.986 -90)
		(property "Reference" "R2"
			(at -1.651 0.60833 90)
			(unlocked yes)
			(layer "F.SilkS")
			(effects
				(font
					(size 0.7874 0.5842)
					(thickness 0.1524)
				)
			)
		)
		(property "Value" ""
			(at 0 0 270)
			(layer "F.Fab")
			(effects
				(font
					(size 1.27 1.27)
				)
			)
		)
		(duplicate_pad_numbers_are_jumpers no)
		(fp_line
			(start -0.7874 0.4064)
			(end -0.7874 -0.4064)
			(stroke
				(width 0.1524)
				(type default)
			)
			(layer "F.SilkS")
		)
		(fp_line
			(start 0.7874 0.4064)
			(end -0.7874 0.4064)
			(stroke
				(width 0.1524)
				(type default)
			)
			(layer "F.SilkS")
		)
		(fp_line
			(start -0.7874 -0.4064)
			(end 0.7874 -0.4064)
			(stroke
				(width 0.1524)
				(type default)
			)
			(layer "F.SilkS")
		)
		(fp_line
			(start 0.7874 -0.4064)
			(end 0.7874 0.4064)
			(stroke
				(width 0.1524)
				(type default)
			)
			(layer "F.SilkS")
		)
		(fp_line
			(start -0.67945 0.3048)
			(end -0.67945 -0.305054)
			(stroke
				(width 0.1)
				(type default)
			)
			(layer "F.Fab")
		)
		(fp_line
			(start -0.12065 0.3048)
			(end -0.67945 0.3048)
			(stroke
				(width 0.1)
				(type default)
			)
			(layer "F.Fab")
		)
		(fp_line
			(start 0.120396 0.3048)
			(end 0.120396 0.2794)
			(stroke
				(width 0.1)
				(type default)
			)
			(layer "F.Fab")
		)
		(fp_line
			(start 0.67945 0.3048)
			(end 0.120396 0.3048)
			(stroke
				(width 0.1)
				(type default)
			)
			(layer "F.Fab")
		)
		(fp_line
			(start -0.12065 0.2794)
			(end -0.12065 0.3048)
			(stroke
				(width 0.1)
				(type default)
			)
			(layer "F.Fab")
		)
		(fp_line
			(start 0.120396 0.2794)
			(end -0.12065 0.2794)
			(stroke
				(width 0.1)
				(type default)
			)
			(layer "F.Fab")
		)
		(fp_line
			(start -0.12065 -0.2794)
			(end 0.12065 -0.2794)
			(stroke
				(width 0.1)
				(type default)
			)
			(layer "F.Fab")
		)
		(fp_line
			(start 0.12065 -0.2794)
			(end 0.12065 -0.3048)
			(stroke
				(width 0.1)
				(type default)
			)
			(layer "F.Fab")
		)
		(fp_line
			(start 0.12065 -0.3048)
			(end 0.67945 -0.3048)
			(stroke
				(width 0.1)
				(type default)
			)
			(layer "F.Fab")
		)
		(fp_line
			(start 0.67945 -0.3048)
			(end 0.67945 0.3048)
			(stroke
				(width 0.1)
				(type default)
			)
			(layer "F.Fab")
		)
		(fp_line
			(start -0.67945 -0.305054)
			(end -0.12065 -0.305054)
			(stroke
				(width 0.1)
				(type default)
			)
			(layer "F.Fab")
		)
		(fp_line
			(start -0.12065 -0.305054)
			(end -0.12065 -0.2794)
			(stroke
				(width 0.1)
				(type default)
			)
			(layer "F.Fab")
		)
		(pad "1" smd circle
			(at -0.40005 0 270)
			(size 0 0)
			(layers "F.Cu" "F.Mask" "F.Paste")
			(net "FM_PFR_LED_AMBER_N")
		)
		(pad "2" smd circle
			(at 0.40005 0 270)
			(size 0 0)
			(layers "F.Cu" "F.Mask" "F.Paste")
			(net "FM_PFR_LED_AMBER_R_N")
		)
	)
	(footprint ""
		(layer "F.Cu")
		(at 9.525 -29.083 180)
		(property "Reference" "R10"
			(at -0.254 2.13233 0)
			(unlocked yes)
			(layer "F.SilkS")
			(effects
				(font
					(size 0.7874 0.5842)
					(thickness 0.1524)
				)
			)
		)
		(property "Value" ""
			(at 0 0 180)
			(layer "F.Fab")
			(effects
				(font
					(size 1.27 1.27)
				)
			)
		)
		(duplicate_pad_numbers_are_jumpers no)
		(fp_line
			(start 0.7874 0.4064)
			(end -0.7874 0.4064)
			(stroke
				(width 0.1524)
				(type default)
			)
			(layer "F.SilkS")
		)
		(fp_line
			(start 0.7874 -0.4064)
			(end 0.7874 0.4064)
			(stroke
				(width 0.1524)
				(type default)
			)
			(layer "F.SilkS")
		)
		(fp_line
			(start -0.7874 0.4064)
			(end -0.7874 -0.4064)
			(stroke
				(width 0.1524)
				(type default)
			)
			(layer "F.SilkS")
		)
		(fp_line
			(start -0.7874 -0.4064)
			(end 0.7874 -0.4064)
			(stroke
				(width 0.1524)
				(type default)
			)
			(layer "F.SilkS")
		)
		(fp_line
			(start 0.67945 0.3048)
			(end 0.120396 0.3048)
			(stroke
				(width 0.1)
				(type default)
			)
			(layer "F.Fab")
		)
		(fp_line
			(start 0.67945 -0.3048)
			(end 0.67945 0.3048)
			(stroke
				(width 0.1)
				(type default)
			)
			(layer "F.Fab")
		)
		(fp_line
			(start 0.12065 -0.2794)
			(end 0.12065 -0.3048)
			(stroke
				(width 0.1)
				(type default)
			)
			(layer "F.Fab")
		)
		(fp_line
			(start 0.12065 -0.3048)
			(end 0.67945 -0.3048)
			(stroke
				(width 0.1)
				(type default)
			)
			(layer "F.Fab")
		)
		(fp_line
			(start 0.120396 0.3048)
			(end 0.120396 0.2794)
			(stroke
				(width 0.1)
				(type default)
			)
			(layer "F.Fab")
		)
		(fp_line
			(start 0.120396 0.2794)
			(end -0.12065 0.2794)
			(stroke
				(width 0.1)
				(type default)
			)
			(layer "F.Fab")
		)
		(fp_line
			(start -0.12065 0.3048)
			(end -0.67945 0.3048)
			(stroke
				(width 0.1)
				(type default)
			)
			(layer "F.Fab")
		)
		(fp_line
			(start -0.12065 0.2794)
			(end -0.12065 0.3048)
			(stroke
				(width 0.1)
				(type default)
			)
			(layer "F.Fab")
		)
		(fp_line
			(start -0.12065 -0.2794)
			(end 0.12065 -0.2794)
			(stroke
				(width 0.1)
				(type default)
			)
			(layer "F.Fab")
		)
		(fp_line
			(start -0.12065 -0.305054)
			(end -0.12065 -0.2794)
			(stroke
				(width 0.1)
				(type default)
			)
			(layer "F.Fab")
		)
		(fp_line
			(start -0.67945 0.3048)
			(end -0.67945 -0.305054)
			(stroke
				(width 0.1)
				(type default)
			)
			(layer "F.Fab")
		)
		(fp_line
			(start -0.67945 -0.305054)
			(end -0.12065 -0.305054)
			(stroke
				(width 0.1)
				(type default)
			)
			(layer "F.Fab")
		)
		(pad "1" smd circle
			(at -0.40005 0 180)
			(size 0 0)
			(layers "F.Cu" "F.Mask" "F.Paste")
			(net "P5V_STBY")
		)
		(pad "2" smd circle
			(at 0.40005 0 180)
			(size 0 0)
			(layers "F.Cu" "F.Mask" "F.Paste")
			(net "PWR_LED_R1_N")
		)
	)
	(footprint ""
		(layer "F.Cu")
		(at 3.048 -25.273 180)
		(property "Reference" "R8"
			(at 1.905 -0.02667 0)
			(unlocked yes)
			(layer "F.SilkS")
			(effects
				(font
					(size 0.7874 0.5842)
					(thickness 0.1524)
				)
			)
		)
		(property "Value" ""
			(at 0 0 180)
			(layer "F.Fab")
			(effects
				(font
					(size 1.27 1.27)
				)
			)
		)
		(duplicate_pad_numbers_are_jumpers no)
		(fp_line
			(start 0.7874 0.4064)
			(end -0.7874 0.4064)
			(stroke
				(width 0.1524)
				(type default)
			)
			(layer "F.SilkS")
		)
		(fp_line
			(start 0.7874 -0.4064)
			(end 0.7874 0.4064)
			(stroke
				(width 0.1524)
				(type default)
			)
			(layer "F.SilkS")
		)
		(fp_line
			(start -0.7874 0.4064)
			(end -0.7874 -0.4064)
			(stroke
				(width 0.1524)
				(type default)
			)
			(layer "F.SilkS")
		)
		(fp_line
			(start -0.7874 -0.4064)
			(end 0.7874 -0.4064)
			(stroke
				(width 0.1524)
				(type default)
			)
			(layer "F.SilkS")
		)
		(fp_line
			(start 0.67945 0.3048)
			(end 0.120396 0.3048)
			(stroke
				(width 0.1)
				(type default)
			)
			(layer "F.Fab")
		)
		(fp_line
			(start 0.67945 -0.3048)
			(end 0.67945 0.3048)
			(stroke
				(width 0.1)
				(type default)
			)
			(layer "F.Fab")
		)
		(fp_line
			(start 0.12065 -0.2794)
			(end 0.12065 -0.3048)
			(stroke
				(width 0.1)
				(type default)
			)
			(layer "F.Fab")
		)
		(fp_line
			(start 0.12065 -0.3048)
			(end 0.67945 -0.3048)
			(stroke
				(width 0.1)
				(type default)
			)
			(layer "F.Fab")
		)
		(fp_line
			(start 0.120396 0.3048)
			(end 0.120396 0.2794)
			(stroke
				(width 0.1)
				(type default)
			)
			(layer "F.Fab")
		)
		(fp_line
			(start 0.120396 0.2794)
			(end -0.12065 0.2794)
			(stroke
				(width 0.1)
				(type default)
			)
			(layer "F.Fab")
		)
		(fp_line
			(start -0.12065 0.3048)
			(end -0.67945 0.3048)
			(stroke
				(width 0.1)
				(type default)
			)
			(layer "F.Fab")
		)
		(fp_line
			(start -0.12065 0.2794)
			(end -0.12065 0.3048)
			(stroke
				(width 0.1)
				(type default)
			)
			(layer "F.Fab")
		)
		(fp_line
			(start -0.12065 -0.2794)
			(end 0.12065 -0.2794)
			(stroke
				(width 0.1)
				(type default)
			)
			(layer "F.Fab")
		)
		(fp_line
			(start -0.12065 -0.305054)
			(end -0.12065 -0.2794)
			(stroke
				(width 0.1)
				(type default)
			)
			(layer "F.Fab")
		)
		(fp_line
			(start -0.67945 0.3048)
			(end -0.67945 -0.305054)
			(stroke
				(width 0.1)
				(type default)
			)
			(layer "F.Fab")
		)
		(fp_line
			(start -0.67945 -0.305054)
			(end -0.12065 -0.305054)
			(stroke
				(width 0.1)
				(type default)
			)
			(layer "F.Fab")
		)
		(pad "1" smd circle
			(at -0.40005 0 180)
			(size 0 0)
			(layers "F.Cu" "F.Mask" "F.Paste")
			(net "SYSTEM_FAULT_ID_LED_R1")
		)
		(pad "2" smd circle
			(at 0.40005 0 180)
			(size 0 0)
			(layers "F.Cu" "F.Mask" "F.Paste")
			(net "GND")
		)
	)
	(footprint ""
		(layer "F.Cu")
		(at 21.850096 -77.250036 180)
		(property "Reference" "J1"
			(at 8.007096 -7.553706 0)
			(unlocked yes)
			(layer "F.SilkS")
			(effects
				(font
					(size 0.7874 0.5842)
					(thickness 0.1524)
				)
				(justify left)
			)
		)
		(property "Value" ""
			(at 0 0 180)
			(layer "F.Fab")
			(effects
				(font
					(size 1.27 1.27)
				)
			)
		)
		(duplicate_pad_numbers_are_jumpers no)
		(fp_line
			(start 6.35 7.899908)
			(end 6.35 6.400292)
			(stroke
				(width 0.1524)
				(type default)
			)
			(layer "F.SilkS")
		)
		(fp_line
			(start 6.35 3.400552)
			(end 6.35 5.099812)
			(stroke
				(width 0.1524)
				(type default)
			)
			(layer "F.SilkS")
		)
		(fp_line
			(start 6.35 -1.781048)
			(end 6.35 2.100072)
			(stroke
				(width 0.1524)
				(type default)
			)
			(layer "F.SilkS")
		)
		(fp_line
			(start 6.35 -7.899908)
			(end 6.35 -3.015488)
			(stroke
				(width 0.1524)
				(type default)
			)
			(layer "F.SilkS")
		)
		(fp_line
			(start 5.71754 -7.899908)
			(end 6.35 -7.899908)
			(stroke
				(width 0.1524)
				(type default)
			)
			(layer "F.SilkS")
		)
		(fp_line
			(start -6.35 7.899908)
			(end 6.35 7.899908)
			(stroke
				(width 0.1524)
				(type default)
			)
			(layer "F.SilkS")
		)
		(fp_line
			(start -6.35 6.400292)
			(end -6.35 7.899908)
			(stroke
				(width 0.1524)
				(type default)
			)
			(layer "F.SilkS")
		)
		(fp_line
			(start -6.35 5.099812)
			(end -6.35 3.400552)
			(stroke
				(width 0.1524)
				(type default)
			)
			(layer "F.SilkS")
		)
		(fp_line
			(start -6.35 2.100072)
			(end -6.35 -1.783588)
			(stroke
				(width 0.1524)
				(type default)
			)
			(layer "F.SilkS")
		)
		(fp_line
			(start -6.35 -3.015488)
			(end -6.35 -7.899908)
			(stroke
				(width 0.1524)
				(type default)
			)
			(layer "F.SilkS")
		)
		(fp_line
			(start -6.35 -7.899908)
			(end -5.71754 -7.899908)
			(stroke
				(width 0.1524)
				(type default)
			)
			(layer "F.SilkS")
		)
		(fp_poly
			(pts
				(xy -7.50824 -4.592066) (xy -7.50824 -5.608066) (xy -6.49224 -5.100066)
			)
			(stroke
				(width 0)
				(type default)
			)
			(fill yes)
			(layer "F.SilkS")
		)
		(fp_line
			(start 6.35 7.899908)
			(end -6.35 7.899908)
			(stroke
				(width 0.1)
				(type default)
			)
			(layer "F.Fab")
		)
		(fp_line
			(start 6.35 -7.899908)
			(end 6.35 7.899908)
			(stroke
				(width 0.1)
				(type default)
			)
			(layer "F.Fab")
		)
		(fp_line
			(start -6.35 7.899908)
			(end -6.35 -7.899908)
			(stroke
				(width 0.1)
				(type default)
			)
			(layer "F.Fab")
		)
		(fp_line
			(start -6.35 -7.899908)
			(end 6.35 -7.899908)
			(stroke
				(width 0.1)
				(type default)
			)
			(layer "F.Fab")
		)
		(fp_poly
			(pts
				(xy -7.50824 -4.592066) (xy -7.50824 -5.608066) (xy -6.49224 -5.100066)
			)
			(stroke
				(width 0)
				(type default)
			)
			(fill yes)
			(layer "F.Fab")
		)
		(pad "" np_thru_hole circle
			(at -5.5499 -2.400046)
			(size 1.3208 1.3208)
			(drill 1.3208)
			(layers "*.Cu" "*.Mask")
			(clearance 0.381)
			(thermal_gap 0.381)
		)
		(pad "" np_thru_hole circle
			(at 5.5499 -2.400046)
			(size 1.3208 1.3208)
			(drill 1.3208)
			(layers "*.Cu" "*.Mask")
			(clearance 0.381)
			(thermal_gap 0.381)
		)
		(pad "A1" smd rect
			(at -5.40004 -5.100066)
			(size 0.381 1.3462)
			(layers "F.Cu" "F.Mask" "F.Paste")
			(net "GND")
		)
		(pad "A2" smd rect
			(at -4.800092 -5.100066)
			(size 0.381 1.3462)
			(layers "F.Cu" "F.Mask" "F.Paste")
			(net "GND")
		)
		(pad "A3" smd rect
			(at -4.19989 -5.100066)
			(size 0.381 1.3462)
			(layers "F.Cu" "F.Mask" "F.Paste")
			(net "GND")
		)
		(pad "A4" smd rect
			(at -3.599942 -5.100066)
			(size 0.381 1.3462)
			(layers "F.Cu" "F.Mask" "F.Paste")
			(net "GND")
		)
		(pad "A5" smd rect
			(at -2.999994 -5.100066)
			(size 0.381 1.3462)
			(layers "F.Cu" "F.Mask" "F.Paste")
			(net "P5V_STBY")
		)
		(pad "A6" smd rect
			(at -2.400046 -5.100066)
			(size 0.381 1.3462)
			(layers "F.Cu" "F.Mask" "F.Paste")
			(net "P5V_STBY")
		)
		(pad "A7" smd rect
			(at -1.800098 -5.100066)
			(size 0.381 1.3462)
			(layers "F.Cu" "F.Mask" "F.Paste")
			(net "GND")
		)
		(pad "A8" smd rect
			(at -1.199896 -5.100066)
			(size 0.381 1.3462)
			(layers "F.Cu" "F.Mask" "F.Paste")
			(net "P5V_STBY")
		)
		(pad "A9" smd rect
			(at -0.599948 -5.100066)
			(size 0.381 1.3462)
			(layers "F.Cu" "F.Mask" "F.Paste")
			(net "P5V_STBY")
		)
		(pad "A10" smd rect
			(at 0 -5.100066)
			(size 0.381 1.3462)
			(layers "F.Cu" "F.Mask" "F.Paste")
			(net "GND")
		)
		(pad "A11" smd rect
			(at 0.599948 -5.100066)
			(size 0.381 1.3462)
			(layers "F.Cu" "F.Mask" "F.Paste")
			(net "GND")
		)
		(pad "A12" smd rect
			(at 1.199896 -5.100066)
			(size 0.381 1.3462)
			(layers "F.Cu" "F.Mask" "F.Paste")
			(net "GND")
		)
		(pad "A13" smd rect
			(at 1.800098 -5.100066)
			(size 0.381 1.3462)
			(layers "F.Cu" "F.Mask" "F.Paste")
			(net "GND")
		)
		(pad "A14" smd rect
			(at 2.400046 -5.100066)
			(size 0.381 1.3462)
			(layers "F.Cu" "F.Mask" "F.Paste")
			(net "P5V_STBY")
		)
		(pad "A15" smd rect
			(at 2.999994 -5.100066)
			(size 0.381 1.3462)
			(layers "F.Cu" "F.Mask" "F.Paste")
			(net "P5V_STBY")
		)
		(pad "A16" smd rect
			(at 3.599942 -5.100066)
			(size 0.381 1.3462)
			(layers "F.Cu" "F.Mask" "F.Paste")
			(net "GND")
		)
		(pad "A17" smd rect
			(at 4.19989 -5.100066)
			(size 0.381 1.3462)
			(layers "F.Cu" "F.Mask" "F.Paste")
			(net "P5V_STBY")
		)
		(pad "A18" smd rect
			(at 4.800092 -5.100066)
			(size 0.381 1.3462)
			(layers "F.Cu" "F.Mask" "F.Paste")
			(net "P5V_STBY")
		)
		(pad "A19" smd rect
			(at 5.40004 -5.100066)
			(size 0.381 1.3462)
			(layers "F.Cu" "F.Mask" "F.Paste")
			(net "GND")
		)
		(pad "B1" smd rect
			(at -5.40004 -7.450074)
			(size 0.381 1.3462)
			(layers "F.Cu" "F.Mask" "F.Paste")
			(net "GND")
		)
		(pad "B2" smd rect
			(at -4.800092 -7.450074)
			(size 0.381 1.3462)
			(layers "F.Cu" "F.Mask" "F.Paste")
			(net "USB2_DP")
		)
		(pad "B3" smd rect
			(at -4.19989 -7.450074)
			(size 0.381 1.3462)
			(layers "F.Cu" "F.Mask" "F.Paste")
			(net "USB2_DN")
		)
		(pad "B4" smd rect
			(at -3.599942 -7.450074)
			(size 0.381 1.3462)
			(layers "F.Cu" "F.Mask" "F.Paste")
			(net "GND")
		)
		(pad "B5" smd rect
			(at -2.999994 -7.450074)
			(size 0.381 1.3462)
			(layers "F.Cu" "F.Mask" "F.Paste")
			(net "FM_PFR_LED_AMBER_N")
		)
		(pad "B6" smd rect
			(at -2.400046 -7.450074)
			(size 0.381 1.3462)
			(layers "F.Cu" "F.Mask" "F.Paste")
			(net "FM_PFR_LED_BLUE_N")
		)
		(pad "B7" smd rect
			(at -1.800098 -7.450074)
			(size 0.381 1.3462)
			(layers "F.Cu" "F.Mask" "F.Paste")
			(net "GND")
		)
		(pad "B8" smd rect
			(at -1.199896 -7.450074)
			(size 0.381 1.3462)
			(layers "F.Cu" "F.Mask" "F.Paste")
			(net "RST_SMB_N")
		)
		(pad "B9" smd rect
			(at -0.599948 -7.450074)
			(size 0.381 1.3462)
			(layers "F.Cu" "F.Mask" "F.Paste")
			(net "PRSNT_DBV2_SLIMSAS")
		)
		(pad "B10" smd rect
			(at 0 -7.450074)
			(size 0.381 1.3462)
			(layers "F.Cu" "F.Mask" "F.Paste")
			(net "GND")
		)
		(pad "B11" smd rect
			(at 0.599948 -7.450074)
			(size 0.381 1.3462)
			(layers "F.Cu" "F.Mask" "F.Paste")
			(net "SMB_SWB_SCL")
		)
		(pad "B12" smd rect
			(at 1.199896 -7.450074)
			(size 0.381 1.3462)
			(layers "F.Cu" "F.Mask" "F.Paste")
			(net "SMB_SWB_SDA")
		)
		(pad "B13" smd rect
			(at 1.800098 -7.450074)
			(size 0.381 1.3462)
			(layers "F.Cu" "F.Mask" "F.Paste")
			(net "GND")
		)
		(pad "B14" smd rect
			(at 2.400046 -7.450074)
			(size 0.381 1.3462)
			(layers "F.Cu" "F.Mask" "F.Paste")
			(net "UART_DEBUG_TX")
		)
		(pad "B15" smd rect
			(at 2.999994 -7.450074)
			(size 0.381 1.3462)
			(layers "F.Cu" "F.Mask" "F.Paste")
			(net "UART_DEBUG_RX")
		)
		(pad "B16" smd rect
			(at 3.599942 -7.450074)
			(size 0.381 1.3462)
			(layers "F.Cu" "F.Mask" "F.Paste")
			(net "GND")
		)
		(pad "B17" smd rect
			(at 4.19989 -7.450074)
			(size 0.381 1.3462)
			(layers "F.Cu" "F.Mask" "F.Paste")
			(net "P3V3_STBY")
		)
		(pad "B18" smd rect
			(at 4.800092 -7.450074)
			(size 0.381 1.3462)
			(layers "F.Cu" "F.Mask" "F.Paste")
			(net "P5V_STBY")
		)
		(pad "B19" smd rect
			(at 5.40004 -7.450074)
			(size 0.381 1.3462)
			(layers "F.Cu" "F.Mask" "F.Paste")
			(net "GND")
		)
		(pad "G1" thru_hole circle
			(at 6.225032 5.750052)
			(size 1.0668 1.0668)
			(drill 0.6604)
			(layers "*.Cu" "*.Mask")
			(remove_unused_layers no)
			(net "GND")
			(clearance 0.0508)
			(thermal_gap 0.0508)
		)
		(pad "G2" thru_hole circle
			(at 6.225032 2.750058)
			(size 1.0668 1.0668)
			(drill 0.6604)
			(layers "*.Cu" "*.Mask")
			(remove_unused_layers no)
			(net "GND")
			(clearance 0.0508)
			(thermal_gap 0.0508)
		)
		(pad "G3" thru_hole circle
			(at -6.225032 2.750058)
			(size 1.0668 1.0668)
			(drill 0.6604)
			(layers "*.Cu" "*.Mask")
			(remove_unused_layers no)
			(net "GND")
			(clearance 0.0508)
			(thermal_gap 0.0508)
		)
		(pad "G4" thru_hole circle
			(at -6.225032 5.750052)
			(size 1.0668 1.0668)
			(drill 0.6604)
			(layers "*.Cu" "*.Mask")
			(remove_unused_layers no)
			(net "GND")
			(clearance 0.0508)
			(thermal_gap 0.0508)
		)
		(zone
			(layer "F.Cu")
			(hatch none 0.5)
			(connect_pads
				(clearance 0)
			)
			(min_thickness 0.25)
			(keepout
				(tracks not_allowed)
				(vias allowed)
				(pads allowed)
				(copperpour not_allowed)
				(footprints allowed)
			)
			(placement
				(enabled no)
				(sheetname "")
			)
			(fill
				(thermal_gap 0.5)
				(thermal_bridge_width 0.5)
				(island_removal_mode 0)
			)
			(polygon
				(pts
					(xy 16.12519 -85.149944) (xy 16.12519 -83.584288) (xy 15.125192 -83.584288) (xy 15.125192 -85.149944)
				)
			)
		)
		(zone
			(layer "F.Cu")
			(hatch none 0.5)
			(connect_pads
				(clearance 0)
			)
			(min_thickness 0.25)
			(keepout
				(tracks not_allowed)
				(vias allowed)
				(pads allowed)
				(copperpour not_allowed)
				(footprints allowed)
			)
			(placement
				(enabled no)
				(sheetname "")
			)
			(fill
				(thermal_gap 0.5)
				(thermal_bridge_width 0.5)
				(island_removal_mode 0)
			)
			(polygon
				(pts
					(xy 16.12519 -82.415888) (xy 16.12519 -80.587088) (xy 15.125192 -80.587088) (xy 15.125192 -82.415888)
				)
			)
		)
		(zone
			(layer "F.Cu")
			(hatch none 0.5)
			(connect_pads
				(clearance 0)
			)
			(min_thickness 0.25)
			(keepout
				(tracks not_allowed)
				(vias allowed)
				(pads allowed)
				(copperpour not_allowed)
				(footprints allowed)
			)
			(placement
				(enabled no)
				(sheetname "")
			)
			(fill
				(thermal_gap 0.5)
				(thermal_bridge_width 0.5)
				(island_removal_mode 0)
			)
			(polygon
				(pts
					(xy 28.575 -85.149944) (xy 28.575 -83.584288) (xy 27.575002 -83.584288) (xy 27.575002 -85.149944)
				)
			)
		)
		(zone
			(layer "F.Cu")
			(hatch none 0.5)
			(connect_pads
				(clearance 0)
			)
			(min_thickness 0.25)
			(keepout
				(tracks not_allowed)
				(vias allowed)
				(pads allowed)
				(copperpour not_allowed)
				(footprints allowed)
			)
			(placement
				(enabled no)
				(sheetname "")
			)
			(fill
				(thermal_gap 0.5)
				(thermal_bridge_width 0.5)
				(island_removal_mode 0)
			)
			(polygon
				(pts
					(xy 28.575 -82.415888) (xy 28.575 -80.587088) (xy 27.575002 -80.587088) (xy 27.575002 -82.415888)
				)
			)
		)
		(zone
			(layer "F.Cu")
			(hatch none 0.5)
			(connect_pads
				(clearance 0)
			)
			(min_thickness 0.25)
			(keepout
				(tracks not_allowed)
				(vias allowed)
				(pads allowed)
				(copperpour not_allowed)
				(footprints allowed)
			)
			(placement
				(enabled no)
				(sheetname "")
			)
			(fill
				(thermal_gap 0.5)
				(thermal_bridge_width 0.5)
				(island_removal_mode 0)
			)
			(polygon
				(pts
					(xy 17.524984 -79.44993) (xy 17.524984 -76.05014) (xy 15.125192 -76.05014) (xy 15.125192 -79.44993)
					(xy 15.423896 -79.44993) (xy 15.423896 -79.409036) (xy 15.830296 -79.409036) (xy 15.830296 -79.44993)
				)
			)
		)
		(zone
			(layer "F.Cu")
			(hatch none 0.5)
			(connect_pads
				(clearance 0)
			)
			(min_thickness 0.25)
			(keepout
				(tracks not_allowed)
				(vias allowed)
				(pads allowed)
				(copperpour not_allowed)
				(footprints allowed)
			)
			(placement
				(enabled no)
				(sheetname "")
			)
			(fill
				(thermal_gap 0.5)
				(thermal_bridge_width 0.5)
				(island_removal_mode 0)
			)
			(polygon
				(pts
					(xy 26.175208 -79.44993) (xy 26.175208 -76.05014) (xy 28.575 -76.05014) (xy 28.575 -79.44993) (xy 28.276296 -79.44993)
					(xy 28.276296 -79.409036) (xy 27.869896 -79.409036) (xy 27.869896 -79.44993)
				)
			)
		)
		(zone
			(layers "F.Cu" "B.Cu" "In1.Cu" "In2.Cu")
			(hatch none 0.5)
			(connect_pads
				(clearance 0)
			)
			(min_thickness 0.25)
			(keepout
				(tracks not_allowed)
				(vias allowed)
				(pads allowed)
				(copperpour not_allowed)
				(footprints allowed)
			)
			(placement
				(enabled no)
				(sheetname "")
			)
			(fill
				(thermal_gap 0.5)
				(thermal_bridge_width 0.5)
				(island_removal_mode 0)
			)
			(polygon
				(pts
					(arc
						(start 17.392142 -74.84999)
						(mid 15.20825 -74.84999)
						(end 17.392142 -74.84999)
					)
				)
			)
		)
		(zone
			(layers "F.Cu" "B.Cu" "In1.Cu" "In2.Cu")
			(hatch none 0.5)
			(connect_pads
				(clearance 0)
			)
			(min_thickness 0.25)
			(keepout
				(tracks not_allowed)
				(vias allowed)
				(pads allowed)
				(copperpour not_allowed)
				(footprints allowed)
			)
			(placement
				(enabled no)
				(sheetname "")
			)
			(fill
				(thermal_gap 0.5)
				(thermal_bridge_width 0.5)
				(island_removal_mode 0)
			)
			(polygon
				(pts
					(arc
						(start 28.49245 -74.84999)
						(mid 26.307542 -74.84999)
						(end 28.49245 -74.84999)
					)
				)
			)
		)
	)
	(footprint ""
		(layer "F.Cu")
		(at 88.146382 -62.918086 180)
		(property "Reference" "J3"
			(at 2.548382 2.079244 0)
			(unlocked yes)
			(layer "F.SilkS")
			(effects
				(font
					(size 0.7874 0.5842)
					(thickness 0.1524)
				)
				(justify left)
			)
		)
		(property "Value" ""
			(at 0 0 180)
			(layer "F.Fab")
			(effects
				(font
					(size 1.27 1.27)
				)
			)
		)
		(duplicate_pad_numbers_are_jumpers no)
		(fp_line
			(start 3.330702 -4.771136)
			(end 0 4.011168)
			(stroke
				(width 0.1524)
				(type default)
			)
			(layer "F.SilkS")
		)
		(fp_line
			(start 0 4.011168)
			(end -3.330702 -4.771136)
			(stroke
				(width 0.1524)
				(type default)
			)
			(layer "F.SilkS")
		)
		(fp_line
			(start -3.330702 -4.771136)
			(end 3.330702 -4.771136)
			(stroke
				(width 0.1524)
				(type default)
			)
			(layer "F.SilkS")
		)
		(fp_line
			(start 3.330702 -4.771136)
			(end 0 4.011168)
			(stroke
				(width 0.1)
				(type default)
			)
			(layer "F.Fab")
		)
		(fp_line
			(start 0 4.011168)
			(end -3.330702 -4.771136)
			(stroke
				(width 0.1)
				(type default)
			)
			(layer "F.Fab")
		)
		(fp_line
			(start -3.330702 -4.771136)
			(end 3.330702 -4.771136)
			(stroke
				(width 0.1)
				(type default)
			)
			(layer "F.Fab")
		)
		(pad "1" thru_hole circle
			(at 0 0 180)
			(size 2.159 2.159)
			(drill 1.7018)
			(layers "*.Cu" "*.Mask")
			(remove_unused_layers no)
			(net "GND_TDR")
			(clearance 0.0254)
			(thermal_gap 0.0254)
		)
		(pad "2" thru_hole circle
			(at -1.27 -3.348736 180)
			(size 2.159 2.159)
			(drill 1.7018)
			(layers "*.Cu" "*.Mask")
			(remove_unused_layers no)
			(net "TDR_SE_50_OHM_TOP")
			(clearance 0.0254)
			(thermal_gap 0.0254)
		)
		(pad "3" thru_hole circle
			(at 1.27 -3.348736 180)
			(size 2.159 2.159)
			(drill 1.7018)
			(layers "*.Cu" "*.Mask")
			(remove_unused_layers no)
			(net "TDR_SE_50_OHM_TOP")
			(clearance 0.0254)
			(thermal_gap 0.0254)
		)
	)
	(footprint ""
		(layer "F.Cu")
		(at 15.875 -47.117 180)
		(property "Reference" "R59"
			(at -2.54 -0.02667 0)
			(unlocked yes)
			(layer "F.SilkS")
			(effects
				(font
					(size 0.7874 0.5842)
					(thickness 0.1524)
				)
			)
		)
		(property "Value" ""
			(at 0 0 180)
			(layer "F.Fab")
			(effects
				(font
					(size 1.27 1.27)
				)
			)
		)
		(duplicate_pad_numbers_are_jumpers no)
		(fp_line
			(start 0.7874 0.4064)
			(end -0.7874 0.4064)
			(stroke
				(width 0.1524)
				(type default)
			)
			(layer "F.SilkS")
		)
		(fp_line
			(start 0.7874 -0.4064)
			(end 0.7874 0.4064)
			(stroke
				(width 0.1524)
				(type default)
			)
			(layer "F.SilkS")
		)
		(fp_line
			(start -0.7874 0.4064)
			(end -0.7874 -0.4064)
			(stroke
				(width 0.1524)
				(type default)
			)
			(layer "F.SilkS")
		)
		(fp_line
			(start -0.7874 -0.4064)
			(end 0.7874 -0.4064)
			(stroke
				(width 0.1524)
				(type default)
			)
			(layer "F.SilkS")
		)
		(fp_line
			(start 0.67945 0.3048)
			(end 0.120396 0.3048)
			(stroke
				(width 0.1)
				(type default)
			)
			(layer "F.Fab")
		)
		(fp_line
			(start 0.67945 -0.3048)
			(end 0.67945 0.3048)
			(stroke
				(width 0.1)
				(type default)
			)
			(layer "F.Fab")
		)
		(fp_line
			(start 0.12065 -0.2794)
			(end 0.12065 -0.3048)
			(stroke
				(width 0.1)
				(type default)
			)
			(layer "F.Fab")
		)
		(fp_line
			(start 0.12065 -0.3048)
			(end 0.67945 -0.3048)
			(stroke
				(width 0.1)
				(type default)
			)
			(layer "F.Fab")
		)
		(fp_line
			(start 0.120396 0.3048)
			(end 0.120396 0.2794)
			(stroke
				(width 0.1)
				(type default)
			)
			(layer "F.Fab")
		)
		(fp_line
			(start 0.120396 0.2794)
			(end -0.12065 0.2794)
			(stroke
				(width 0.1)
				(type default)
			)
			(layer "F.Fab")
		)
		(fp_line
			(start -0.12065 0.3048)
			(end -0.67945 0.3048)
			(stroke
				(width 0.1)
				(type default)
			)
			(layer "F.Fab")
		)
		(fp_line
			(start -0.12065 0.2794)
			(end -0.12065 0.3048)
			(stroke
				(width 0.1)
				(type default)
			)
			(layer "F.Fab")
		)
		(fp_line
			(start -0.12065 -0.2794)
			(end 0.12065 -0.2794)
			(stroke
				(width 0.1)
				(type default)
			)
			(layer "F.Fab")
		)
		(fp_line
			(start -0.12065 -0.305054)
			(end -0.12065 -0.2794)
			(stroke
				(width 0.1)
				(type default)
			)
			(layer "F.Fab")
		)
		(fp_line
			(start -0.67945 0.3048)
			(end -0.67945 -0.305054)
			(stroke
				(width 0.1)
				(type default)
			)
			(layer "F.Fab")
		)
		(fp_line
			(start -0.67945 -0.305054)
			(end -0.12065 -0.305054)
			(stroke
				(width 0.1)
				(type default)
			)
			(layer "F.Fab")
		)
		(pad "1" smd circle
			(at -0.40005 0 180)
			(size 0 0)
			(layers "F.Cu" "F.Mask" "F.Paste")
			(net "SMB_SCL")
		)
		(pad "2" smd circle
			(at 0.40005 0 180)
			(size 0 0)
			(layers "F.Cu" "F.Mask" "F.Paste")
			(net "SMB_FRU_SCL")
		)
	)
	(footprint ""
		(layer "F.Cu")
		(at -77.343 -64.0842 90)
		(property "Reference" "ME7"
			(at 0 0 90)
			(layer "F.SilkS")
			(hide yes)
			(effects
				(font
					(size 1.27 1.27)
				)
			)
		)
		(property "Value" ""
			(at 0 0 90)
			(layer "F.Fab")
			(effects
				(font
					(size 1.27 1.27)
				)
			)
		)
		(duplicate_pad_numbers_are_jumpers no)
	)
	(footprint ""
		(layer "F.Cu")
		(at 13.081 -24.384 90)
		(property "Reference" "Q1"
			(at -1.524 1.80467 90)
			(unlocked yes)
			(layer "F.SilkS")
			(effects
				(font
					(size 0.7874 0.5842)
					(thickness 0.1524)
				)
				(justify left)
			)
		)
		(property "Value" ""
			(at 0 0 90)
			(layer "F.Fab")
			(effects
				(font
					(size 1.27 1.27)
				)
			)
		)
		(duplicate_pad_numbers_are_jumpers no)
		(fp_line
			(start 1.38176 -1.100074)
			(end 0.592074 -1.100074)
			(stroke
				(width 0.1524)
				(type default)
			)
			(layer "F.SilkS")
		)
		(fp_line
			(start 0.592074 -1.100074)
			(end 0 -0.508)
			(stroke
				(width 0.1524)
				(type default)
			)
			(layer "F.SilkS")
		)
		(fp_line
			(start -0.592074 -1.100074)
			(end -1.38176 -1.100074)
			(stroke
				(width 0.1524)
				(type default)
			)
			(layer "F.SilkS")
		)
		(fp_line
			(start -1.38176 -1.100074)
			(end -1.38176 1.100074)
			(stroke
				(width 0.1524)
				(type default)
			)
			(layer "F.SilkS")
		)
		(fp_line
			(start 0 -0.508)
			(end -0.592074 -1.100074)
			(stroke
				(width 0.1524)
				(type default)
			)
			(layer "F.SilkS")
		)
		(fp_line
			(start 1.38176 1.100074)
			(end 1.38176 -1.100074)
			(stroke
				(width 0.1524)
				(type default)
			)
			(layer "F.SilkS")
		)
		(fp_line
			(start -1.38176 1.100074)
			(end 1.38176 1.100074)
			(stroke
				(width 0.1524)
				(type default)
			)
			(layer "F.SilkS")
		)
		(fp_poly
			(pts
				(xy -0.780796 -1.6891) (xy -1.001014 -1.24841) (xy -1.221232 -1.6891)
			)
			(stroke
				(width 0)
				(type default)
			)
			(fill yes)
			(layer "F.SilkS")
		)
		(fp_line
			(start 0.674878 -1.100074)
			(end -0.674878 -1.100074)
			(stroke
				(width 0.1)
				(type default)
			)
			(layer "F.Fab")
		)
		(fp_line
			(start -0.674878 -1.100074)
			(end -0.674878 1.100074)
			(stroke
				(width 0.1)
				(type default)
			)
			(layer "F.Fab")
		)
		(fp_line
			(start 0.674878 1.100074)
			(end 0.674878 -1.100074)
			(stroke
				(width 0.1)
				(type default)
			)
			(layer "F.Fab")
		)
		(fp_line
			(start -0.674878 1.100074)
			(end 0.674878 1.100074)
			(stroke
				(width 0.1)
				(type default)
			)
			(layer "F.Fab")
		)
		(fp_poly
			(pts
				(xy -1.9431 -0.870204) (xy -1.50241 -0.649986) (xy -1.9431 -0.429768)
			)
			(stroke
				(width 0)
				(type default)
			)
			(fill yes)
			(layer "F.Fab")
		)
		(pad "1" smd rect
			(at -0.94996 -0.649986)
			(size 0.4318 0.6096)
			(layers "F.Cu" "F.Mask" "F.Paste")
			(net "GND")
		)
		(pad "2" smd rect
			(at -0.94996 0)
			(size 0.4318 0.6096)
			(layers "F.Cu" "F.Mask" "F.Paste")
			(net "PRSNT_DBV2_USB")
		)
		(pad "3" smd rect
			(at -0.94996 0.649986)
			(size 0.4318 0.6096)
			(layers "F.Cu" "F.Mask" "F.Paste")
			(net "PRSNT_DBV2_SLIMSAS")
		)
		(pad "4" smd rect
			(at 0.94996 0.649986)
			(size 0.4318 0.6096)
			(layers "F.Cu" "F.Mask" "F.Paste")
			(net "GND")
		)
		(pad "5" smd rect
			(at 0.94996 0)
			(size 0.4318 0.6096)
			(layers "F.Cu" "F.Mask" "F.Paste")
			(net "PRSNT_DBV2_USB_N")
		)
		(pad "6" smd rect
			(at 0.94996 -0.649986)
			(size 0.4318 0.6096)
			(layers "F.Cu" "F.Mask" "F.Paste")
			(net "PRSNT_DBV2_USB_N")
		)
	)
	(footprint ""
		(layer "F.Cu")
		(at 12.954 -76.454)
		(property "Reference" ""
			(at 0 0 0)
			(layer "F.SilkS")
			(hide yes)
			(effects
				(font
					(size 1.27 1.27)
				)
			)
		)
		(property "Value" ""
			(at 0 0 0)
			(layer "F.Fab")
			(effects
				(font
					(size 1.27 1.27)
				)
			)
		)
		(duplicate_pad_numbers_are_jumpers no)
		(pad "1" smd circle
			(at 0 0)
			(size 0.9906 0.9906)
			(layers "F.Cu" "F.Mask" "F.Paste")
			(net "Net_75")
		)
		(zone
			(layer "F.Cu")
			(hatch none 0.5)
			(connect_pads
				(clearance 0)
			)
			(min_thickness 0.25)
			(keepout
				(tracks not_allowed)
				(vias allowed)
				(pads allowed)
				(copperpour not_allowed)
				(footprints allowed)
			)
			(placement
				(enabled no)
				(sheetname "")
			)
			(fill
				(thermal_gap 0.5)
				(thermal_bridge_width 0.5)
				(island_removal_mode 0)
			)
			(polygon
				(pts
					(arc
						(start 14.5796 -76.454)
						(mid 11.3284 -76.454)
						(end 14.5796 -76.454)
					)
				)
			)
		)
	)
	(footprint ""
		(layer "F.Cu")
		(at 87.613998 -23.298912)
		(property "Reference" "J4"
			(at -3.031998 1.354582 0)
			(unlocked yes)
			(layer "F.SilkS")
			(effects
				(font
					(size 0.7874 0.5842)
					(thickness 0.1524)
				)
				(justify left)
			)
		)
		(property "Value" ""
			(at 0 0 0)
			(layer "F.Fab")
			(effects
				(font
					(size 1.27 1.27)
				)
			)
		)
		(duplicate_pad_numbers_are_jumpers no)
		(fp_line
			(start -3.330702 -4.771136)
			(end 3.330702 -4.771136)
			(stroke
				(width 0.1524)
				(type default)
			)
			(layer "F.SilkS")
		)
		(fp_line
			(start 0 4.011168)
			(end -3.330702 -4.771136)
			(stroke
				(width 0.1524)
				(type default)
			)
			(layer "F.SilkS")
		)
		(fp_line
			(start 3.330702 -4.771136)
			(end 0 4.011168)
			(stroke
				(width 0.1524)
				(type default)
			)
			(layer "F.SilkS")
		)
		(fp_line
			(start -3.330702 -4.771136)
			(end 3.330702 -4.771136)
			(stroke
				(width 0.1)
				(type default)
			)
			(layer "F.Fab")
		)
		(fp_line
			(start 0 4.011168)
			(end -3.330702 -4.771136)
			(stroke
				(width 0.1)
				(type default)
			)
			(layer "F.Fab")
		)
		(fp_line
			(start 3.330702 -4.771136)
			(end 0 4.011168)
			(stroke
				(width 0.1)
				(type default)
			)
			(layer "F.Fab")
		)
		(pad "1" thru_hole circle
			(at 0 0)
			(size 2.159 2.159)
			(drill 1.7018)
			(layers "*.Cu" "*.Mask")
			(remove_unused_layers no)
			(net "GND_TDR")
			(clearance 0.0254)
			(thermal_gap 0.0254)
		)
		(pad "2" thru_hole circle
			(at -1.27 -3.348736)
			(size 2.159 2.159)
			(drill 1.7018)
			(layers "*.Cu" "*.Mask")
			(remove_unused_layers no)
			(net "TDR_SE_50_OHM_BOT")
			(clearance 0.0254)
			(thermal_gap 0.0254)
		)
		(pad "3" thru_hole circle
			(at 1.27 -3.348736)
			(size 2.159 2.159)
			(drill 1.7018)
			(layers "*.Cu" "*.Mask")
			(remove_unused_layers no)
			(net "TDR_SE_50_OHM_BOT")
			(clearance 0.0254)
			(thermal_gap 0.0254)
		)
	)
	(footprint ""
		(layer "F.Cu")
		(at 36.703 -23.368 180)
		(property "Reference" "R34"
			(at 2.032 -0.02667 0)
			(unlocked yes)
			(layer "F.SilkS")
			(effects
				(font
					(size 0.7874 0.5842)
					(thickness 0.1524)
				)
			)
		)
		(property "Value" ""
			(at 0 0 180)
			(layer "F.Fab")
			(effects
				(font
					(size 1.27 1.27)
				)
			)
		)
		(duplicate_pad_numbers_are_jumpers no)
		(fp_line
			(start 0.7874 0.4064)
			(end -0.7874 0.4064)
			(stroke
				(width 0.1524)
				(type default)
			)
			(layer "F.SilkS")
		)
		(fp_line
			(start 0.7874 -0.4064)
			(end 0.7874 0.4064)
			(stroke
				(width 0.1524)
				(type default)
			)
			(layer "F.SilkS")
		)
		(fp_line
			(start -0.7874 0.4064)
			(end -0.7874 -0.4064)
			(stroke
				(width 0.1524)
				(type default)
			)
			(layer "F.SilkS")
		)
		(fp_line
			(start -0.7874 -0.4064)
			(end 0.7874 -0.4064)
			(stroke
				(width 0.1524)
				(type default)
			)
			(layer "F.SilkS")
		)
		(fp_line
			(start 0.67945 0.3048)
			(end 0.120396 0.3048)
			(stroke
				(width 0.1)
				(type default)
			)
			(layer "F.Fab")
		)
		(fp_line
			(start 0.67945 -0.3048)
			(end 0.67945 0.3048)
			(stroke
				(width 0.1)
				(type default)
			)
			(layer "F.Fab")
		)
		(fp_line
			(start 0.12065 -0.2794)
			(end 0.12065 -0.3048)
			(stroke
				(width 0.1)
				(type default)
			)
			(layer "F.Fab")
		)
		(fp_line
			(start 0.12065 -0.3048)
			(end 0.67945 -0.3048)
			(stroke
				(width 0.1)
				(type default)
			)
			(layer "F.Fab")
		)
		(fp_line
			(start 0.120396 0.3048)
			(end 0.120396 0.2794)
			(stroke
				(width 0.1)
				(type default)
			)
			(layer "F.Fab")
		)
		(fp_line
			(start 0.120396 0.2794)
			(end -0.12065 0.2794)
			(stroke
				(width 0.1)
				(type default)
			)
			(layer "F.Fab")
		)
		(fp_line
			(start -0.12065 0.3048)
			(end -0.67945 0.3048)
			(stroke
				(width 0.1)
				(type default)
			)
			(layer "F.Fab")
		)
		(fp_line
			(start -0.12065 0.2794)
			(end -0.12065 0.3048)
			(stroke
				(width 0.1)
				(type default)
			)
			(layer "F.Fab")
		)
		(fp_line
			(start -0.12065 -0.2794)
			(end 0.12065 -0.2794)
			(stroke
				(width 0.1)
				(type default)
			)
			(layer "F.Fab")
		)
		(fp_line
			(start -0.12065 -0.305054)
			(end -0.12065 -0.2794)
			(stroke
				(width 0.1)
				(type default)
			)
			(layer "F.Fab")
		)
		(fp_line
			(start -0.67945 0.3048)
			(end -0.67945 -0.305054)
			(stroke
				(width 0.1)
				(type default)
			)
			(layer "F.Fab")
		)
		(fp_line
			(start -0.67945 -0.305054)
			(end -0.12065 -0.305054)
			(stroke
				(width 0.1)
				(type default)
			)
			(layer "F.Fab")
		)
		(pad "1" smd circle
			(at -0.40005 0 180)
			(size 0 0)
			(layers "F.Cu" "F.Mask" "F.Paste")
			(net "P3V3_STBY")
		)
		(pad "2" smd circle
			(at 0.40005 0 180)
			(size 0 0)
			(layers "F.Cu" "F.Mask" "F.Paste")
			(net "THERMAL_ADDR_A2")
		)
	)
	(footprint ""
		(layer "F.Cu")
		(at 36.703 -20.32)
		(property "Reference" "R37"
			(at -2.032 0.02667 0)
			(unlocked yes)
			(layer "F.SilkS")
			(effects
				(font
					(size 0.7874 0.5842)
					(thickness 0.1524)
				)
			)
		)
		(property "Value" ""
			(at 0 0 0)
			(layer "F.Fab")
			(effects
				(font
					(size 1.27 1.27)
				)
			)
		)
		(duplicate_pad_numbers_are_jumpers no)
		(fp_line
			(start -0.7874 -0.4064)
			(end 0.7874 -0.4064)
			(stroke
				(width 0.1524)
				(type default)
			)
			(layer "F.SilkS")
		)
		(fp_line
			(start -0.7874 0.4064)
			(end -0.7874 -0.4064)
			(stroke
				(width 0.1524)
				(type default)
			)
			(layer "F.SilkS")
		)
		(fp_line
			(start 0.7874 -0.4064)
			(end 0.7874 0.4064)
			(stroke
				(width 0.1524)
				(type default)
			)
			(layer "F.SilkS")
		)
		(fp_line
			(start 0.7874 0.4064)
			(end -0.7874 0.4064)
			(stroke
				(width 0.1524)
				(type default)
			)
			(layer "F.SilkS")
		)
		(fp_line
			(start -0.67945 -0.305054)
			(end -0.12065 -0.305054)
			(stroke
				(width 0.1)
				(type default)
			)
			(layer "F.Fab")
		)
		(fp_line
			(start -0.67945 0.3048)
			(end -0.67945 -0.305054)
			(stroke
				(width 0.1)
				(type default)
			)
			(layer "F.Fab")
		)
		(fp_line
			(start -0.12065 -0.305054)
			(end -0.12065 -0.2794)
			(stroke
				(width 0.1)
				(type default)
			)
			(layer "F.Fab")
		)
		(fp_line
			(start -0.12065 -0.2794)
			(end 0.12065 -0.2794)
			(stroke
				(width 0.1)
				(type default)
			)
			(layer "F.Fab")
		)
		(fp_line
			(start -0.12065 0.2794)
			(end -0.12065 0.3048)
			(stroke
				(width 0.1)
				(type default)
			)
			(layer "F.Fab")
		)
		(fp_line
			(start -0.12065 0.3048)
			(end -0.67945 0.3048)
			(stroke
				(width 0.1)
				(type default)
			)
			(layer "F.Fab")
		)
		(fp_line
			(start 0.120396 0.2794)
			(end -0.12065 0.2794)
			(stroke
				(width 0.1)
				(type default)
			)
			(layer "F.Fab")
		)
		(fp_line
			(start 0.120396 0.3048)
			(end 0.120396 0.2794)
			(stroke
				(width 0.1)
				(type default)
			)
			(layer "F.Fab")
		)
		(fp_line
			(start 0.12065 -0.3048)
			(end 0.67945 -0.3048)
			(stroke
				(width 0.1)
				(type default)
			)
			(layer "F.Fab")
		)
		(fp_line
			(start 0.12065 -0.2794)
			(end 0.12065 -0.3048)
			(stroke
				(width 0.1)
				(type default)
			)
			(layer "F.Fab")
		)
		(fp_line
			(start 0.67945 -0.3048)
			(end 0.67945 0.3048)
			(stroke
				(width 0.1)
				(type default)
			)
			(layer "F.Fab")
		)
		(fp_line
			(start 0.67945 0.3048)
			(end 0.120396 0.3048)
			(stroke
				(width 0.1)
				(type default)
			)
			(layer "F.Fab")
		)
		(pad "1" smd circle
			(at -0.40005 0)
			(size 0 0)
			(layers "F.Cu" "F.Mask" "F.Paste")
			(net "THERMAL_ADDR_A0")
		)
		(pad "2" smd circle
			(at 0.40005 0)
			(size 0 0)
			(layers "F.Cu" "F.Mask" "F.Paste")
			(net "GND")
		)
	)
	(footprint ""
		(layer "F.Cu")
		(at 32.385 -32.385 180)
		(property "Reference" "C15"
			(at 1.016 8.10133 0)
			(unlocked yes)
			(layer "F.SilkS")
			(effects
				(font
					(size 0.7874 0.5842)
					(thickness 0.1524)
				)
				(justify left)
			)
		)
		(property "Value" ""
			(at 0 0 180)
			(layer "F.Fab")
			(effects
				(font
					(size 1.27 1.27)
				)
			)
		)
		(duplicate_pad_numbers_are_jumpers no)
		(fp_line
			(start 1.524 0.762)
			(end -1.524 0.762)
			(stroke
				(width 0.1524)
				(type default)
			)
			(layer "F.SilkS")
		)
		(fp_line
			(start 1.524 -0.762)
			(end 1.524 0.762)
			(stroke
				(width 0.1524)
				(type default)
			)
			(layer "F.SilkS")
		)
		(fp_line
			(start -1.524 0.762)
			(end -1.524 -0.762)
			(stroke
				(width 0.1524)
				(type default)
			)
			(layer "F.SilkS")
		)
		(fp_line
			(start -1.524 -0.762)
			(end 1.524 -0.762)
			(stroke
				(width 0.1524)
				(type default)
			)
			(layer "F.SilkS")
		)
		(fp_line
			(start 1.1049 0.724916)
			(end 1.1049 -0.724916)
			(stroke
				(width 0.1)
				(type default)
			)
			(layer "F.Fab")
		)
		(fp_line
			(start 1.1049 -0.724916)
			(end -1.1049 -0.724916)
			(stroke
				(width 0.1)
				(type default)
			)
			(layer "F.Fab")
		)
		(fp_line
			(start -1.1049 0.724916)
			(end 1.1049 0.724916)
			(stroke
				(width 0.1)
				(type default)
			)
			(layer "F.Fab")
		)
		(fp_line
			(start -1.1049 -0.724916)
			(end -1.1049 0.724916)
			(stroke
				(width 0.1)
				(type default)
			)
			(layer "F.Fab")
		)
		(pad "1" smd rect
			(at -0.889 0)
			(size 1.016 1.27)
			(layers "F.Cu" "F.Mask" "F.Paste")
			(net "P5V_STBY_DEBUG")
		)
		(pad "2" smd rect
			(at 0.889 0)
			(size 1.016 1.27)
			(layers "F.Cu" "F.Mask" "F.Paste")
			(net "GND")
		)
	)
	(footprint ""
		(layer "F.Cu")
		(at 2.98196 -37.505132)
		(property "Reference" "ME6"
			(at 0 0 0)
			(layer "F.SilkS")
			(hide yes)
			(effects
				(font
					(size 1.27 1.27)
				)
			)
		)
		(property "Value" ""
			(at 0 0 0)
			(layer "F.Fab")
			(effects
				(font
					(size 1.27 1.27)
				)
			)
		)
		(duplicate_pad_numbers_are_jumpers no)
		(fp_text user "P/N"
			(at 2.3368 -3.39725 0)
			(unlocked yes)
			(layer "F.SilkS")
			(effects
				(font
					(size 1.905 1.4224)
					(thickness 0.1524)
				)
				(justify left)
			)
		)
	)
	(footprint ""
		(layer "F.Cu")
		(at 3.048 -28.067 180)
		(property "Reference" "R12"
			(at 0.762 2.00533 0)
			(unlocked yes)
			(layer "F.SilkS")
			(effects
				(font
					(size 0.7874 0.5842)
					(thickness 0.1524)
				)
			)
		)
		(property "Value" ""
			(at 0 0 180)
			(layer "F.Fab")
			(effects
				(font
					(size 1.27 1.27)
				)
			)
		)
		(duplicate_pad_numbers_are_jumpers no)
		(fp_line
			(start 0.7874 0.4064)
			(end -0.7874 0.4064)
			(stroke
				(width 0.1524)
				(type default)
			)
			(layer "F.SilkS")
		)
		(fp_line
			(start 0.7874 -0.4064)
			(end 0.7874 0.4064)
			(stroke
				(width 0.1524)
				(type default)
			)
			(layer "F.SilkS")
		)
		(fp_line
			(start -0.7874 0.4064)
			(end -0.7874 -0.4064)
			(stroke
				(width 0.1524)
				(type default)
			)
			(layer "F.SilkS")
		)
		(fp_line
			(start -0.7874 -0.4064)
			(end 0.7874 -0.4064)
			(stroke
				(width 0.1524)
				(type default)
			)
			(layer "F.SilkS")
		)
		(fp_line
			(start 0.67945 0.3048)
			(end 0.120396 0.3048)
			(stroke
				(width 0.1)
				(type default)
			)
			(layer "F.Fab")
		)
		(fp_line
			(start 0.67945 -0.3048)
			(end 0.67945 0.3048)
			(stroke
				(width 0.1)
				(type default)
			)
			(layer "F.Fab")
		)
		(fp_line
			(start 0.12065 -0.2794)
			(end 0.12065 -0.3048)
			(stroke
				(width 0.1)
				(type default)
			)
			(layer "F.Fab")
		)
		(fp_line
			(start 0.12065 -0.3048)
			(end 0.67945 -0.3048)
			(stroke
				(width 0.1)
				(type default)
			)
			(layer "F.Fab")
		)
		(fp_line
			(start 0.120396 0.3048)
			(end 0.120396 0.2794)
			(stroke
				(width 0.1)
				(type default)
			)
			(layer "F.Fab")
		)
		(fp_line
			(start 0.120396 0.2794)
			(end -0.12065 0.2794)
			(stroke
				(width 0.1)
				(type default)
			)
			(layer "F.Fab")
		)
		(fp_line
			(start -0.12065 0.3048)
			(end -0.67945 0.3048)
			(stroke
				(width 0.1)
				(type default)
			)
			(layer "F.Fab")
		)
		(fp_line
			(start -0.12065 0.2794)
			(end -0.12065 0.3048)
			(stroke
				(width 0.1)
				(type default)
			)
			(layer "F.Fab")
		)
		(fp_line
			(start -0.12065 -0.2794)
			(end 0.12065 -0.2794)
			(stroke
				(width 0.1)
				(type default)
			)
			(layer "F.Fab")
		)
		(fp_line
			(start -0.12065 -0.305054)
			(end -0.12065 -0.2794)
			(stroke
				(width 0.1)
				(type default)
			)
			(layer "F.Fab")
		)
		(fp_line
			(start -0.67945 0.3048)
			(end -0.67945 -0.305054)
			(stroke
				(width 0.1)
				(type default)
			)
			(layer "F.Fab")
		)
		(fp_line
			(start -0.67945 -0.305054)
			(end -0.12065 -0.305054)
			(stroke
				(width 0.1)
				(type default)
			)
			(layer "F.Fab")
		)
		(pad "1" smd circle
			(at -0.40005 0 180)
			(size 0 0)
			(layers "F.Cu" "F.Mask" "F.Paste")
			(net "PWR_LED_R1")
		)
		(pad "2" smd circle
			(at 0.40005 0 180)
			(size 0 0)
			(layers "F.Cu" "F.Mask" "F.Paste")
			(net "GND")
		)
	)
	(footprint ""
		(layer "F.Cu")
		(at 36.703 -22.352)
		(property "Reference" "R38"
			(at -2.032 0.02667 0)
			(unlocked yes)
			(layer "F.SilkS")
			(effects
				(font
					(size 0.7874 0.5842)
					(thickness 0.1524)
				)
			)
		)
		(property "Value" ""
			(at 0 0 0)
			(layer "F.Fab")
			(effects
				(font
					(size 1.27 1.27)
				)
			)
		)
		(duplicate_pad_numbers_are_jumpers no)
		(fp_line
			(start -0.7874 -0.4064)
			(end 0.7874 -0.4064)
			(stroke
				(width 0.1524)
				(type default)
			)
			(layer "F.SilkS")
		)
		(fp_line
			(start -0.7874 0.4064)
			(end -0.7874 -0.4064)
			(stroke
				(width 0.1524)
				(type default)
			)
			(layer "F.SilkS")
		)
		(fp_line
			(start 0.7874 -0.4064)
			(end 0.7874 0.4064)
			(stroke
				(width 0.1524)
				(type default)
			)
			(layer "F.SilkS")
		)
		(fp_line
			(start 0.7874 0.4064)
			(end -0.7874 0.4064)
			(stroke
				(width 0.1524)
				(type default)
			)
			(layer "F.SilkS")
		)
		(fp_line
			(start -0.67945 -0.305054)
			(end -0.12065 -0.305054)
			(stroke
				(width 0.1)
				(type default)
			)
			(layer "F.Fab")
		)
		(fp_line
			(start -0.67945 0.3048)
			(end -0.67945 -0.305054)
			(stroke
				(width 0.1)
				(type default)
			)
			(layer "F.Fab")
		)
		(fp_line
			(start -0.12065 -0.305054)
			(end -0.12065 -0.2794)
			(stroke
				(width 0.1)
				(type default)
			)
			(layer "F.Fab")
		)
		(fp_line
			(start -0.12065 -0.2794)
			(end 0.12065 -0.2794)
			(stroke
				(width 0.1)
				(type default)
			)
			(layer "F.Fab")
		)
		(fp_line
			(start -0.12065 0.2794)
			(end -0.12065 0.3048)
			(stroke
				(width 0.1)
				(type default)
			)
			(layer "F.Fab")
		)
		(fp_line
			(start -0.12065 0.3048)
			(end -0.67945 0.3048)
			(stroke
				(width 0.1)
				(type default)
			)
			(layer "F.Fab")
		)
		(fp_line
			(start 0.120396 0.2794)
			(end -0.12065 0.2794)
			(stroke
				(width 0.1)
				(type default)
			)
			(layer "F.Fab")
		)
		(fp_line
			(start 0.120396 0.3048)
			(end 0.120396 0.2794)
			(stroke
				(width 0.1)
				(type default)
			)
			(layer "F.Fab")
		)
		(fp_line
			(start 0.12065 -0.3048)
			(end 0.67945 -0.3048)
			(stroke
				(width 0.1)
				(type default)
			)
			(layer "F.Fab")
		)
		(fp_line
			(start 0.12065 -0.2794)
			(end 0.12065 -0.3048)
			(stroke
				(width 0.1)
				(type default)
			)
			(layer "F.Fab")
		)
		(fp_line
			(start 0.67945 -0.3048)
			(end 0.67945 0.3048)
			(stroke
				(width 0.1)
				(type default)
			)
			(layer "F.Fab")
		)
		(fp_line
			(start 0.67945 0.3048)
			(end 0.120396 0.3048)
			(stroke
				(width 0.1)
				(type default)
			)
			(layer "F.Fab")
		)
		(pad "1" smd circle
			(at -0.40005 0)
			(size 0 0)
			(layers "F.Cu" "F.Mask" "F.Paste")
			(net "THERMAL_ADDR_A1")
		)
		(pad "2" smd circle
			(at 0.40005 0)
			(size 0 0)
			(layers "F.Cu" "F.Mask" "F.Paste")
			(net "GND")
		)
	)
	(footprint ""
		(layer "F.Cu")
		(at 17.526 -24.13)
		(property "Reference" "R49"
			(at -0.127 -4.16433 0)
			(unlocked yes)
			(layer "F.SilkS")
			(effects
				(font
					(size 0.7874 0.5842)
					(thickness 0.1524)
				)
			)
		)
		(property "Value" ""
			(at 0 0 0)
			(layer "F.Fab")
			(effects
				(font
					(size 1.27 1.27)
				)
			)
		)
		(duplicate_pad_numbers_are_jumpers no)
		(fp_line
			(start -0.7874 -0.4064)
			(end 0.7874 -0.4064)
			(stroke
				(width 0.1524)
				(type default)
			)
			(layer "F.SilkS")
		)
		(fp_line
			(start -0.7874 0.4064)
			(end -0.7874 -0.4064)
			(stroke
				(width 0.1524)
				(type default)
			)
			(layer "F.SilkS")
		)
		(fp_line
			(start 0.7874 -0.4064)
			(end 0.7874 0.4064)
			(stroke
				(width 0.1524)
				(type default)
			)
			(layer "F.SilkS")
		)
		(fp_line
			(start 0.7874 0.4064)
			(end -0.7874 0.4064)
			(stroke
				(width 0.1524)
				(type default)
			)
			(layer "F.SilkS")
		)
		(fp_line
			(start -0.67945 -0.305054)
			(end -0.12065 -0.305054)
			(stroke
				(width 0.1)
				(type default)
			)
			(layer "F.Fab")
		)
		(fp_line
			(start -0.67945 0.3048)
			(end -0.67945 -0.305054)
			(stroke
				(width 0.1)
				(type default)
			)
			(layer "F.Fab")
		)
		(fp_line
			(start -0.12065 -0.305054)
			(end -0.12065 -0.2794)
			(stroke
				(width 0.1)
				(type default)
			)
			(layer "F.Fab")
		)
		(fp_line
			(start -0.12065 -0.2794)
			(end 0.12065 -0.2794)
			(stroke
				(width 0.1)
				(type default)
			)
			(layer "F.Fab")
		)
		(fp_line
			(start -0.12065 0.2794)
			(end -0.12065 0.3048)
			(stroke
				(width 0.1)
				(type default)
			)
			(layer "F.Fab")
		)
		(fp_line
			(start -0.12065 0.3048)
			(end -0.67945 0.3048)
			(stroke
				(width 0.1)
				(type default)
			)
			(layer "F.Fab")
		)
		(fp_line
			(start 0.120396 0.2794)
			(end -0.12065 0.2794)
			(stroke
				(width 0.1)
				(type default)
			)
			(layer "F.Fab")
		)
		(fp_line
			(start 0.120396 0.3048)
			(end 0.120396 0.2794)
			(stroke
				(width 0.1)
				(type default)
			)
			(layer "F.Fab")
		)
		(fp_line
			(start 0.12065 -0.3048)
			(end 0.67945 -0.3048)
			(stroke
				(width 0.1)
				(type default)
			)
			(layer "F.Fab")
		)
		(fp_line
			(start 0.12065 -0.2794)
			(end 0.12065 -0.3048)
			(stroke
				(width 0.1)
				(type default)
			)
			(layer "F.Fab")
		)
		(fp_line
			(start 0.67945 -0.3048)
			(end 0.67945 0.3048)
			(stroke
				(width 0.1)
				(type default)
			)
			(layer "F.Fab")
		)
		(fp_line
			(start 0.67945 0.3048)
			(end 0.120396 0.3048)
			(stroke
				(width 0.1)
				(type default)
			)
			(layer "F.Fab")
		)
		(pad "1" smd circle
			(at -0.40005 0)
			(size 0 0)
			(layers "F.Cu" "F.Mask" "F.Paste")
			(net "SMB_IO_DEBUG_CARD_SDA")
		)
		(pad "2" smd circle
			(at 0.40005 0)
			(size 0 0)
			(layers "F.Cu" "F.Mask" "F.Paste")
			(net "SMB_SDA")
		)
	)
	(footprint ""
		(layer "F.Cu")
		(at 31.609792 -20.163536 180)
		(property "Reference" "U8"
			(at 2.49555 -0.042418 0)
			(unlocked yes)
			(layer "F.SilkS")
			(effects
				(font
					(size 0.7874 0.5842)
					(thickness 0.1524)
				)
				(justify left)
			)
		)
		(property "Value" ""
			(at 0 0 180)
			(layer "F.Fab")
			(effects
				(font
					(size 1.27 1.27)
				)
			)
		)
		(duplicate_pad_numbers_are_jumpers no)
		(fp_line
			(start 0.517398 1.500124)
			(end -0.517398 1.500124)
			(stroke
				(width 0.1524)
				(type default)
			)
			(layer "F.SilkS")
		)
		(fp_line
			(start 0.517398 -1.500124)
			(end 0.517398 1.500124)
			(stroke
				(width 0.1524)
				(type default)
			)
			(layer "F.SilkS")
		)
		(fp_line
			(start -0.517398 1.500124)
			(end -0.517398 -1.500124)
			(stroke
				(width 0.1524)
				(type default)
			)
			(layer "F.SilkS")
		)
		(fp_line
			(start -0.517398 -1.500124)
			(end 0.517398 -1.500124)
			(stroke
				(width 0.1524)
				(type default)
			)
			(layer "F.SilkS")
		)
		(fp_poly
			(pts
				(xy -0.362966 -1.62814) (xy 0.310642 -1.852422) (xy -0.13843 -2.301494)
			)
			(stroke
				(width 0)
				(type default)
			)
			(fill yes)
			(layer "F.SilkS")
		)
		(fp_line
			(start 0.700024 1.500124)
			(end -0.700024 1.500124)
			(stroke
				(width 0.1)
				(type default)
			)
			(layer "F.Fab")
		)
		(fp_line
			(start 0.700024 -1.500124)
			(end 0.700024 1.500124)
			(stroke
				(width 0.1)
				(type default)
			)
			(layer "F.Fab")
		)
		(fp_line
			(start -0.700024 1.500124)
			(end -0.700024 -1.500124)
			(stroke
				(width 0.1)
				(type default)
			)
			(layer "F.Fab")
		)
		(fp_line
			(start -0.700024 -1.500124)
			(end 0.700024 -1.500124)
			(stroke
				(width 0.1)
				(type default)
			)
			(layer "F.Fab")
		)
		(fp_poly
			(pts
				(xy -1.5113 -0.750062) (xy -2.1463 -1.067562) (xy -2.1463 -0.432562)
			)
			(stroke
				(width 0)
				(type default)
			)
			(fill yes)
			(layer "F.Fab")
		)
		(pad "1" smd rect
			(at -0.999998 -0.750062 180)
			(size 0.7112 1.016)
			(layers "F.Cu" "F.Mask" "F.Paste")
			(net "GND")
		)
		(pad "2" smd rect
			(at -0.999998 0.94996 90)
			(size 0.6096 0.7112)
			(layers "F.Cu" "F.Mask" "F.Paste")
			(net "USB2_DEBUG_DP")
		)
		(pad "3" smd rect
			(at 0.999998 0.94996 90)
			(size 0.6096 0.7112)
			(layers "F.Cu" "F.Mask" "F.Paste")
			(net "USB2_DEBUG_DN")
		)
		(pad "4" smd rect
			(at 0.999998 -0.94996 90)
			(size 0.6096 0.7112)
			(layers "F.Cu" "F.Mask" "F.Paste")
			(net "P5V_STBY_DEBUG")
		)
	)
	(footprint ""
		(layer "F.Cu")
		(at 29.591 -32.004)
		(property "Reference" "C8"
			(at -1.651 0.02667 0)
			(unlocked yes)
			(layer "F.SilkS")
			(effects
				(font
					(size 0.7874 0.5842)
					(thickness 0.1524)
				)
			)
		)
		(property "Value" ""
			(at 0 0 0)
			(layer "F.Fab")
			(effects
				(font
					(size 1.27 1.27)
				)
			)
		)
		(duplicate_pad_numbers_are_jumpers no)
		(fp_line
			(start -0.7874 -0.4064)
			(end 0.7874 -0.4064)
			(stroke
				(width 0.1524)
				(type default)
			)
			(layer "F.SilkS")
		)
		(fp_line
			(start -0.7874 0.4064)
			(end -0.7874 -0.4064)
			(stroke
				(width 0.1524)
				(type default)
			)
			(layer "F.SilkS")
		)
		(fp_line
			(start 0.7874 -0.4064)
			(end 0.7874 0.4064)
			(stroke
				(width 0.1524)
				(type default)
			)
			(layer "F.SilkS")
		)
		(fp_line
			(start 0.7874 0.4064)
			(end -0.7874 0.4064)
			(stroke
				(width 0.1524)
				(type default)
			)
			(layer "F.SilkS")
		)
		(fp_line
			(start -0.67945 -0.305054)
			(end -0.12065 -0.305054)
			(stroke
				(width 0.1)
				(type default)
			)
			(layer "F.Fab")
		)
		(fp_line
			(start -0.67945 0.3048)
			(end -0.67945 -0.305054)
			(stroke
				(width 0.1)
				(type default)
			)
			(layer "F.Fab")
		)
		(fp_line
			(start -0.12065 -0.305054)
			(end -0.12065 -0.2794)
			(stroke
				(width 0.1)
				(type default)
			)
			(layer "F.Fab")
		)
		(fp_line
			(start -0.12065 -0.2794)
			(end 0.12065 -0.2794)
			(stroke
				(width 0.1)
				(type default)
			)
			(layer "F.Fab")
		)
		(fp_line
			(start -0.12065 0.2794)
			(end -0.12065 0.3048)
			(stroke
				(width 0.1)
				(type default)
			)
			(layer "F.Fab")
		)
		(fp_line
			(start -0.12065 0.3048)
			(end -0.67945 0.3048)
			(stroke
				(width 0.1)
				(type default)
			)
			(layer "F.Fab")
		)
		(fp_line
			(start 0.120396 0.2794)
			(end -0.12065 0.2794)
			(stroke
				(width 0.1)
				(type default)
			)
			(layer "F.Fab")
		)
		(fp_line
			(start 0.120396 0.3048)
			(end 0.120396 0.2794)
			(stroke
				(width 0.1)
				(type default)
			)
			(layer "F.Fab")
		)
		(fp_line
			(start 0.12065 -0.3048)
			(end 0.67945 -0.3048)
			(stroke
				(width 0.1)
				(type default)
			)
			(layer "F.Fab")
		)
		(fp_line
			(start 0.12065 -0.2794)
			(end 0.12065 -0.3048)
			(stroke
				(width 0.1)
				(type default)
			)
			(layer "F.Fab")
		)
		(fp_line
			(start 0.67945 -0.3048)
			(end 0.67945 0.3048)
			(stroke
				(width 0.1)
				(type default)
			)
			(layer "F.Fab")
		)
		(fp_line
			(start 0.67945 0.3048)
			(end 0.120396 0.3048)
			(stroke
				(width 0.1)
				(type default)
			)
			(layer "F.Fab")
		)
		(pad "1" smd circle
			(at -0.40005 0)
			(size 0 0)
			(layers "F.Cu" "F.Mask" "F.Paste")
			(net "P5V_STBY")
		)
		(pad "2" smd circle
			(at 0.40005 0)
			(size 0 0)
			(layers "F.Cu" "F.Mask" "F.Paste")
			(net "GND")
		)
	)
	(footprint ""
		(layer "F.Cu")
		(at 35.941 -34.163)
		(property "Reference" "C16"
			(at 0.762 -4.67233 0)
			(unlocked yes)
			(layer "F.SilkS")
			(effects
				(font
					(size 0.7874 0.5842)
					(thickness 0.1524)
				)
				(justify left)
			)
		)
		(property "Value" ""
			(at 0 0 0)
			(layer "F.Fab")
			(effects
				(font
					(size 1.27 1.27)
				)
			)
		)
		(duplicate_pad_numbers_are_jumpers no)
		(fp_line
			(start -1.524 -0.762)
			(end 1.524 -0.762)
			(stroke
				(width 0.1524)
				(type default)
			)
			(layer "F.SilkS")
		)
		(fp_line
			(start -1.524 0.762)
			(end -1.524 -0.762)
			(stroke
				(width 0.1524)
				(type default)
			)
			(layer "F.SilkS")
		)
		(fp_line
			(start 1.524 -0.762)
			(end 1.524 0.762)
			(stroke
				(width 0.1524)
				(type default)
			)
			(layer "F.SilkS")
		)
		(fp_line
			(start 1.524 0.762)
			(end -1.524 0.762)
			(stroke
				(width 0.1524)
				(type default)
			)
			(layer "F.SilkS")
		)
		(fp_line
			(start -1.1049 -0.724916)
			(end -1.1049 0.724916)
			(stroke
				(width 0.1)
				(type default)
			)
			(layer "F.Fab")
		)
		(fp_line
			(start -1.1049 0.724916)
			(end 1.1049 0.724916)
			(stroke
				(width 0.1)
				(type default)
			)
			(layer "F.Fab")
		)
		(fp_line
			(start 1.1049 -0.724916)
			(end -1.1049 -0.724916)
			(stroke
				(width 0.1)
				(type default)
			)
			(layer "F.Fab")
		)
		(fp_line
			(start 1.1049 0.724916)
			(end 1.1049 -0.724916)
			(stroke
				(width 0.1)
				(type default)
			)
			(layer "F.Fab")
		)
		(pad "1" smd rect
			(at -0.889 0 180)
			(size 1.016 1.27)
			(layers "F.Cu" "F.Mask" "F.Paste")
			(net "P5V_STBY_DEBUG")
		)
		(pad "2" smd rect
			(at 0.889 0 180)
			(size 1.016 1.27)
			(layers "F.Cu" "F.Mask" "F.Paste")
			(net "GND")
		)
	)
	(footprint ""
		(layer "F.Cu")
		(at 5.969 -61.341 180)
		(property "Reference" "R19"
			(at 2.667 -0.40767 0)
			(unlocked yes)
			(layer "F.SilkS")
			(effects
				(font
					(size 0.7874 0.5842)
					(thickness 0.1524)
				)
			)
		)
		(property "Value" ""
			(at 0 0 180)
			(layer "F.Fab")
			(effects
				(font
					(size 1.27 1.27)
				)
			)
		)
		(duplicate_pad_numbers_are_jumpers no)
		(fp_line
			(start 0.7874 0.4064)
			(end -0.7874 0.4064)
			(stroke
				(width 0.1524)
				(type default)
			)
			(layer "F.SilkS")
		)
		(fp_line
			(start 0.7874 -0.4064)
			(end 0.7874 0.4064)
			(stroke
				(width 0.1524)
				(type default)
			)
			(layer "F.SilkS")
		)
		(fp_line
			(start -0.7874 0.4064)
			(end -0.7874 -0.4064)
			(stroke
				(width 0.1524)
				(type default)
			)
			(layer "F.SilkS")
		)
		(fp_line
			(start -0.7874 -0.4064)
			(end 0.7874 -0.4064)
			(stroke
				(width 0.1524)
				(type default)
			)
			(layer "F.SilkS")
		)
		(fp_line
			(start 0.67945 0.3048)
			(end 0.120396 0.3048)
			(stroke
				(width 0.1)
				(type default)
			)
			(layer "F.Fab")
		)
		(fp_line
			(start 0.67945 -0.3048)
			(end 0.67945 0.3048)
			(stroke
				(width 0.1)
				(type default)
			)
			(layer "F.Fab")
		)
		(fp_line
			(start 0.12065 -0.2794)
			(end 0.12065 -0.3048)
			(stroke
				(width 0.1)
				(type default)
			)
			(layer "F.Fab")
		)
		(fp_line
			(start 0.12065 -0.3048)
			(end 0.67945 -0.3048)
			(stroke
				(width 0.1)
				(type default)
			)
			(layer "F.Fab")
		)
		(fp_line
			(start 0.120396 0.3048)
			(end 0.120396 0.2794)
			(stroke
				(width 0.1)
				(type default)
			)
			(layer "F.Fab")
		)
		(fp_line
			(start 0.120396 0.2794)
			(end -0.12065 0.2794)
			(stroke
				(width 0.1)
				(type default)
			)
			(layer "F.Fab")
		)
		(fp_line
			(start -0.12065 0.3048)
			(end -0.67945 0.3048)
			(stroke
				(width 0.1)
				(type default)
			)
			(layer "F.Fab")
		)
		(fp_line
			(start -0.12065 0.2794)
			(end -0.12065 0.3048)
			(stroke
				(width 0.1)
				(type default)
			)
			(layer "F.Fab")
		)
		(fp_line
			(start -0.12065 -0.2794)
			(end 0.12065 -0.2794)
			(stroke
				(width 0.1)
				(type default)
			)
			(layer "F.Fab")
		)
		(fp_line
			(start -0.12065 -0.305054)
			(end -0.12065 -0.2794)
			(stroke
				(width 0.1)
				(type default)
			)
			(layer "F.Fab")
		)
		(fp_line
			(start -0.67945 0.3048)
			(end -0.67945 -0.305054)
			(stroke
				(width 0.1)
				(type default)
			)
			(layer "F.Fab")
		)
		(fp_line
			(start -0.67945 -0.305054)
			(end -0.12065 -0.305054)
			(stroke
				(width 0.1)
				(type default)
			)
			(layer "F.Fab")
		)
		(pad "1" smd circle
			(at -0.40005 0 180)
			(size 0 0)
			(layers "F.Cu" "F.Mask" "F.Paste")
			(net "PCA9539_A1")
		)
		(pad "2" smd circle
			(at 0.40005 0 180)
			(size 0 0)
			(layers "F.Cu" "F.Mask" "F.Paste")
			(net "P3V3_STBY")
		)
	)
	(footprint ""
		(layer "F.Cu")
		(at 15.875 -48.133 180)
		(property "Reference" "R53"
			(at -2.54 -0.02667 0)
			(unlocked yes)
			(layer "F.SilkS")
			(effects
				(font
					(size 0.7874 0.5842)
					(thickness 0.1524)
				)
			)
		)
		(property "Value" ""
			(at 0 0 180)
			(layer "F.Fab")
			(effects
				(font
					(size 1.27 1.27)
				)
			)
		)
		(duplicate_pad_numbers_are_jumpers no)
		(fp_line
			(start 0.7874 0.4064)
			(end -0.7874 0.4064)
			(stroke
				(width 0.1524)
				(type default)
			)
			(layer "F.SilkS")
		)
		(fp_line
			(start 0.7874 -0.4064)
			(end 0.7874 0.4064)
			(stroke
				(width 0.1524)
				(type default)
			)
			(layer "F.SilkS")
		)
		(fp_line
			(start -0.7874 0.4064)
			(end -0.7874 -0.4064)
			(stroke
				(width 0.1524)
				(type default)
			)
			(layer "F.SilkS")
		)
		(fp_line
			(start -0.7874 -0.4064)
			(end 0.7874 -0.4064)
			(stroke
				(width 0.1524)
				(type default)
			)
			(layer "F.SilkS")
		)
		(fp_line
			(start 0.67945 0.3048)
			(end 0.120396 0.3048)
			(stroke
				(width 0.1)
				(type default)
			)
			(layer "F.Fab")
		)
		(fp_line
			(start 0.67945 -0.3048)
			(end 0.67945 0.3048)
			(stroke
				(width 0.1)
				(type default)
			)
			(layer "F.Fab")
		)
		(fp_line
			(start 0.12065 -0.2794)
			(end 0.12065 -0.3048)
			(stroke
				(width 0.1)
				(type default)
			)
			(layer "F.Fab")
		)
		(fp_line
			(start 0.12065 -0.3048)
			(end 0.67945 -0.3048)
			(stroke
				(width 0.1)
				(type default)
			)
			(layer "F.Fab")
		)
		(fp_line
			(start 0.120396 0.3048)
			(end 0.120396 0.2794)
			(stroke
				(width 0.1)
				(type default)
			)
			(layer "F.Fab")
		)
		(fp_line
			(start 0.120396 0.2794)
			(end -0.12065 0.2794)
			(stroke
				(width 0.1)
				(type default)
			)
			(layer "F.Fab")
		)
		(fp_line
			(start -0.12065 0.3048)
			(end -0.67945 0.3048)
			(stroke
				(width 0.1)
				(type default)
			)
			(layer "F.Fab")
		)
		(fp_line
			(start -0.12065 0.2794)
			(end -0.12065 0.3048)
			(stroke
				(width 0.1)
				(type default)
			)
			(layer "F.Fab")
		)
		(fp_line
			(start -0.12065 -0.2794)
			(end 0.12065 -0.2794)
			(stroke
				(width 0.1)
				(type default)
			)
			(layer "F.Fab")
		)
		(fp_line
			(start -0.12065 -0.305054)
			(end -0.12065 -0.2794)
			(stroke
				(width 0.1)
				(type default)
			)
			(layer "F.Fab")
		)
		(fp_line
			(start -0.67945 0.3048)
			(end -0.67945 -0.305054)
			(stroke
				(width 0.1)
				(type default)
			)
			(layer "F.Fab")
		)
		(fp_line
			(start -0.67945 -0.305054)
			(end -0.12065 -0.305054)
			(stroke
				(width 0.1)
				(type default)
			)
			(layer "F.Fab")
		)
		(pad "1" smd circle
			(at -0.40005 0 180)
			(size 0 0)
			(layers "F.Cu" "F.Mask" "F.Paste")
			(net "P3V3_STBY")
		)
		(pad "2" smd circle
			(at 0.40005 0 180)
			(size 0 0)
			(layers "F.Cu" "F.Mask" "F.Paste")
			(net "SMB_FRU_SCL")
		)
	)
	(footprint ""
		(layer "F.Cu")
		(at 36.703 -26.416)
		(property "Reference" "R42"
			(at -7.874 -0.35433 0)
			(unlocked yes)
			(layer "F.SilkS")
			(effects
				(font
					(size 0.7874 0.5842)
					(thickness 0.1524)
				)
			)
		)
		(property "Value" ""
			(at 0 0 0)
			(layer "F.Fab")
			(effects
				(font
					(size 1.27 1.27)
				)
			)
		)
		(duplicate_pad_numbers_are_jumpers no)
		(fp_line
			(start -0.7874 -0.4064)
			(end 0.7874 -0.4064)
			(stroke
				(width 0.1524)
				(type default)
			)
			(layer "F.SilkS")
		)
		(fp_line
			(start -0.7874 0.4064)
			(end -0.7874 -0.4064)
			(stroke
				(width 0.1524)
				(type default)
			)
			(layer "F.SilkS")
		)
		(fp_line
			(start 0.7874 -0.4064)
			(end 0.7874 0.4064)
			(stroke
				(width 0.1524)
				(type default)
			)
			(layer "F.SilkS")
		)
		(fp_line
			(start 0.7874 0.4064)
			(end -0.7874 0.4064)
			(stroke
				(width 0.1524)
				(type default)
			)
			(layer "F.SilkS")
		)
		(fp_line
			(start -0.67945 -0.305054)
			(end -0.12065 -0.305054)
			(stroke
				(width 0.1)
				(type default)
			)
			(layer "F.Fab")
		)
		(fp_line
			(start -0.67945 0.3048)
			(end -0.67945 -0.305054)
			(stroke
				(width 0.1)
				(type default)
			)
			(layer "F.Fab")
		)
		(fp_line
			(start -0.12065 -0.305054)
			(end -0.12065 -0.2794)
			(stroke
				(width 0.1)
				(type default)
			)
			(layer "F.Fab")
		)
		(fp_line
			(start -0.12065 -0.2794)
			(end 0.12065 -0.2794)
			(stroke
				(width 0.1)
				(type default)
			)
			(layer "F.Fab")
		)
		(fp_line
			(start -0.12065 0.2794)
			(end -0.12065 0.3048)
			(stroke
				(width 0.1)
				(type default)
			)
			(layer "F.Fab")
		)
		(fp_line
			(start -0.12065 0.3048)
			(end -0.67945 0.3048)
			(stroke
				(width 0.1)
				(type default)
			)
			(layer "F.Fab")
		)
		(fp_line
			(start 0.120396 0.2794)
			(end -0.12065 0.2794)
			(stroke
				(width 0.1)
				(type default)
			)
			(layer "F.Fab")
		)
		(fp_line
			(start 0.120396 0.3048)
			(end 0.120396 0.2794)
			(stroke
				(width 0.1)
				(type default)
			)
			(layer "F.Fab")
		)
		(fp_line
			(start 0.12065 -0.3048)
			(end 0.67945 -0.3048)
			(stroke
				(width 0.1)
				(type default)
			)
			(layer "F.Fab")
		)
		(fp_line
			(start 0.12065 -0.2794)
			(end 0.12065 -0.3048)
			(stroke
				(width 0.1)
				(type default)
			)
			(layer "F.Fab")
		)
		(fp_line
			(start 0.67945 -0.3048)
			(end 0.67945 0.3048)
			(stroke
				(width 0.1)
				(type default)
			)
			(layer "F.Fab")
		)
		(fp_line
			(start 0.67945 0.3048)
			(end 0.120396 0.3048)
			(stroke
				(width 0.1)
				(type default)
			)
			(layer "F.Fab")
		)
		(pad "1" smd circle
			(at -0.40005 0)
			(size 0 0)
			(layers "F.Cu" "F.Mask" "F.Paste")
			(net "NCP380_ILIM")
		)
		(pad "2" smd circle
			(at 0.40005 0)
			(size 0 0)
			(layers "F.Cu" "F.Mask" "F.Paste")
			(net "GND")
		)
	)
	(footprint ""
		(layer "F.Cu")
		(at 9.906 -49.149)
		(property "Reference" "U9"
			(at 0.508 -3.14833 0)
			(unlocked yes)
			(layer "F.SilkS")
			(effects
				(font
					(size 0.7874 0.5842)
					(thickness 0.1524)
				)
				(justify left)
			)
		)
		(property "Value" ""
			(at 0 0 0)
			(layer "F.Fab")
			(effects
				(font
					(size 1.27 1.27)
				)
			)
		)
		(duplicate_pad_numbers_are_jumpers no)
		(fp_line
			(start -1.796796 -2.500122)
			(end -1.796796 2.500122)
			(stroke
				(width 0.1524)
				(type default)
			)
			(layer "F.SilkS")
		)
		(fp_line
			(start -1.796796 2.500122)
			(end 1.796796 2.500122)
			(stroke
				(width 0.1524)
				(type default)
			)
			(layer "F.SilkS")
		)
		(fp_line
			(start -0.976122 -2.500122)
			(end -1.796796 -2.500122)
			(stroke
				(width 0.1524)
				(type default)
			)
			(layer "F.SilkS")
		)
		(fp_line
			(start 0 -1.524)
			(end -0.976122 -2.500122)
			(stroke
				(width 0.1524)
				(type default)
			)
			(layer "F.SilkS")
		)
		(fp_line
			(start 0.976122 -2.500122)
			(end 0 -1.524)
			(stroke
				(width 0.1524)
				(type default)
			)
			(layer "F.SilkS")
		)
		(fp_line
			(start 1.796796 -2.500122)
			(end 0.976122 -2.500122)
			(stroke
				(width 0.1524)
				(type default)
			)
			(layer "F.SilkS")
		)
		(fp_line
			(start 1.796796 2.500122)
			(end 1.796796 -2.500122)
			(stroke
				(width 0.1524)
				(type default)
			)
			(layer "F.SilkS")
		)
		(fp_poly
			(pts
				(xy -1.916176 -3.387852) (xy -2.932176 -3.387852) (xy -2.424176 -2.371852)
			)
			(stroke
				(width 0)
				(type default)
			)
			(fill yes)
			(layer "F.SilkS")
		)
		(fp_line
			(start -1.999996 -2.500122)
			(end -1.999996 2.500122)
			(stroke
				(width 0.1)
				(type default)
			)
			(layer "F.Fab")
		)
		(fp_line
			(start -1.999996 2.500122)
			(end 1.999996 2.500122)
			(stroke
				(width 0.1)
				(type default)
			)
			(layer "F.Fab")
		)
		(fp_line
			(start 1.999996 -2.500122)
			(end -1.999996 -2.500122)
			(stroke
				(width 0.1)
				(type default)
			)
			(layer "F.Fab")
		)
		(fp_line
			(start 1.999996 2.500122)
			(end 1.999996 -2.500122)
			(stroke
				(width 0.1)
				(type default)
			)
			(layer "F.Fab")
		)
		(fp_poly
			(pts
				(xy -4.5974 -2.413) (xy -4.5974 -1.397) (xy -3.5814 -1.905)
			)
			(stroke
				(width 0)
				(type default)
			)
			(fill yes)
			(layer "F.Fab")
		)
		(pad "1" smd rect
			(at -2.649982 -1.905 270)
			(size 0.6096 1.4224)
			(layers "F.Cu" "F.Mask" "F.Paste")
			(net "PD_FRU_A0")
		)
		(pad "2" smd rect
			(at -2.649982 -0.635 270)
			(size 0.6096 1.4224)
			(layers "F.Cu" "F.Mask" "F.Paste")
			(net "PD_FRU_A1")
		)
		(pad "3" smd rect
			(at -2.649982 0.635 270)
			(size 0.6096 1.4224)
			(layers "F.Cu" "F.Mask" "F.Paste")
			(net "PD_FRU_A2")
		)
		(pad "4" smd rect
			(at -2.649982 1.905 270)
			(size 0.6096 1.4224)
			(layers "F.Cu" "F.Mask" "F.Paste")
			(net "GND")
		)
		(pad "5" smd rect
			(at 2.649982 1.905 270)
			(size 0.6096 1.4224)
			(layers "F.Cu" "F.Mask" "F.Paste")
			(net "SMB_FRU_SDA")
		)
		(pad "6" smd rect
			(at 2.649982 0.635 270)
			(size 0.6096 1.4224)
			(layers "F.Cu" "F.Mask" "F.Paste")
			(net "SMB_FRU_SCL")
		)
		(pad "7" smd rect
			(at 2.649982 -0.635 270)
			(size 0.6096 1.4224)
			(layers "F.Cu" "F.Mask" "F.Paste")
			(net "PD_FRU_WP")
		)
		(pad "8" smd rect
			(at 2.649982 -1.905 270)
			(size 0.6096 1.4224)
			(layers "F.Cu" "F.Mask" "F.Paste")
			(net "P3V3_STBY")
		)
	)
	(footprint ""
		(layer "F.Cu")
		(at 26.67 -59.563)
		(property "Reference" ""
			(at 0 0 0)
			(layer "F.SilkS")
			(hide yes)
			(effects
				(font
					(size 1.27 1.27)
				)
			)
		)
		(property "Value" ""
			(at 0 0 0)
			(layer "F.Fab")
			(effects
				(font
					(size 1.27 1.27)
				)
			)
		)
		(duplicate_pad_numbers_are_jumpers no)
		(pad "1" smd circle
			(at 0 0)
			(size 0.9906 0.9906)
			(layers "F.Cu" "F.Mask" "F.Paste")
			(net "Net_6")
		)
		(zone
			(layer "F.Cu")
			(hatch none 0.5)
			(connect_pads
				(clearance 0)
			)
			(min_thickness 0.25)
			(keepout
				(tracks not_allowed)
				(vias allowed)
				(pads allowed)
				(copperpour not_allowed)
				(footprints allowed)
			)
			(placement
				(enabled no)
				(sheetname "")
			)
			(fill
				(thermal_gap 0.5)
				(thermal_bridge_width 0.5)
				(island_removal_mode 0)
			)
			(polygon
				(pts
					(arc
						(start 28.2956 -59.563)
						(mid 25.0444 -59.563)
						(end 28.2956 -59.563)
					)
				)
			)
		)
	)
	(footprint ""
		(layer "F.Cu")
		(at 3.048 -26.289)
		(property "Reference" "R5"
			(at -1.905 0.02667 0)
			(unlocked yes)
			(layer "F.SilkS")
			(effects
				(font
					(size 0.7874 0.5842)
					(thickness 0.1524)
				)
			)
		)
		(property "Value" ""
			(at 0 0 0)
			(layer "F.Fab")
			(effects
				(font
					(size 1.27 1.27)
				)
			)
		)
		(duplicate_pad_numbers_are_jumpers no)
		(fp_line
			(start -0.7874 -0.4064)
			(end 0.7874 -0.4064)
			(stroke
				(width 0.1524)
				(type default)
			)
			(layer "F.SilkS")
		)
		(fp_line
			(start -0.7874 0.4064)
			(end -0.7874 -0.4064)
			(stroke
				(width 0.1524)
				(type default)
			)
			(layer "F.SilkS")
		)
		(fp_line
			(start 0.7874 -0.4064)
			(end 0.7874 0.4064)
			(stroke
				(width 0.1524)
				(type default)
			)
			(layer "F.SilkS")
		)
		(fp_line
			(start 0.7874 0.4064)
			(end -0.7874 0.4064)
			(stroke
				(width 0.1524)
				(type default)
			)
			(layer "F.SilkS")
		)
		(fp_line
			(start -0.67945 -0.305054)
			(end -0.12065 -0.305054)
			(stroke
				(width 0.1)
				(type default)
			)
			(layer "F.Fab")
		)
		(fp_line
			(start -0.67945 0.3048)
			(end -0.67945 -0.305054)
			(stroke
				(width 0.1)
				(type default)
			)
			(layer "F.Fab")
		)
		(fp_line
			(start -0.12065 -0.305054)
			(end -0.12065 -0.2794)
			(stroke
				(width 0.1)
				(type default)
			)
			(layer "F.Fab")
		)
		(fp_line
			(start -0.12065 -0.2794)
			(end 0.12065 -0.2794)
			(stroke
				(width 0.1)
				(type default)
			)
			(layer "F.Fab")
		)
		(fp_line
			(start -0.12065 0.2794)
			(end -0.12065 0.3048)
			(stroke
				(width 0.1)
				(type default)
			)
			(layer "F.Fab")
		)
		(fp_line
			(start -0.12065 0.3048)
			(end -0.67945 0.3048)
			(stroke
				(width 0.1)
				(type default)
			)
			(layer "F.Fab")
		)
		(fp_line
			(start 0.120396 0.2794)
			(end -0.12065 0.2794)
			(stroke
				(width 0.1)
				(type default)
			)
			(layer "F.Fab")
		)
		(fp_line
			(start 0.120396 0.3048)
			(end 0.120396 0.2794)
			(stroke
				(width 0.1)
				(type default)
			)
			(layer "F.Fab")
		)
		(fp_line
			(start 0.12065 -0.3048)
			(end 0.67945 -0.3048)
			(stroke
				(width 0.1)
				(type default)
			)
			(layer "F.Fab")
		)
		(fp_line
			(start 0.12065 -0.2794)
			(end 0.12065 -0.3048)
			(stroke
				(width 0.1)
				(type default)
			)
			(layer "F.Fab")
		)
		(fp_line
			(start 0.67945 -0.3048)
			(end 0.67945 0.3048)
			(stroke
				(width 0.1)
				(type default)
			)
			(layer "F.Fab")
		)
		(fp_line
			(start 0.67945 0.3048)
			(end 0.120396 0.3048)
			(stroke
				(width 0.1)
				(type default)
			)
			(layer "F.Fab")
		)
		(pad "1" smd circle
			(at -0.40005 0)
			(size 0 0)
			(layers "F.Cu" "F.Mask" "F.Paste")
			(net "P3V3_STBY")
		)
		(pad "2" smd circle
			(at 0.40005 0)
			(size 0 0)
			(layers "F.Cu" "F.Mask" "F.Paste")
			(net "SYSTEM_FAULT_ID_LED_R1")
		)
	)
	(footprint ""
		(layer "F.Cu")
		(at 6.100064 -14.899894 180)
		(property "Reference" "H9"
			(at -7.742936 3.361436 0)
			(unlocked yes)
			(layer "F.SilkS")
			(effects
				(font
					(size 0.7874 0.5842)
					(thickness 0.1524)
				)
				(justify left)
			)
		)
		(property "Value" ""
			(at 0 0 180)
			(layer "F.Fab")
			(effects
				(font
					(size 1.27 1.27)
				)
			)
		)
		(duplicate_pad_numbers_are_jumpers no)
		(fp_arc
			(start 1.628648 7.832598)
			(mid -5.048281 6.206014)
			(end -7.999984 0)
			(stroke
				(width 0.1524)
				(type default)
			)
			(layer "F.SilkS")
		)
		(fp_arc
			(start -7.999984 0)
			(mid 3.542385 -7.173048)
			(end 4.863084 6.352286)
			(stroke
				(width 0.1524)
				(type default)
			)
			(layer "F.SilkS")
		)
		(fp_arc
			(start 7.999984 0)
			(mid 6.825974 4.172084)
			(end 3.648456 7.11962)
			(stroke
				(width 0.1524)
				(type default)
			)
			(layer "B.SilkS")
		)
		(fp_arc
			(start -3.65887 7.114286)
			(mid -4.167106 -6.828976)
			(end 7.999984 0)
			(stroke
				(width 0.1524)
				(type default)
			)
			(layer "B.SilkS")
		)
		(fp_circle
			(center 0 0)
			(end -7.999984 0)
			(stroke
				(width 0.1)
				(type default)
			)
			(fill no)
			(layer "B.Fab")
		)
		(fp_circle
			(center 0 0)
			(end -7.999984 0)
			(stroke
				(width 0.1)
				(type default)
			)
			(fill no)
			(layer "F.Fab")
		)
		(pad "" np_thru_hole circle
			(at 0 0 180)
			(size 4.0132 4.0132)
			(drill 4.0132)
			(layers "*.Cu" "*.Mask")
			(clearance 0.381)
			(thermal_gap 0.381)
		)
		(pad "2" thru_hole circle
			(at 3.758692 0 180)
			(size 0.762 0.762)
			(drill 0.5588)
			(layers "*.Cu" "*.Mask")
			(remove_unused_layers no)
			(net "GND")
			(clearance 0.1524)
			(thermal_gap 0.1524)
		)
		(pad "3" thru_hole circle
			(at 2.657602 -2.657602 180)
			(size 0.762 0.762)
			(drill 0.5588)
			(layers "*.Cu" "*.Mask")
			(remove_unused_layers no)
			(net "GND")
			(clearance 0.1524)
			(thermal_gap 0.1524)
		)
		(pad "4" thru_hole circle
			(at 0 -3.758692 180)
			(size 0.762 0.762)
			(drill 0.5588)
			(layers "*.Cu" "*.Mask")
			(remove_unused_layers no)
			(net "GND")
			(clearance 0.1524)
			(thermal_gap 0.1524)
		)
		(pad "5" thru_hole circle
			(at -2.657602 -2.657602 180)
			(size 0.762 0.762)
			(drill 0.5588)
			(layers "*.Cu" "*.Mask")
			(remove_unused_layers no)
			(net "GND")
			(clearance 0.1524)
			(thermal_gap 0.1524)
		)
		(pad "6" thru_hole circle
			(at -3.758692 0 180)
			(size 0.762 0.762)
			(drill 0.5588)
			(layers "*.Cu" "*.Mask")
			(remove_unused_layers no)
			(net "GND")
			(clearance 0.1524)
			(thermal_gap 0.1524)
		)
		(pad "7" thru_hole circle
			(at -2.657602 2.657602 180)
			(size 0.762 0.762)
			(drill 0.5588)
			(layers "*.Cu" "*.Mask")
			(remove_unused_layers no)
			(net "GND")
			(clearance 0.1524)
			(thermal_gap 0.1524)
		)
		(pad "8" thru_hole circle
			(at 0 3.758692 180)
			(size 0.762 0.762)
			(drill 0.5588)
			(layers "*.Cu" "*.Mask")
			(remove_unused_layers no)
			(net "GND")
			(clearance 0.1524)
			(thermal_gap 0.1524)
		)
		(pad "9" thru_hole circle
			(at 2.657602 2.657602 180)
			(size 0.762 0.762)
			(drill 0.5588)
			(layers "*.Cu" "*.Mask")
			(remove_unused_layers no)
			(net "GND")
			(clearance 0.1524)
			(thermal_gap 0.1524)
		)
		(zone
			(layer "F.Cu")
			(hatch none 0.5)
			(connect_pads
				(clearance 0)
			)
			(min_thickness 0.25)
			(keepout
				(tracks not_allowed)
				(vias allowed)
				(pads allowed)
				(copperpour not_allowed)
				(footprints allowed)
			)
			(placement
				(enabled no)
				(sheetname "")
			)
			(fill
				(thermal_gap 0.5)
				(thermal_bridge_width 0.5)
				(island_removal_mode 0)
			)
			(polygon
				(pts
					(arc
						(start 6.100064 -9.645904)
						(mid 0.846074 -14.899894)
						(end 6.100064 -20.153884)
					)
					(arc
						(start 6.100064 -19.925284)
						(mid 1.074674 -14.899894)
						(end 6.100064 -9.874504)
					)
				)
			)
		)
		(zone
			(layer "F.Cu")
			(hatch none 0.5)
			(connect_pads
				(clearance 0)
			)
			(min_thickness 0.25)
			(keepout
				(tracks not_allowed)
				(vias allowed)
				(pads allowed)
				(copperpour not_allowed)
				(footprints allowed)
			)
			(placement
				(enabled no)
				(sheetname "")
			)
			(fill
				(thermal_gap 0.5)
				(thermal_bridge_width 0.5)
				(island_removal_mode 0)
			)
			(polygon
				(pts
					(arc
						(start 6.100064 -9.645904)
						(mid 11.354054 -14.899894)
						(end 6.100064 -20.153884)
					)
					(arc
						(start 6.100064 -19.925284)
						(mid 11.125454 -14.899894)
						(end 6.100064 -9.874504)
					)
				)
			)
		)
		(zone
			(layer "F.Cu")
			(hatch none 0.5)
			(connect_pads
				(clearance 0)
			)
			(min_thickness 0.25)
			(keepout
				(tracks not_allowed)
				(vias allowed)
				(pads allowed)
				(copperpour not_allowed)
				(footprints allowed)
			)
			(placement
				(enabled no)
				(sheetname "")
			)
			(fill
				(thermal_gap 0.5)
				(thermal_bridge_width 0.5)
				(island_removal_mode 0)
			)
			(polygon
				(pts
					(arc
						(start 6.100064 -22.899878)
						(mid -1.89992 -14.899894)
						(end 6.100064 -6.89991)
					)
					(arc
						(start 6.100064 -9.645904)
						(mid 0.764794 -14.981174)
						(end 6.100064 -20.31619)
					)
				)
			)
		)
		(zone
			(layer "F.Cu")
			(hatch none 0.5)
			(connect_pads
				(clearance 0)
			)
			(min_thickness 0.25)
			(keepout
				(tracks not_allowed)
				(vias allowed)
				(pads allowed)
				(copperpour not_allowed)
				(footprints allowed)
			)
			(placement
				(enabled no)
				(sheetname "")
			)
			(fill
				(thermal_gap 0.5)
				(thermal_bridge_width 0.5)
				(island_removal_mode 0)
			)
			(polygon
				(pts
					(arc
						(start 6.100064 -22.899878)
						(mid 14.100048 -14.899894)
						(end 6.100064 -6.89991)
					)
					(arc
						(start 6.100064 -9.645904)
						(mid 11.435334 -14.981174)
						(end 6.100064 -20.31619)
					)
				)
			)
		)
		(zone
			(layers "F.Cu" "B.Cu" "In1.Cu" "In2.Cu")
			(hatch none 0.5)
			(connect_pads
				(clearance 0)
			)
			(min_thickness 0.25)
			(keepout
				(tracks not_allowed)
				(vias allowed)
				(pads allowed)
				(copperpour not_allowed)
				(footprints allowed)
			)
			(placement
				(enabled no)
				(sheetname "")
			)
			(fill
				(thermal_gap 0.5)
				(thermal_bridge_width 0.5)
				(island_removal_mode 0)
			)
			(polygon
				(pts
					(arc
						(start 8.614664 -14.899894)
						(mid 3.585464 -14.899894)
						(end 8.614664 -14.899894)
					)
				)
			)
		)
		(zone
			(layer "B.Cu")
			(hatch none 0.5)
			(connect_pads
				(clearance 0)
			)
			(min_thickness 0.25)
			(keepout
				(tracks not_allowed)
				(vias allowed)
				(pads allowed)
				(copperpour not_allowed)
				(footprints allowed)
			)
			(placement
				(enabled no)
				(sheetname "")
			)
			(fill
				(thermal_gap 0.5)
				(thermal_bridge_width 0.5)
				(island_removal_mode 0)
			)
			(polygon
				(pts
					(arc
						(start 0.592074 -18.400014)
						(mid 2.205327 -22.294751)
						(end 6.100064 -23.908004)
					)
					(arc
						(start 6.100064 -23.425404)
						(mid 2.546577 -21.953501)
						(end 1.074674 -18.400014)
					)
					(arc
						(start 1.074674 -14.899894)
						(mid 2.546577 -11.346407)
						(end 6.100064 -9.874504)
					)
					(arc
						(start 6.100064 -9.391904)
						(mid 2.205327 -11.005157)
						(end 0.592074 -14.899894)
					)
				)
			)
		)
		(zone
			(layer "B.Cu")
			(hatch none 0.5)
			(connect_pads
				(clearance 0)
			)
			(min_thickness 0.25)
			(keepout
				(tracks not_allowed)
				(vias allowed)
				(pads allowed)
				(copperpour not_allowed)
				(footprints allowed)
			)
			(placement
				(enabled no)
				(sheetname "")
			)
			(fill
				(thermal_gap 0.5)
				(thermal_bridge_width 0.5)
				(island_removal_mode 0)
			)
			(polygon
				(pts
					(arc
						(start 11.608054 -18.400014)
						(mid 9.994801 -22.294751)
						(end 6.100064 -23.908004)
					)
					(arc
						(start 6.100064 -23.425404)
						(mid 9.653551 -21.953501)
						(end 11.125454 -18.400014)
					)
					(arc
						(start 11.125454 -14.899894)
						(mid 9.653551 -11.346407)
						(end 6.100064 -9.874504)
					)
					(arc
						(start 6.100064 -9.391904)
						(mid 9.994801 -11.005157)
						(end 11.608054 -14.899894)
					)
				)
			)
		)
	)
	(footprint ""
		(layer "F.Cu")
		(at 96.56953 -23.622 -90)
		(property "Reference" "X2"
			(at 4.59867 0.30353 0)
			(unlocked yes)
			(layer "F.SilkS")
			(effects
				(font
					(size 0.7874 0.5842)
					(thickness 0.1524)
				)
				(justify left)
			)
		)
		(property "Value" ""
			(at 0 0 270)
			(layer "F.Fab")
			(effects
				(font
					(size 1.27 1.27)
				)
			)
		)
		(property "Device Type" "TP_TDR_4P_FTS_MPKT4_H025P0200_IO_TP15_TP_TDR_4P_DIP"
			(at 1.30175 1.27 0)
			(unlocked yes)
			(layer "F.Fab")
			(hide yes)
			(effects
				(font
					(size 0.635 0.4064)
					(thickness 0.1524)
				)
			)
		)
		(property "User Part Number" "TP15"
			(at 1.30175 1.27 0)
			(unlocked yes)
			(layer "Cmts.User")
			(hide yes)
			(effects
				(font
					(size 0.635 0.4064)
					(thickness 0.1524)
				)
			)
		)
		(duplicate_pad_numbers_are_jumpers no)
		(fp_line
			(start 0 3.81)
			(end 2.54 3.81)
			(stroke
				(width 0.1524)
				(type default)
			)
			(layer "F.SilkS")
		)
		(fp_line
			(start 2.54 3.81)
			(end 2.54 3.6703)
			(stroke
				(width 0.1524)
				(type default)
			)
			(layer "F.SilkS")
		)
		(fp_line
			(start 0 3.175)
			(end 0 3.81)
			(stroke
				(width 0.1524)
				(type default)
			)
			(layer "F.SilkS")
		)
		(fp_line
			(start 2.54 1.4097)
			(end 2.54 1.1303)
			(stroke
				(width 0.1524)
				(type default)
			)
			(layer "F.SilkS")
		)
		(fp_line
			(start 0 0.635)
			(end 0 1.905)
			(stroke
				(width 0.1524)
				(type default)
			)
			(layer "F.SilkS")
		)
		(fp_line
			(start 2.54 -1.1303)
			(end 2.54 -1.27)
			(stroke
				(width 0.1524)
				(type default)
			)
			(layer "F.SilkS")
		)
		(fp_line
			(start 0 -1.27)
			(end 0 -0.635)
			(stroke
				(width 0.1524)
				(type default)
			)
			(layer "F.SilkS")
		)
		(fp_line
			(start 2.54 -1.27)
			(end 0 -1.27)
			(stroke
				(width 0.1524)
				(type default)
			)
			(layer "F.SilkS")
		)
		(fp_poly
			(pts
				(xy -0.761746 0) (xy -2.285746 -0.762) (xy -2.285746 0.762)
			)
			(stroke
				(width 0)
				(type default)
			)
			(fill yes)
			(layer "F.SilkS")
		)
		(fp_line
			(start 0 3.81)
			(end 2.54 3.81)
			(stroke
				(width 0.1)
				(type default)
			)
			(layer "F.Fab")
		)
		(fp_line
			(start 2.54 3.81)
			(end 2.54 -1.27)
			(stroke
				(width 0.1)
				(type default)
			)
			(layer "F.Fab")
		)
		(fp_line
			(start 0 -1.27)
			(end 0 3.81)
			(stroke
				(width 0.1)
				(type default)
			)
			(layer "F.Fab")
		)
		(fp_line
			(start 2.54 -1.27)
			(end 0 -1.27)
			(stroke
				(width 0.1)
				(type default)
			)
			(layer "F.Fab")
		)
		(fp_poly
			(pts
				(xy -0.761746 0) (xy -2.285746 -0.762) (xy -2.285746 0.762)
			)
			(stroke
				(width 0)
				(type default)
			)
			(fill yes)
			(layer "F.Fab")
		)
		(pad "1" thru_hole circle
			(at 0 0 270)
			(size 1.0033 1.0033)
			(drill 0.249936)
			(layers "*.Cu" "*.Mask")
			(remove_unused_layers no)
			(net "TDR_DIFF_85_TOP_DN")
			(clearance 0.10795)
			(thermal_gap 0.10795)
			(padstack
				(mode front_inner_back)
				(layer "Inner"
					(shape circle)
					(size 0.8001 0.8001)
					(clearance 0.1524)
				)
				(layer "B.Cu"
					(shape circle)
					(size 1.0033 1.0033)
					(clearance 0.10795)
				)
			)
		)
		(pad "2" thru_hole circle
			(at 2.54 0 270)
			(size 1.9939 1.9939)
			(drill 0.249936)
			(layers "*.Cu" "*.Mask")
			(remove_unused_layers no)
			(net "GND_TDR")
			(clearance 0.10795)
			(thermal_gap 0.10795)
			(padstack
				(mode front_inner_back)
				(layer "Inner"
					(shape circle)
					(size 0.8001 0.8001)
					(clearance 0.1524)
				)
				(layer "B.Cu"
					(shape circle)
					(size 1.9939 1.9939)
					(clearance 0.10795)
				)
			)
		)
		(pad "3" thru_hole circle
			(at 2.54 2.54 270)
			(size 1.9939 1.9939)
			(drill 0.249936)
			(layers "*.Cu" "*.Mask")
			(remove_unused_layers no)
			(net "GND_TDR")
			(clearance 0.10795)
			(thermal_gap 0.10795)
			(padstack
				(mode front_inner_back)
				(layer "Inner"
					(shape circle)
					(size 0.8001 0.8001)
					(clearance 0.1524)
				)
				(layer "B.Cu"
					(shape circle)
					(size 1.9939 1.9939)
					(clearance 0.10795)
				)
			)
		)
		(pad "4" thru_hole circle
			(at 0 2.54 270)
			(size 1.0033 1.0033)
			(drill 0.249936)
			(layers "*.Cu" "*.Mask")
			(remove_unused_layers no)
			(net "TDR_DIFF_85_TOP_DP")
			(clearance 0.10795)
			(thermal_gap 0.10795)
			(padstack
				(mode front_inner_back)
				(layer "Inner"
					(shape circle)
					(size 0.8001 0.8001)
					(clearance 0.1524)
				)
				(layer "B.Cu"
					(shape circle)
					(size 1.0033 1.0033)
					(clearance 0.10795)
				)
			)
		)
	)
	(footprint ""
		(layer "F.Cu")
		(at 34.040064 -37.573712)
		(property "Reference" "H3"
			(at 0.707136 -3.026918 0)
			(unlocked yes)
			(layer "F.SilkS")
			(effects
				(font
					(size 0.7874 0.5842)
					(thickness 0.1524)
				)
				(justify left)
			)
		)
		(property "Value" ""
			(at 0 0 0)
			(layer "F.Fab")
			(effects
				(font
					(size 1.27 1.27)
				)
			)
		)
		(duplicate_pad_numbers_are_jumpers no)
		(fp_circle
			(center 0 0)
			(end 2.4003 0)
			(stroke
				(width 0.1524)
				(type default)
			)
			(fill no)
			(layer "F.SilkS")
		)
		(fp_circle
			(center 0 0)
			(end 6.5913 0)
			(stroke
				(width 0.1524)
				(type default)
			)
			(fill no)
			(layer "B.SilkS")
		)
		(fp_circle
			(center 0 0)
			(end 6.5913 0)
			(stroke
				(width 0.1)
				(type default)
			)
			(fill no)
			(layer "B.Fab")
		)
		(fp_circle
			(center 0 0)
			(end 2.4003 0)
			(stroke
				(width 0.1)
				(type default)
			)
			(fill no)
			(layer "F.Fab")
		)
		(pad "" np_thru_hole circle
			(at 0 0)
			(size 3.175 3.175)
			(drill 3.175)
			(layers "*.Cu" "*.Mask")
			(clearance 0.381)
			(thermal_gap 0.381)
		)
		(zone
			(layers "F.Cu" "B.Cu" "In1.Cu" "In2.Cu")
			(hatch none 0.5)
			(connect_pads
				(clearance 0)
			)
			(min_thickness 0.25)
			(keepout
				(tracks not_allowed)
				(vias allowed)
				(pads allowed)
				(copperpour not_allowed)
				(footprints allowed)
			)
			(placement
				(enabled no)
				(sheetname "")
			)
			(fill
				(thermal_gap 0.5)
				(thermal_bridge_width 0.5)
				(island_removal_mode 0)
			)
			(polygon
				(pts
					(arc
						(start 36.135564 -37.573712)
						(mid 31.944564 -37.573712)
						(end 36.135564 -37.573712)
					)
				)
			)
		)
	)
	(footprint ""
		(layer "F.Cu")
		(at 19.558 -23.114)
		(property "Reference" "R36"
			(at 0.381 -4.16433 0)
			(unlocked yes)
			(layer "F.SilkS")
			(effects
				(font
					(size 0.7874 0.5842)
					(thickness 0.1524)
				)
			)
		)
		(property "Value" ""
			(at 0 0 0)
			(layer "F.Fab")
			(effects
				(font
					(size 1.27 1.27)
				)
			)
		)
		(duplicate_pad_numbers_are_jumpers no)
		(fp_line
			(start -0.7874 -0.4064)
			(end 0.7874 -0.4064)
			(stroke
				(width 0.1524)
				(type default)
			)
			(layer "F.SilkS")
		)
		(fp_line
			(start -0.7874 0.4064)
			(end -0.7874 -0.4064)
			(stroke
				(width 0.1524)
				(type default)
			)
			(layer "F.SilkS")
		)
		(fp_line
			(start 0.7874 -0.4064)
			(end 0.7874 0.4064)
			(stroke
				(width 0.1524)
				(type default)
			)
			(layer "F.SilkS")
		)
		(fp_line
			(start 0.7874 0.4064)
			(end -0.7874 0.4064)
			(stroke
				(width 0.1524)
				(type default)
			)
			(layer "F.SilkS")
		)
		(fp_line
			(start -0.67945 -0.305054)
			(end -0.12065 -0.305054)
			(stroke
				(width 0.1)
				(type default)
			)
			(layer "F.Fab")
		)
		(fp_line
			(start -0.67945 0.3048)
			(end -0.67945 -0.305054)
			(stroke
				(width 0.1)
				(type default)
			)
			(layer "F.Fab")
		)
		(fp_line
			(start -0.12065 -0.305054)
			(end -0.12065 -0.2794)
			(stroke
				(width 0.1)
				(type default)
			)
			(layer "F.Fab")
		)
		(fp_line
			(start -0.12065 -0.2794)
			(end 0.12065 -0.2794)
			(stroke
				(width 0.1)
				(type default)
			)
			(layer "F.Fab")
		)
		(fp_line
			(start -0.12065 0.2794)
			(end -0.12065 0.3048)
			(stroke
				(width 0.1)
				(type default)
			)
			(layer "F.Fab")
		)
		(fp_line
			(start -0.12065 0.3048)
			(end -0.67945 0.3048)
			(stroke
				(width 0.1)
				(type default)
			)
			(layer "F.Fab")
		)
		(fp_line
			(start 0.120396 0.2794)
			(end -0.12065 0.2794)
			(stroke
				(width 0.1)
				(type default)
			)
			(layer "F.Fab")
		)
		(fp_line
			(start 0.120396 0.3048)
			(end 0.120396 0.2794)
			(stroke
				(width 0.1)
				(type default)
			)
			(layer "F.Fab")
		)
		(fp_line
			(start 0.12065 -0.3048)
			(end 0.67945 -0.3048)
			(stroke
				(width 0.1)
				(type default)
			)
			(layer "F.Fab")
		)
		(fp_line
			(start 0.12065 -0.2794)
			(end 0.12065 -0.3048)
			(stroke
				(width 0.1)
				(type default)
			)
			(layer "F.Fab")
		)
		(fp_line
			(start 0.67945 -0.3048)
			(end 0.67945 0.3048)
			(stroke
				(width 0.1)
				(type default)
			)
			(layer "F.Fab")
		)
		(fp_line
			(start 0.67945 0.3048)
			(end 0.120396 0.3048)
			(stroke
				(width 0.1)
				(type default)
			)
			(layer "F.Fab")
		)
		(pad "1" smd circle
			(at -0.40005 0)
			(size 0 0)
			(layers "F.Cu" "F.Mask" "F.Paste")
			(net "SMB_SCL")
		)
		(pad "2" smd circle
			(at 0.40005 0)
			(size 0 0)
			(layers "F.Cu" "F.Mask" "F.Paste")
			(net "SMB_TMP75_SCL")
		)
	)
	(footprint ""
		(layer "F.Cu")
		(at 3.556 -64.897)
		(property "Reference" "H4"
			(at -2.54 -2.76733 0)
			(unlocked yes)
			(layer "F.SilkS")
			(effects
				(font
					(size 0.7874 0.5842)
					(thickness 0.1524)
				)
				(justify left)
			)
		)
		(property "Value" ""
			(at 0 0 0)
			(layer "F.Fab")
			(effects
				(font
					(size 1.27 1.27)
				)
			)
		)
		(duplicate_pad_numbers_are_jumpers no)
		(fp_circle
			(center 0 0)
			(end 2.4003 0)
			(stroke
				(width 0.1524)
				(type default)
			)
			(fill no)
			(layer "F.SilkS")
		)
		(fp_arc
			(start 5.969762 -2.794254)
			(mid 6.434026 -1.43127)
			(end 6.5913 0)
			(stroke
				(width 0.1524)
				(type default)
			)
			(layer "B.SilkS")
		)
		(fp_arc
			(start 6.5913 0)
			(mid -4.141127 5.129364)
			(end -1.389634 -6.443218)
			(stroke
				(width 0.1524)
				(type default)
			)
			(layer "B.SilkS")
		)
		(fp_circle
			(center 0 0)
			(end 6.5913 0)
			(stroke
				(width 0.1)
				(type default)
			)
			(fill no)
			(layer "B.Fab")
		)
		(fp_circle
			(center 0 0)
			(end 2.4003 0)
			(stroke
				(width 0.1)
				(type default)
			)
			(fill no)
			(layer "F.Fab")
		)
		(pad "" np_thru_hole circle
			(at 0 0)
			(size 3.175 3.175)
			(drill 3.175)
			(layers "*.Cu" "*.Mask")
			(clearance 0.381)
			(thermal_gap 0.381)
		)
		(zone
			(layers "F.Cu" "B.Cu" "In1.Cu" "In2.Cu")
			(hatch none 0.5)
			(connect_pads
				(clearance 0)
			)
			(min_thickness 0.25)
			(keepout
				(tracks not_allowed)
				(vias allowed)
				(pads allowed)
				(copperpour not_allowed)
				(footprints allowed)
			)
			(placement
				(enabled no)
				(sheetname "")
			)
			(fill
				(thermal_gap 0.5)
				(thermal_bridge_width 0.5)
				(island_removal_mode 0)
			)
			(polygon
				(pts
					(arc
						(start 5.6515 -64.897)
						(mid 1.4605 -64.897)
						(end 5.6515 -64.897)
					)
				)
			)
		)
	)
	(footprint ""
		(layer "F.Cu")
		(at 17.526 -25.146 180)
		(property "Reference" "R46"
			(at 0.127 4.16433 0)
			(unlocked yes)
			(layer "F.SilkS")
			(effects
				(font
					(size 0.7874 0.5842)
					(thickness 0.1524)
				)
			)
		)
		(property "Value" ""
			(at 0 0 180)
			(layer "F.Fab")
			(effects
				(font
					(size 1.27 1.27)
				)
			)
		)
		(duplicate_pad_numbers_are_jumpers no)
		(fp_line
			(start 0.7874 0.4064)
			(end -0.7874 0.4064)
			(stroke
				(width 0.1524)
				(type default)
			)
			(layer "F.SilkS")
		)
		(fp_line
			(start 0.7874 -0.4064)
			(end 0.7874 0.4064)
			(stroke
				(width 0.1524)
				(type default)
			)
			(layer "F.SilkS")
		)
		(fp_line
			(start -0.7874 0.4064)
			(end -0.7874 -0.4064)
			(stroke
				(width 0.1524)
				(type default)
			)
			(layer "F.SilkS")
		)
		(fp_line
			(start -0.7874 -0.4064)
			(end 0.7874 -0.4064)
			(stroke
				(width 0.1524)
				(type default)
			)
			(layer "F.SilkS")
		)
		(fp_line
			(start 0.67945 0.3048)
			(end 0.120396 0.3048)
			(stroke
				(width 0.1)
				(type default)
			)
			(layer "F.Fab")
		)
		(fp_line
			(start 0.67945 -0.3048)
			(end 0.67945 0.3048)
			(stroke
				(width 0.1)
				(type default)
			)
			(layer "F.Fab")
		)
		(fp_line
			(start 0.12065 -0.2794)
			(end 0.12065 -0.3048)
			(stroke
				(width 0.1)
				(type default)
			)
			(layer "F.Fab")
		)
		(fp_line
			(start 0.12065 -0.3048)
			(end 0.67945 -0.3048)
			(stroke
				(width 0.1)
				(type default)
			)
			(layer "F.Fab")
		)
		(fp_line
			(start 0.120396 0.3048)
			(end 0.120396 0.2794)
			(stroke
				(width 0.1)
				(type default)
			)
			(layer "F.Fab")
		)
		(fp_line
			(start 0.120396 0.2794)
			(end -0.12065 0.2794)
			(stroke
				(width 0.1)
				(type default)
			)
			(layer "F.Fab")
		)
		(fp_line
			(start -0.12065 0.3048)
			(end -0.67945 0.3048)
			(stroke
				(width 0.1)
				(type default)
			)
			(layer "F.Fab")
		)
		(fp_line
			(start -0.12065 0.2794)
			(end -0.12065 0.3048)
			(stroke
				(width 0.1)
				(type default)
			)
			(layer "F.Fab")
		)
		(fp_line
			(start -0.12065 -0.2794)
			(end 0.12065 -0.2794)
			(stroke
				(width 0.1)
				(type default)
			)
			(layer "F.Fab")
		)
		(fp_line
			(start -0.12065 -0.305054)
			(end -0.12065 -0.2794)
			(stroke
				(width 0.1)
				(type default)
			)
			(layer "F.Fab")
		)
		(fp_line
			(start -0.67945 0.3048)
			(end -0.67945 -0.305054)
			(stroke
				(width 0.1)
				(type default)
			)
			(layer "F.Fab")
		)
		(fp_line
			(start -0.67945 -0.305054)
			(end -0.12065 -0.305054)
			(stroke
				(width 0.1)
				(type default)
			)
			(layer "F.Fab")
		)
		(pad "1" smd circle
			(at -0.40005 0 180)
			(size 0 0)
			(layers "F.Cu" "F.Mask" "F.Paste")
			(net "P3V3_STBY")
		)
		(pad "2" smd circle
			(at 0.40005 0 180)
			(size 0 0)
			(layers "F.Cu" "F.Mask" "F.Paste")
			(net "SMB_IO_DEBUG_CARD_SDA")
		)
	)
	(footprint ""
		(layer "F.Cu")
		(at 16.234918 -12.026392)
		(property "Reference" "U1"
			(at -2.772918 2.528062 0)
			(unlocked yes)
			(layer "F.SilkS")
			(effects
				(font
					(size 0.7874 0.5842)
					(thickness 0.1524)
				)
			)
		)
		(property "Value" ""
			(at 0 0 0)
			(layer "F.Fab")
			(effects
				(font
					(size 1.27 1.27)
				)
			)
		)
		(duplicate_pad_numbers_are_jumpers no)
		(fp_line
			(start -1.949958 -1.610106)
			(end 1.949958 -1.610106)
			(stroke
				(width 0.1524)
				(type default)
			)
			(layer "F.SilkS")
		)
		(fp_line
			(start -1.949958 1.610106)
			(end -1.949958 -1.610106)
			(stroke
				(width 0.1524)
				(type default)
			)
			(layer "F.SilkS")
		)
		(fp_line
			(start 1.949958 -1.560068)
			(end 1.949958 1.610106)
			(stroke
				(width 0.1524)
				(type default)
			)
			(layer "F.SilkS")
		)
		(fp_line
			(start 1.949958 1.610106)
			(end -1.949958 1.610106)
			(stroke
				(width 0.1524)
				(type default)
			)
			(layer "F.SilkS")
		)
		(fp_line
			(start -0.750062 -1.560068)
			(end 0.750062 -1.560068)
			(stroke
				(width 0.1)
				(type default)
			)
			(layer "F.Fab")
		)
		(fp_line
			(start -0.750062 1.560068)
			(end -0.750062 -1.560068)
			(stroke
				(width 0.1)
				(type default)
			)
			(layer "F.Fab")
		)
		(fp_line
			(start 0.750062 -1.560068)
			(end 0.750062 1.560068)
			(stroke
				(width 0.1)
				(type default)
			)
			(layer "F.Fab")
		)
		(fp_line
			(start 0.750062 1.560068)
			(end -0.750062 1.560068)
			(stroke
				(width 0.1)
				(type default)
			)
			(layer "F.Fab")
		)
		(pad "D" smd rect
			(at 1.100074 0 270)
			(size 1.016 1.4224)
			(layers "F.Cu" "F.Mask" "F.Paste")
			(net "FM_PFR_LED_AMBER_R")
		)
		(pad "G" smd rect
			(at -1.100074 -0.94996 270)
			(size 1.016 1.4224)
			(layers "F.Cu" "F.Mask" "F.Paste")
			(net "FM_PFR_LED_AMBER_R_N")
		)
		(pad "S" smd rect
			(at -1.100074 0.94996 270)
			(size 1.016 1.4224)
			(layers "F.Cu" "F.Mask" "F.Paste")
			(net "GND")
		)
	)
	(footprint ""
		(layer "F.Cu")
		(at 18.415 -58.801)
		(property "Reference" "R20"
			(at 3.81 0.02667 0)
			(unlocked yes)
			(layer "F.SilkS")
			(effects
				(font
					(size 0.7874 0.5842)
					(thickness 0.1524)
				)
			)
		)
		(property "Value" ""
			(at 0 0 0)
			(layer "F.Fab")
			(effects
				(font
					(size 1.27 1.27)
				)
			)
		)
		(duplicate_pad_numbers_are_jumpers no)
		(fp_line
			(start -0.7874 -0.4064)
			(end 0.7874 -0.4064)
			(stroke
				(width 0.1524)
				(type default)
			)
			(layer "F.SilkS")
		)
		(fp_line
			(start -0.7874 0.4064)
			(end -0.7874 -0.4064)
			(stroke
				(width 0.1524)
				(type default)
			)
			(layer "F.SilkS")
		)
		(fp_line
			(start 0.7874 -0.4064)
			(end 0.7874 0.4064)
			(stroke
				(width 0.1524)
				(type default)
			)
			(layer "F.SilkS")
		)
		(fp_line
			(start 0.7874 0.4064)
			(end -0.7874 0.4064)
			(stroke
				(width 0.1524)
				(type default)
			)
			(layer "F.SilkS")
		)
		(fp_line
			(start -0.67945 -0.305054)
			(end -0.12065 -0.305054)
			(stroke
				(width 0.1)
				(type default)
			)
			(layer "F.Fab")
		)
		(fp_line
			(start -0.67945 0.3048)
			(end -0.67945 -0.305054)
			(stroke
				(width 0.1)
				(type default)
			)
			(layer "F.Fab")
		)
		(fp_line
			(start -0.12065 -0.305054)
			(end -0.12065 -0.2794)
			(stroke
				(width 0.1)
				(type default)
			)
			(layer "F.Fab")
		)
		(fp_line
			(start -0.12065 -0.2794)
			(end 0.12065 -0.2794)
			(stroke
				(width 0.1)
				(type default)
			)
			(layer "F.Fab")
		)
		(fp_line
			(start -0.12065 0.2794)
			(end -0.12065 0.3048)
			(stroke
				(width 0.1)
				(type default)
			)
			(layer "F.Fab")
		)
		(fp_line
			(start -0.12065 0.3048)
			(end -0.67945 0.3048)
			(stroke
				(width 0.1)
				(type default)
			)
			(layer "F.Fab")
		)
		(fp_line
			(start 0.120396 0.2794)
			(end -0.12065 0.2794)
			(stroke
				(width 0.1)
				(type default)
			)
			(layer "F.Fab")
		)
		(fp_line
			(start 0.120396 0.3048)
			(end 0.120396 0.2794)
			(stroke
				(width 0.1)
				(type default)
			)
			(layer "F.Fab")
		)
		(fp_line
			(start 0.12065 -0.3048)
			(end 0.67945 -0.3048)
			(stroke
				(width 0.1)
				(type default)
			)
			(layer "F.Fab")
		)
		(fp_line
			(start 0.12065 -0.2794)
			(end 0.12065 -0.3048)
			(stroke
				(width 0.1)
				(type default)
			)
			(layer "F.Fab")
		)
		(fp_line
			(start 0.67945 -0.3048)
			(end 0.67945 0.3048)
			(stroke
				(width 0.1)
				(type default)
			)
			(layer "F.Fab")
		)
		(fp_line
			(start 0.67945 0.3048)
			(end 0.120396 0.3048)
			(stroke
				(width 0.1)
				(type default)
			)
			(layer "F.Fab")
		)
		(pad "1" smd circle
			(at -0.40005 0)
			(size 0 0)
			(layers "F.Cu" "F.Mask" "F.Paste")
			(net "PCA9539_A0")
		)
		(pad "2" smd circle
			(at 0.40005 0)
			(size 0 0)
			(layers "F.Cu" "F.Mask" "F.Paste")
			(net "P3V3_STBY")
		)
	)
	(footprint ""
		(layer "F.Cu")
		(at 13.462 -22.225 180)
		(property "Reference" "R50"
			(at 2.032 -0.02667 0)
			(unlocked yes)
			(layer "F.SilkS")
			(effects
				(font
					(size 0.7874 0.5842)
					(thickness 0.1524)
				)
			)
		)
		(property "Value" ""
			(at 0 0 180)
			(layer "F.Fab")
			(effects
				(font
					(size 1.27 1.27)
				)
			)
		)
		(duplicate_pad_numbers_are_jumpers no)
		(fp_line
			(start 0.7874 0.4064)
			(end -0.7874 0.4064)
			(stroke
				(width 0.1524)
				(type default)
			)
			(layer "F.SilkS")
		)
		(fp_line
			(start 0.7874 -0.4064)
			(end 0.7874 0.4064)
			(stroke
				(width 0.1524)
				(type default)
			)
			(layer "F.SilkS")
		)
		(fp_line
			(start -0.7874 0.4064)
			(end -0.7874 -0.4064)
			(stroke
				(width 0.1524)
				(type default)
			)
			(layer "F.SilkS")
		)
		(fp_line
			(start -0.7874 -0.4064)
			(end 0.7874 -0.4064)
			(stroke
				(width 0.1524)
				(type default)
			)
			(layer "F.SilkS")
		)
		(fp_line
			(start 0.67945 0.3048)
			(end 0.120396 0.3048)
			(stroke
				(width 0.1)
				(type default)
			)
			(layer "F.Fab")
		)
		(fp_line
			(start 0.67945 -0.3048)
			(end 0.67945 0.3048)
			(stroke
				(width 0.1)
				(type default)
			)
			(layer "F.Fab")
		)
		(fp_line
			(start 0.12065 -0.2794)
			(end 0.12065 -0.3048)
			(stroke
				(width 0.1)
				(type default)
			)
			(layer "F.Fab")
		)
		(fp_line
			(start 0.12065 -0.3048)
			(end 0.67945 -0.3048)
			(stroke
				(width 0.1)
				(type default)
			)
			(layer "F.Fab")
		)
		(fp_line
			(start 0.120396 0.3048)
			(end 0.120396 0.2794)
			(stroke
				(width 0.1)
				(type default)
			)
			(layer "F.Fab")
		)
		(fp_line
			(start 0.120396 0.2794)
			(end -0.12065 0.2794)
			(stroke
				(width 0.1)
				(type default)
			)
			(layer "F.Fab")
		)
		(fp_line
			(start -0.12065 0.3048)
			(end -0.67945 0.3048)
			(stroke
				(width 0.1)
				(type default)
			)
			(layer "F.Fab")
		)
		(fp_line
			(start -0.12065 0.2794)
			(end -0.12065 0.3048)
			(stroke
				(width 0.1)
				(type default)
			)
			(layer "F.Fab")
		)
		(fp_line
			(start -0.12065 -0.2794)
			(end 0.12065 -0.2794)
			(stroke
				(width 0.1)
				(type default)
			)
			(layer "F.Fab")
		)
		(fp_line
			(start -0.12065 -0.305054)
			(end -0.12065 -0.2794)
			(stroke
				(width 0.1)
				(type default)
			)
			(layer "F.Fab")
		)
		(fp_line
			(start -0.67945 0.3048)
			(end -0.67945 -0.305054)
			(stroke
				(width 0.1)
				(type default)
			)
			(layer "F.Fab")
		)
		(fp_line
			(start -0.67945 -0.305054)
			(end -0.12065 -0.305054)
			(stroke
				(width 0.1)
				(type default)
			)
			(layer "F.Fab")
		)
		(pad "1" smd circle
			(at -0.40005 0 180)
			(size 0 0)
			(layers "F.Cu" "F.Mask" "F.Paste")
			(net "PRSNT_DBV2_USB")
		)
		(pad "2" smd circle
			(at 0.40005 0 180)
			(size 0 0)
			(layers "F.Cu" "F.Mask" "F.Paste")
			(net "GND")
		)
	)
	(footprint ""
		(layer "F.Cu")
		(at 8.619998 -5.100066)
		(property "Reference" "D3"
			(at 1.921002 -2.64922 0)
			(unlocked yes)
			(layer "F.SilkS")
			(effects
				(font
					(size 0.7874 0.5842)
					(thickness 0.1524)
				)
				(justify left)
			)
		)
		(property "Value" ""
			(at 0 0 0)
			(layer "F.Fab")
			(effects
				(font
					(size 1.27 1.27)
				)
			)
		)
		(duplicate_pad_numbers_are_jumpers no)
		(fp_line
			(start -1.080008 -1.999996)
			(end 3.620008 -1.999996)
			(stroke
				(width 0.1524)
				(type default)
			)
			(layer "F.SilkS")
		)
		(fp_line
			(start -1.080008 3.999992)
			(end -1.080008 -1.999996)
			(stroke
				(width 0.1524)
				(type default)
			)
			(layer "F.SilkS")
		)
		(fp_line
			(start -0.230124 3.999992)
			(end -1.080008 3.999992)
			(stroke
				(width 0.1524)
				(type default)
			)
			(layer "F.SilkS")
		)
		(fp_line
			(start -0.230124 5.199888)
			(end -0.230124 3.999992)
			(stroke
				(width 0.1524)
				(type default)
			)
			(layer "F.SilkS")
		)
		(fp_line
			(start 2.770124 3.999992)
			(end 2.770124 5.199888)
			(stroke
				(width 0.1524)
				(type default)
			)
			(layer "F.SilkS")
		)
		(fp_line
			(start 3.620008 -1.999996)
			(end 3.620008 3.999992)
			(stroke
				(width 0.1524)
				(type default)
			)
			(layer "F.SilkS")
		)
		(fp_line
			(start 3.620008 3.999992)
			(end 2.770124 3.999992)
			(stroke
				(width 0.1524)
				(type default)
			)
			(layer "F.SilkS")
		)
		(fp_arc
			(start 1.27 6.700012)
			(mid 0.209252 6.260636)
			(end -0.230124 5.199888)
			(stroke
				(width 0.1524)
				(type default)
			)
			(layer "F.SilkS")
		)
		(fp_arc
			(start 2.770124 5.199888)
			(mid 2.330748 6.260636)
			(end 1.27 6.700012)
			(stroke
				(width 0.1524)
				(type default)
			)
			(layer "F.SilkS")
		)
		(fp_line
			(start -1.080008 -1.999996)
			(end 3.620008 -1.999996)
			(stroke
				(width 0.1)
				(type default)
			)
			(layer "F.Fab")
		)
		(fp_line
			(start -1.080008 3.999992)
			(end -1.080008 -1.999996)
			(stroke
				(width 0.1)
				(type default)
			)
			(layer "F.Fab")
		)
		(fp_line
			(start -0.230124 3.999992)
			(end -1.080008 3.999992)
			(stroke
				(width 0.1)
				(type default)
			)
			(layer "F.Fab")
		)
		(fp_line
			(start -0.230124 5.199888)
			(end -0.230124 3.999992)
			(stroke
				(width 0.1)
				(type default)
			)
			(layer "F.Fab")
		)
		(fp_line
			(start 2.770124 3.999992)
			(end 2.770124 5.199888)
			(stroke
				(width 0.1)
				(type default)
			)
			(layer "F.Fab")
		)
		(fp_line
			(start 3.620008 -1.999996)
			(end 3.620008 3.999992)
			(stroke
				(width 0.1)
				(type default)
			)
			(layer "F.Fab")
		)
		(fp_line
			(start 3.620008 3.999992)
			(end 2.770124 3.999992)
			(stroke
				(width 0.1)
				(type default)
			)
			(layer "F.Fab")
		)
		(fp_arc
			(start 1.27 6.700012)
			(mid 0.209252 6.260636)
			(end -0.230124 5.199888)
			(stroke
				(width 0.1)
				(type default)
			)
			(layer "F.Fab")
		)
		(fp_arc
			(start 2.770124 5.199888)
			(mid 2.330748 6.260636)
			(end 1.27 6.700012)
			(stroke
				(width 0.1)
				(type default)
			)
			(layer "F.Fab")
		)
		(pad "A" thru_hole rect
			(at 0 0)
			(size 1.2192 1.2192)
			(drill 0.8128)
			(layers "*.Cu" "*.Mask")
			(remove_unused_layers no)
			(net "P5V_STBY")
			(clearance 0.0508)
			(thermal_gap 0.0508)
			(padstack
				(mode front_inner_back)
				(layer "Inner"
					(shape circle)
					(size 1.2192 1.2192)
					(clearance 0.0508)
				)
				(layer "B.Cu"
					(shape rect)
					(size 1.2192 1.2192)
					(clearance 0.0508)
				)
			)
		)
		(pad "C" thru_hole circle
			(at 2.54 0)
			(size 1.2192 1.2192)
			(drill 0.8128)
			(layers "*.Cu" "*.Mask")
			(remove_unused_layers no)
			(net "PWR_LED_R2_N")
			(clearance 0.0508)
			(thermal_gap 0.0508)
		)
	)
	(footprint ""
		(layer "F.Cu")
		(at 5.715 -25.654)
		(property "Reference" "U3"
			(at -0.762 1.93167 0)
			(unlocked yes)
			(layer "F.SilkS")
			(effects
				(font
					(size 0.7874 0.5842)
					(thickness 0.1524)
				)
				(justify left)
			)
		)
		(property "Value" ""
			(at 0 0 0)
			(layer "F.Fab")
			(effects
				(font
					(size 1.27 1.27)
				)
			)
		)
		(duplicate_pad_numbers_are_jumpers no)
		(fp_line
			(start -1.335278 -1.100074)
			(end -1.335278 1.100074)
			(stroke
				(width 0.1524)
				(type default)
			)
			(layer "F.SilkS")
		)
		(fp_line
			(start -1.335278 1.100074)
			(end 1.335278 1.100074)
			(stroke
				(width 0.1524)
				(type default)
			)
			(layer "F.SilkS")
		)
		(fp_line
			(start 1.335278 -1.100074)
			(end -1.335278 -1.100074)
			(stroke
				(width 0.1524)
				(type default)
			)
			(layer "F.SilkS")
		)
		(fp_line
			(start 1.335278 1.100074)
			(end 1.335278 -1.100074)
			(stroke
				(width 0.1524)
				(type default)
			)
			(layer "F.SilkS")
		)
		(fp_line
			(start -0.674878 -1.100074)
			(end -0.674878 1.100074)
			(stroke
				(width 0.1)
				(type default)
			)
			(layer "F.Fab")
		)
		(fp_line
			(start -0.674878 1.100074)
			(end 0.674878 1.100074)
			(stroke
				(width 0.1)
				(type default)
			)
			(layer "F.Fab")
		)
		(fp_line
			(start 0.674878 -1.100074)
			(end -0.674878 -1.100074)
			(stroke
				(width 0.1)
				(type default)
			)
			(layer "F.Fab")
		)
		(fp_line
			(start 0.674878 1.100074)
			(end 0.674878 -1.100074)
			(stroke
				(width 0.1)
				(type default)
			)
			(layer "F.Fab")
		)
		(pad "D" smd rect
			(at 0.8001 0 270)
			(size 0.6096 0.8128)
			(layers "F.Cu" "F.Mask" "F.Paste")
			(net "SYSTEM_FAULT_ID_LED_R1_N")
		)
		(pad "G" smd rect
			(at -0.8001 -0.649986 270)
			(size 0.6096 0.8128)
			(layers "F.Cu" "F.Mask" "F.Paste")
			(net "SYSTEM_FAULT_ID_LED_R1")
		)
		(pad "S" smd rect
			(at -0.8001 0.649986 270)
			(size 0.6096 0.8128)
			(layers "F.Cu" "F.Mask" "F.Paste")
			(net "GND")
		)
	)
	(footprint ""
		(layer "F.Cu")
		(at 3.937 -49.784)
		(property "Reference" "R57"
			(at -2.413 0.15367 0)
			(unlocked yes)
			(layer "F.SilkS")
			(effects
				(font
					(size 0.7874 0.5842)
					(thickness 0.1524)
				)
			)
		)
		(property "Value" ""
			(at 0 0 0)
			(layer "F.Fab")
			(effects
				(font
					(size 1.27 1.27)
				)
			)
		)
		(duplicate_pad_numbers_are_jumpers no)
		(fp_line
			(start -0.7874 -0.4064)
			(end 0.7874 -0.4064)
			(stroke
				(width 0.1524)
				(type default)
			)
			(layer "F.SilkS")
		)
		(fp_line
			(start -0.7874 0.4064)
			(end -0.7874 -0.4064)
			(stroke
				(width 0.1524)
				(type default)
			)
			(layer "F.SilkS")
		)
		(fp_line
			(start 0.7874 -0.4064)
			(end 0.7874 0.4064)
			(stroke
				(width 0.1524)
				(type default)
			)
			(layer "F.SilkS")
		)
		(fp_line
			(start 0.7874 0.4064)
			(end -0.7874 0.4064)
			(stroke
				(width 0.1524)
				(type default)
			)
			(layer "F.SilkS")
		)
		(fp_line
			(start -0.67945 -0.305054)
			(end -0.12065 -0.305054)
			(stroke
				(width 0.1)
				(type default)
			)
			(layer "F.Fab")
		)
		(fp_line
			(start -0.67945 0.3048)
			(end -0.67945 -0.305054)
			(stroke
				(width 0.1)
				(type default)
			)
			(layer "F.Fab")
		)
		(fp_line
			(start -0.12065 -0.305054)
			(end -0.12065 -0.2794)
			(stroke
				(width 0.1)
				(type default)
			)
			(layer "F.Fab")
		)
		(fp_line
			(start -0.12065 -0.2794)
			(end 0.12065 -0.2794)
			(stroke
				(width 0.1)
				(type default)
			)
			(layer "F.Fab")
		)
		(fp_line
			(start -0.12065 0.2794)
			(end -0.12065 0.3048)
			(stroke
				(width 0.1)
				(type default)
			)
			(layer "F.Fab")
		)
		(fp_line
			(start -0.12065 0.3048)
			(end -0.67945 0.3048)
			(stroke
				(width 0.1)
				(type default)
			)
			(layer "F.Fab")
		)
		(fp_line
			(start 0.120396 0.2794)
			(end -0.12065 0.2794)
			(stroke
				(width 0.1)
				(type default)
			)
			(layer "F.Fab")
		)
		(fp_line
			(start 0.120396 0.3048)
			(end 0.120396 0.2794)
			(stroke
				(width 0.1)
				(type default)
			)
			(layer "F.Fab")
		)
		(fp_line
			(start 0.12065 -0.3048)
			(end 0.67945 -0.3048)
			(stroke
				(width 0.1)
				(type default)
			)
			(layer "F.Fab")
		)
		(fp_line
			(start 0.12065 -0.2794)
			(end 0.12065 -0.3048)
			(stroke
				(width 0.1)
				(type default)
			)
			(layer "F.Fab")
		)
		(fp_line
			(start 0.67945 -0.3048)
			(end 0.67945 0.3048)
			(stroke
				(width 0.1)
				(type default)
			)
			(layer "F.Fab")
		)
		(fp_line
			(start 0.67945 0.3048)
			(end 0.120396 0.3048)
			(stroke
				(width 0.1)
				(type default)
			)
			(layer "F.Fab")
		)
		(pad "1" smd circle
			(at -0.40005 0)
			(size 0 0)
			(layers "F.Cu" "F.Mask" "F.Paste")
			(net "P3V3_STBY")
		)
		(pad "2" smd circle
			(at 0.40005 0)
			(size 0 0)
			(layers "F.Cu" "F.Mask" "F.Paste")
			(net "PD_FRU_A1")
		)
	)
	(footprint ""
		(layer "F.Cu")
		(at 95.25 -155.194 -90)
		(property "Reference" "J7"
			(at -4.25577 0.54356 0)
			(unlocked yes)
			(layer "F.SilkS")
			(effects
				(font
					(size 0.7874 0.5842)
					(thickness 0.1524)
				)
				(justify left)
			)
		)
		(property "Value" ""
			(at 0 0 270)
			(layer "F.Fab")
			(effects
				(font
					(size 1.27 1.27)
				)
			)
		)
		(duplicate_pad_numbers_are_jumpers no)
		(fp_line
			(start -1.2192 2.1082)
			(end -1.2192 -2.1082)
			(stroke
				(width 0.1524)
				(type default)
			)
			(layer "F.SilkS")
		)
		(fp_line
			(start 1.2192 2.1082)
			(end -1.2192 2.1082)
			(stroke
				(width 0.1524)
				(type default)
			)
			(layer "F.SilkS")
		)
		(fp_line
			(start -1.2192 -2.1082)
			(end 1.2192 -2.1082)
			(stroke
				(width 0.1524)
				(type default)
			)
			(layer "F.SilkS")
		)
		(fp_line
			(start 1.2192 -2.1082)
			(end 1.2192 2.1082)
			(stroke
				(width 0.1524)
				(type default)
			)
			(layer "F.SilkS")
		)
		(pad "" np_thru_hole circle
			(at -2.8829 -1.27 180)
			(size 1.0414 1.0414)
			(drill 1.0414)
			(layers "*.Cu" "*.Mask")
			(clearance 0.381)
			(thermal_gap 0.381)
		)
		(pad "" np_thru_hole circle
			(at -2.8829 1.27 180)
			(size 1.0414 1.0414)
			(drill 1.0414)
			(layers "*.Cu" "*.Mask")
			(clearance 0.381)
			(thermal_gap 0.381)
		)
		(pad "" np_thru_hole circle
			(at 3.4671 -1.27 180)
			(size 1.0414 1.0414)
			(drill 1.0414)
			(layers "*.Cu" "*.Mask")
			(clearance 0.381)
			(thermal_gap 0.381)
		)
		(pad "" np_thru_hole circle
			(at 3.4671 1.27 180)
			(size 1.0414 1.0414)
			(drill 1.0414)
			(layers "*.Cu" "*.Mask")
			(clearance 0.381)
			(thermal_gap 0.381)
		)
		(pad "1" smd rect
			(at 0.8255 -0.249936 180)
			(size 0.3048 0.508)
			(layers "F.Cu" "F.Mask" "F.Paste")
			(net "DELTA_L_85_10INCH_TOP_DP")
		)
		(pad "2" smd rect
			(at 0.8255 0.249936 180)
			(size 0.3048 0.508)
			(layers "F.Cu" "F.Mask" "F.Paste")
			(net "DELTA_L_85_10INCH_TOP_DN")
		)
		(pad "3" smd circle
			(at 0 0 270)
			(size 0 0)
			(layers "F.Cu" "F.Mask" "F.Paste")
			(net "GND1")
		)
		(zone
			(layer "F.Cu")
			(hatch none 0.5)
			(connect_pads
				(clearance 0)
			)
			(min_thickness 0.25)
			(keepout
				(tracks not_allowed)
				(vias allowed)
				(pads allowed)
				(copperpour not_allowed)
				(footprints allowed)
			)
			(placement
				(enabled no)
				(sheetname "")
			)
			(fill
				(thermal_gap 0.5)
				(thermal_bridge_width 0.5)
				(island_removal_mode 0)
			)
			(polygon
				(pts
					(xy 95.79864 -154.0764) (xy 95.703136 -154.0764) (xy 95.703136 -154.6733) (xy 95.296736 -154.6733)
					(xy 95.296736 -154.0764) (xy 95.203264 -154.0764) (xy 95.203264 -154.6733) (xy 94.796864 -154.6733)
					(xy 94.796864 -154.0764) (xy 94.70136 -154.0764) (xy 94.70136 -154.7749) (xy 95.79864 -154.7749)
				)
			)
		)
		(zone
			(layers "F.Cu" "B.Cu" "In1.Cu" "In2.Cu")
			(hatch none 0.5)
			(connect_pads
				(clearance 0)
			)
			(min_thickness 0.25)
			(keepout
				(tracks not_allowed)
				(vias allowed)
				(pads allowed)
				(copperpour not_allowed)
				(footprints allowed)
			)
			(placement
				(enabled no)
				(sheetname "")
			)
			(fill
				(thermal_gap 0.5)
				(thermal_bridge_width 0.5)
				(island_removal_mode 0)
			)
			(polygon
				(pts
					(arc
						(start 94.9071 -158.0769)
						(mid 93.0529 -158.0769)
						(end 94.9071 -158.0769)
					)
				)
			)
		)
		(zone
			(layers "F.Cu" "B.Cu" "In1.Cu" "In2.Cu")
			(hatch none 0.5)
			(connect_pads
				(clearance 0)
			)
			(min_thickness 0.25)
			(keepout
				(tracks not_allowed)
				(vias allowed)
				(pads allowed)
				(copperpour not_allowed)
				(footprints allowed)
			)
			(placement
				(enabled no)
				(sheetname "")
			)
			(fill
				(thermal_gap 0.5)
				(thermal_bridge_width 0.5)
				(island_removal_mode 0)
			)
			(polygon
				(pts
					(arc
						(start 94.9071 -151.7269)
						(mid 93.0529 -151.7269)
						(end 94.9071 -151.7269)
					)
				)
			)
		)
		(zone
			(layers "F.Cu" "B.Cu" "In1.Cu" "In2.Cu")
			(hatch none 0.5)
			(connect_pads
				(clearance 0)
			)
			(min_thickness 0.25)
			(keepout
				(tracks not_allowed)
				(vias allowed)
				(pads allowed)
				(copperpour not_allowed)
				(footprints allowed)
			)
			(placement
				(enabled no)
				(sheetname "")
			)
			(fill
				(thermal_gap 0.5)
				(thermal_bridge_width 0.5)
				(island_removal_mode 0)
			)
			(polygon
				(pts
					(arc
						(start 97.4471 -158.0769)
						(mid 95.5929 -158.0769)
						(end 97.4471 -158.0769)
					)
				)
			)
		)
		(zone
			(layers "F.Cu" "B.Cu" "In1.Cu" "In2.Cu")
			(hatch none 0.5)
			(connect_pads
				(clearance 0)
			)
			(min_thickness 0.25)
			(keepout
				(tracks not_allowed)
				(vias allowed)
				(pads allowed)
				(copperpour not_allowed)
				(footprints allowed)
			)
			(placement
				(enabled no)
				(sheetname "")
			)
			(fill
				(thermal_gap 0.5)
				(thermal_bridge_width 0.5)
				(island_removal_mode 0)
			)
			(polygon
				(pts
					(arc
						(start 97.4471 -151.7269)
						(mid 95.5929 -151.7269)
						(end 97.4471 -151.7269)
					)
				)
			)
		)
	)
	(footprint ""
		(layer "F.Cu")
		(at 95.25 -83.232244 90)
		(property "Reference" "J8"
			(at -4.202684 -0.81153 0)
			(unlocked yes)
			(layer "F.SilkS")
			(effects
				(font
					(size 0.7874 0.5842)
					(thickness 0.1524)
				)
				(justify left)
			)
		)
		(property "Value" ""
			(at 0 0 90)
			(layer "F.Fab")
			(effects
				(font
					(size 1.27 1.27)
				)
			)
		)
		(duplicate_pad_numbers_are_jumpers no)
		(fp_line
			(start 1.2192 -2.1082)
			(end 1.2192 2.1082)
			(stroke
				(width 0.1524)
				(type default)
			)
			(layer "F.SilkS")
		)
		(fp_line
			(start -1.2192 -2.1082)
			(end 1.2192 -2.1082)
			(stroke
				(width 0.1524)
				(type default)
			)
			(layer "F.SilkS")
		)
		(fp_line
			(start 1.2192 2.1082)
			(end -1.2192 2.1082)
			(stroke
				(width 0.1524)
				(type default)
			)
			(layer "F.SilkS")
		)
		(fp_line
			(start -1.2192 2.1082)
			(end -1.2192 -2.1082)
			(stroke
				(width 0.1524)
				(type default)
			)
			(layer "F.SilkS")
		)
		(pad "" np_thru_hole circle
			(at -2.8829 -1.27)
			(size 1.0414 1.0414)
			(drill 1.0414)
			(layers "*.Cu" "*.Mask")
			(clearance 0.381)
			(thermal_gap 0.381)
		)
		(pad "" np_thru_hole circle
			(at -2.8829 1.27)
			(size 1.0414 1.0414)
			(drill 1.0414)
			(layers "*.Cu" "*.Mask")
			(clearance 0.381)
			(thermal_gap 0.381)
		)
		(pad "" np_thru_hole circle
			(at 3.4671 -1.27)
			(size 1.0414 1.0414)
			(drill 1.0414)
			(layers "*.Cu" "*.Mask")
			(clearance 0.381)
			(thermal_gap 0.381)
		)
		(pad "" np_thru_hole circle
			(at 3.4671 1.27)
			(size 1.0414 1.0414)
			(drill 1.0414)
			(layers "*.Cu" "*.Mask")
			(clearance 0.381)
			(thermal_gap 0.381)
		)
		(pad "1" smd rect
			(at 0.8255 -0.249936)
			(size 0.3048 0.508)
			(layers "F.Cu" "F.Mask" "F.Paste")
			(net "DELTA_L_85_10INCH_TOP_DN")
		)
		(pad "2" smd rect
			(at 0.8255 0.249936)
			(size 0.3048 0.508)
			(layers "F.Cu" "F.Mask" "F.Paste")
			(net "DELTA_L_85_10INCH_TOP_DP")
		)
		(pad "3" smd circle
			(at 0 0 90)
			(size 0 0)
			(layers "F.Cu" "F.Mask" "F.Paste")
			(net "GND1")
		)
		(zone
			(layer "F.Cu")
			(hatch none 0.5)
			(connect_pads
				(clearance 0)
			)
			(min_thickness 0.25)
			(keepout
				(tracks not_allowed)
				(vias allowed)
				(pads allowed)
				(copperpour not_allowed)
				(footprints allowed)
			)
			(placement
				(enabled no)
				(sheetname "")
			)
			(fill
				(thermal_gap 0.5)
				(thermal_bridge_width 0.5)
				(island_removal_mode 0)
			)
			(polygon
				(pts
					(xy 94.70136 -84.349844) (xy 94.796864 -84.349844) (xy 94.796864 -83.752944) (xy 95.203264 -83.752944)
					(xy 95.203264 -84.349844) (xy 95.296736 -84.349844) (xy 95.296736 -83.752944) (xy 95.703136 -83.752944)
					(xy 95.703136 -84.349844) (xy 95.79864 -84.349844) (xy 95.79864 -83.651344) (xy 94.70136 -83.651344)
				)
			)
		)
		(zone
			(layers "F.Cu" "B.Cu" "In1.Cu" "In2.Cu")
			(hatch none 0.5)
			(connect_pads
				(clearance 0)
			)
			(min_thickness 0.25)
			(keepout
				(tracks not_allowed)
				(vias allowed)
				(pads allowed)
				(copperpour not_allowed)
				(footprints allowed)
			)
			(placement
				(enabled no)
				(sheetname "")
			)
			(fill
				(thermal_gap 0.5)
				(thermal_bridge_width 0.5)
				(island_removal_mode 0)
			)
			(polygon
				(pts
					(arc
						(start 94.9071 -86.699344)
						(mid 93.0529 -86.699344)
						(end 94.9071 -86.699344)
					)
				)
			)
		)
		(zone
			(layers "F.Cu" "B.Cu" "In1.Cu" "In2.Cu")
			(hatch none 0.5)
			(connect_pads
				(clearance 0)
			)
			(min_thickness 0.25)
			(keepout
				(tracks not_allowed)
				(vias allowed)
				(pads allowed)
				(copperpour not_allowed)
				(footprints allowed)
			)
			(placement
				(enabled no)
				(sheetname "")
			)
			(fill
				(thermal_gap 0.5)
				(thermal_bridge_width 0.5)
				(island_removal_mode 0)
			)
			(polygon
				(pts
					(arc
						(start 94.9071 -80.349344)
						(mid 93.0529 -80.349344)
						(end 94.9071 -80.349344)
					)
				)
			)
		)
		(zone
			(layers "F.Cu" "B.Cu" "In1.Cu" "In2.Cu")
			(hatch none 0.5)
			(connect_pads
				(clearance 0)
			)
			(min_thickness 0.25)
			(keepout
				(tracks not_allowed)
				(vias allowed)
				(pads allowed)
				(copperpour not_allowed)
				(footprints allowed)
			)
			(placement
				(enabled no)
				(sheetname "")
			)
			(fill
				(thermal_gap 0.5)
				(thermal_bridge_width 0.5)
				(island_removal_mode 0)
			)
			(polygon
				(pts
					(arc
						(start 97.4471 -86.699344)
						(mid 95.5929 -86.699344)
						(end 97.4471 -86.699344)
					)
				)
			)
		)
		(zone
			(layers "F.Cu" "B.Cu" "In1.Cu" "In2.Cu")
			(hatch none 0.5)
			(connect_pads
				(clearance 0)
			)
			(min_thickness 0.25)
			(keepout
				(tracks not_allowed)
				(vias allowed)
				(pads allowed)
				(copperpour not_allowed)
				(footprints allowed)
			)
			(placement
				(enabled no)
				(sheetname "")
			)
			(fill
				(thermal_gap 0.5)
				(thermal_bridge_width 0.5)
				(island_removal_mode 0)
			)
			(polygon
				(pts
					(arc
						(start 97.4471 -80.349344)
						(mid 95.5929 -80.349344)
						(end 97.4471 -80.349344)
					)
				)
			)
		)
	)
	(footprint ""
		(layer "F.Cu")
		(at 34.600134 -11.02995 180)
		(property "Reference" "H11"
			(at -2.229866 -4.07162 0)
			(unlocked yes)
			(layer "F.SilkS")
			(effects
				(font
					(size 0.7874 0.5842)
					(thickness 0.1524)
				)
				(justify left)
			)
		)
		(property "Value" ""
			(at 0 0 180)
			(layer "F.Fab")
			(effects
				(font
					(size 1.27 1.27)
				)
			)
		)
		(duplicate_pad_numbers_are_jumpers no)
		(fp_line
			(start 4.126992 0)
			(end 4.126992 3.50012)
			(stroke
				(width 0.1524)
				(type default)
			)
			(layer "F.SilkS")
		)
		(fp_line
			(start -4.126992 3.50012)
			(end -4.126992 0)
			(stroke
				(width 0.1524)
				(type default)
			)
			(layer "F.SilkS")
		)
		(fp_arc
			(start 4.126992 3.50012)
			(mid 0 7.627112)
			(end -4.126992 3.50012)
			(stroke
				(width 0.1524)
				(type default)
			)
			(layer "F.SilkS")
		)
		(fp_arc
			(start -4.126992 0)
			(mid 0 -4.126992)
			(end 4.126992 0)
			(stroke
				(width 0.1524)
				(type default)
			)
			(layer "F.SilkS")
		)
		(fp_line
			(start 4.126992 0)
			(end 4.126992 3.50012)
			(stroke
				(width 0.1524)
				(type default)
			)
			(layer "B.SilkS")
		)
		(fp_line
			(start -4.126992 3.50012)
			(end -4.126992 0)
			(stroke
				(width 0.1524)
				(type default)
			)
			(layer "B.SilkS")
		)
		(fp_arc
			(start 4.126992 3.50012)
			(mid 0 7.627112)
			(end -4.126992 3.50012)
			(stroke
				(width 0.1524)
				(type default)
			)
			(layer "B.SilkS")
		)
		(fp_arc
			(start -4.126992 0)
			(mid 0 -4.126992)
			(end 4.126992 0)
			(stroke
				(width 0.1524)
				(type default)
			)
			(layer "B.SilkS")
		)
		(fp_line
			(start 4.126992 0)
			(end 4.126992 3.50012)
			(stroke
				(width 0.1)
				(type default)
			)
			(layer "B.Fab")
		)
		(fp_line
			(start -4.126992 3.50012)
			(end -4.126992 0)
			(stroke
				(width 0.1)
				(type default)
			)
			(layer "B.Fab")
		)
		(fp_arc
			(start 4.126992 3.50012)
			(mid 0 7.627112)
			(end -4.126992 3.50012)
			(stroke
				(width 0.1)
				(type default)
			)
			(layer "B.Fab")
		)
		(fp_arc
			(start -4.126992 0)
			(mid 0 -4.126992)
			(end 4.126992 0)
			(stroke
				(width 0.1)
				(type default)
			)
			(layer "B.Fab")
		)
		(fp_line
			(start 4.126992 0)
			(end 4.126992 3.50012)
			(stroke
				(width 0.1)
				(type default)
			)
			(layer "F.Fab")
		)
		(fp_line
			(start -4.126992 3.50012)
			(end -4.126992 0)
			(stroke
				(width 0.1)
				(type default)
			)
			(layer "F.Fab")
		)
		(fp_arc
			(start 4.126992 3.50012)
			(mid 0 7.627112)
			(end -4.126992 3.50012)
			(stroke
				(width 0.1)
				(type default)
			)
			(layer "F.Fab")
		)
		(fp_arc
			(start -4.126992 0)
			(mid 0 -4.126992)
			(end 4.126992 0)
			(stroke
				(width 0.1)
				(type default)
			)
			(layer "F.Fab")
		)
		(pad "" np_thru_hole circle
			(at 0 0 180)
			(size 3.0226 3.0226)
			(drill 3.0226)
			(layers "*.Cu" "*.Mask")
			(clearance 0.381)
			(thermal_gap 0.381)
		)
		(zone
			(layers "F.Cu" "B.Cu" "In1.Cu" "In2.Cu")
			(hatch none 0.5)
			(connect_pads
				(clearance 0)
			)
			(min_thickness 0.25)
			(keepout
				(tracks not_allowed)
				(vias allowed)
				(pads allowed)
				(copperpour not_allowed)
				(footprints allowed)
			)
			(placement
				(enabled no)
				(sheetname "")
			)
			(fill
				(thermal_gap 0.5)
				(thermal_bridge_width 0.5)
				(island_removal_mode 0)
			)
			(polygon
				(pts
					(arc
						(start 32.26054 -12.639294)
						(mid 34.600134 -17.537768)
						(end 36.939728 -12.639294)
					)
					(arc
						(start 36.939728 -12.639294)
						(mid 36.693555 -12.198846)
						(end 36.608258 -11.701526)
					)
					(arc
						(start 36.608258 -11.02995)
						(mid 34.600134 -9.021826)
						(end 32.59201 -11.02995)
					)
					(arc
						(start 32.59201 -11.701526)
						(mid 32.506704 -12.198839)
						(end 32.26054 -12.639294)
					)
				)
			)
		)
	)
	(footprint ""
		(layer "F.Cu")
		(at 16.51 -19.685 -90)
		(property "Reference" "R29"
			(at -2.032 0.60833 90)
			(unlocked yes)
			(layer "F.SilkS")
			(effects
				(font
					(size 0.7874 0.5842)
					(thickness 0.1524)
				)
			)
		)
		(property "Value" ""
			(at 0 0 270)
			(layer "F.Fab")
			(effects
				(font
					(size 1.27 1.27)
				)
			)
		)
		(duplicate_pad_numbers_are_jumpers no)
		(fp_line
			(start -0.7874 0.4064)
			(end -0.7874 -0.4064)
			(stroke
				(width 0.1524)
				(type default)
			)
			(layer "F.SilkS")
		)
		(fp_line
			(start 0.7874 0.4064)
			(end -0.7874 0.4064)
			(stroke
				(width 0.1524)
				(type default)
			)
			(layer "F.SilkS")
		)
		(fp_line
			(start -0.7874 -0.4064)
			(end 0.7874 -0.4064)
			(stroke
				(width 0.1524)
				(type default)
			)
			(layer "F.SilkS")
		)
		(fp_line
			(start 0.7874 -0.4064)
			(end 0.7874 0.4064)
			(stroke
				(width 0.1524)
				(type default)
			)
			(layer "F.SilkS")
		)
		(fp_line
			(start -0.67945 0.3048)
			(end -0.67945 -0.305054)
			(stroke
				(width 0.1)
				(type default)
			)
			(layer "F.Fab")
		)
		(fp_line
			(start -0.12065 0.3048)
			(end -0.67945 0.3048)
			(stroke
				(width 0.1)
				(type default)
			)
			(layer "F.Fab")
		)
		(fp_line
			(start 0.120396 0.3048)
			(end 0.120396 0.2794)
			(stroke
				(width 0.1)
				(type default)
			)
			(layer "F.Fab")
		)
		(fp_line
			(start 0.67945 0.3048)
			(end 0.120396 0.3048)
			(stroke
				(width 0.1)
				(type default)
			)
			(layer "F.Fab")
		)
		(fp_line
			(start -0.12065 0.2794)
			(end -0.12065 0.3048)
			(stroke
				(width 0.1)
				(type default)
			)
			(layer "F.Fab")
		)
		(fp_line
			(start 0.120396 0.2794)
			(end -0.12065 0.2794)
			(stroke
				(width 0.1)
				(type default)
			)
			(layer "F.Fab")
		)
		(fp_line
			(start -0.12065 -0.2794)
			(end 0.12065 -0.2794)
			(stroke
				(width 0.1)
				(type default)
			)
			(layer "F.Fab")
		)
		(fp_line
			(start 0.12065 -0.2794)
			(end 0.12065 -0.3048)
			(stroke
				(width 0.1)
				(type default)
			)
			(layer "F.Fab")
		)
		(fp_line
			(start 0.12065 -0.3048)
			(end 0.67945 -0.3048)
			(stroke
				(width 0.1)
				(type default)
			)
			(layer "F.Fab")
		)
		(fp_line
			(start 0.67945 -0.3048)
			(end 0.67945 0.3048)
			(stroke
				(width 0.1)
				(type default)
			)
			(layer "F.Fab")
		)
		(fp_line
			(start -0.67945 -0.305054)
			(end -0.12065 -0.305054)
			(stroke
				(width 0.1)
				(type default)
			)
			(layer "F.Fab")
		)
		(fp_line
			(start -0.12065 -0.305054)
			(end -0.12065 -0.2794)
			(stroke
				(width 0.1)
				(type default)
			)
			(layer "F.Fab")
		)
		(pad "1" smd circle
			(at -0.40005 0 270)
			(size 0 0)
			(layers "F.Cu" "F.Mask" "F.Paste")
			(net "P3V3_STBY")
		)
		(pad "2" smd circle
			(at 0.40005 0 270)
			(size 0 0)
			(layers "F.Cu" "F.Mask" "F.Paste")
			(net "THERMAL_OS")
		)
	)
	(footprint ""
		(layer "F.Cu")
		(at 5.969 -56.261 180)
		(property "Reference" "R27"
			(at 2.794 -0.40767 0)
			(unlocked yes)
			(layer "F.SilkS")
			(effects
				(font
					(size 0.7874 0.5842)
					(thickness 0.1524)
				)
			)
		)
		(property "Value" ""
			(at 0 0 180)
			(layer "F.Fab")
			(effects
				(font
					(size 1.27 1.27)
				)
			)
		)
		(duplicate_pad_numbers_are_jumpers no)
		(fp_line
			(start 0.7874 0.4064)
			(end -0.7874 0.4064)
			(stroke
				(width 0.1524)
				(type default)
			)
			(layer "F.SilkS")
		)
		(fp_line
			(start 0.7874 -0.4064)
			(end 0.7874 0.4064)
			(stroke
				(width 0.1524)
				(type default)
			)
			(layer "F.SilkS")
		)
		(fp_line
			(start -0.7874 0.4064)
			(end -0.7874 -0.4064)
			(stroke
				(width 0.1524)
				(type default)
			)
			(layer "F.SilkS")
		)
		(fp_line
			(start -0.7874 -0.4064)
			(end 0.7874 -0.4064)
			(stroke
				(width 0.1524)
				(type default)
			)
			(layer "F.SilkS")
		)
		(fp_line
			(start 0.67945 0.3048)
			(end 0.120396 0.3048)
			(stroke
				(width 0.1)
				(type default)
			)
			(layer "F.Fab")
		)
		(fp_line
			(start 0.67945 -0.3048)
			(end 0.67945 0.3048)
			(stroke
				(width 0.1)
				(type default)
			)
			(layer "F.Fab")
		)
		(fp_line
			(start 0.12065 -0.2794)
			(end 0.12065 -0.3048)
			(stroke
				(width 0.1)
				(type default)
			)
			(layer "F.Fab")
		)
		(fp_line
			(start 0.12065 -0.3048)
			(end 0.67945 -0.3048)
			(stroke
				(width 0.1)
				(type default)
			)
			(layer "F.Fab")
		)
		(fp_line
			(start 0.120396 0.3048)
			(end 0.120396 0.2794)
			(stroke
				(width 0.1)
				(type default)
			)
			(layer "F.Fab")
		)
		(fp_line
			(start 0.120396 0.2794)
			(end -0.12065 0.2794)
			(stroke
				(width 0.1)
				(type default)
			)
			(layer "F.Fab")
		)
		(fp_line
			(start -0.12065 0.3048)
			(end -0.67945 0.3048)
			(stroke
				(width 0.1)
				(type default)
			)
			(layer "F.Fab")
		)
		(fp_line
			(start -0.12065 0.2794)
			(end -0.12065 0.3048)
			(stroke
				(width 0.1)
				(type default)
			)
			(layer "F.Fab")
		)
		(fp_line
			(start -0.12065 -0.2794)
			(end 0.12065 -0.2794)
			(stroke
				(width 0.1)
				(type default)
			)
			(layer "F.Fab")
		)
		(fp_line
			(start -0.12065 -0.305054)
			(end -0.12065 -0.2794)
			(stroke
				(width 0.1)
				(type default)
			)
			(layer "F.Fab")
		)
		(fp_line
			(start -0.67945 0.3048)
			(end -0.67945 -0.305054)
			(stroke
				(width 0.1)
				(type default)
			)
			(layer "F.Fab")
		)
		(fp_line
			(start -0.67945 -0.305054)
			(end -0.12065 -0.305054)
			(stroke
				(width 0.1)
				(type default)
			)
			(layer "F.Fab")
		)
		(pad "1" smd circle
			(at -0.40005 0 180)
			(size 0 0)
			(layers "F.Cu" "F.Mask" "F.Paste")
			(net "REV_ID<1>")
		)
		(pad "2" smd circle
			(at 0.40005 0 180)
			(size 0 0)
			(layers "F.Cu" "F.Mask" "F.Paste")
			(net "GND")
		)
	)
	(footprint ""
		(layer "F.Cu")
		(at 5.715 -28.448)
		(property "Reference" "U4"
			(at -0.635 -1.75133 0)
			(unlocked yes)
			(layer "F.SilkS")
			(effects
				(font
					(size 0.7874 0.5842)
					(thickness 0.1524)
				)
				(justify left)
			)
		)
		(property "Value" ""
			(at 0 0 0)
			(layer "F.Fab")
			(effects
				(font
					(size 1.27 1.27)
				)
			)
		)
		(duplicate_pad_numbers_are_jumpers no)
		(fp_line
			(start -1.335278 -1.100074)
			(end -1.335278 1.100074)
			(stroke
				(width 0.1524)
				(type default)
			)
			(layer "F.SilkS")
		)
		(fp_line
			(start -1.335278 1.100074)
			(end 1.335278 1.100074)
			(stroke
				(width 0.1524)
				(type default)
			)
			(layer "F.SilkS")
		)
		(fp_line
			(start 1.335278 -1.100074)
			(end -1.335278 -1.100074)
			(stroke
				(width 0.1524)
				(type default)
			)
			(layer "F.SilkS")
		)
		(fp_line
			(start 1.335278 1.100074)
			(end 1.335278 -1.100074)
			(stroke
				(width 0.1524)
				(type default)
			)
			(layer "F.SilkS")
		)
		(fp_line
			(start -0.674878 -1.100074)
			(end -0.674878 1.100074)
			(stroke
				(width 0.1)
				(type default)
			)
			(layer "F.Fab")
		)
		(fp_line
			(start -0.674878 1.100074)
			(end 0.674878 1.100074)
			(stroke
				(width 0.1)
				(type default)
			)
			(layer "F.Fab")
		)
		(fp_line
			(start 0.674878 -1.100074)
			(end -0.674878 -1.100074)
			(stroke
				(width 0.1)
				(type default)
			)
			(layer "F.Fab")
		)
		(fp_line
			(start 0.674878 1.100074)
			(end 0.674878 -1.100074)
			(stroke
				(width 0.1)
				(type default)
			)
			(layer "F.Fab")
		)
		(pad "D" smd rect
			(at 0.8001 0 270)
			(size 0.6096 0.8128)
			(layers "F.Cu" "F.Mask" "F.Paste")
			(net "PWR_LED_R1_N")
		)
		(pad "G" smd rect
			(at -0.8001 -0.649986 270)
			(size 0.6096 0.8128)
			(layers "F.Cu" "F.Mask" "F.Paste")
			(net "PWR_LED_R1")
		)
		(pad "S" smd rect
			(at -0.8001 0.649986 270)
			(size 0.6096 0.8128)
			(layers "F.Cu" "F.Mask" "F.Paste")
			(net "GND")
		)
	)
	(footprint ""
		(layer "F.Cu")
		(at 35.941 -32.385)
		(property "Reference" "C12"
			(at 0.762 -5.43433 0)
			(unlocked yes)
			(layer "F.SilkS")
			(effects
				(font
					(size 0.7874 0.5842)
					(thickness 0.1524)
				)
				(justify left)
			)
		)
		(property "Value" ""
			(at 0 0 0)
			(layer "F.Fab")
			(effects
				(font
					(size 1.27 1.27)
				)
			)
		)
		(duplicate_pad_numbers_are_jumpers no)
		(fp_line
			(start -1.524 -0.762)
			(end 1.524 -0.762)
			(stroke
				(width 0.1524)
				(type default)
			)
			(layer "F.SilkS")
		)
		(fp_line
			(start -1.524 0.762)
			(end -1.524 -0.762)
			(stroke
				(width 0.1524)
				(type default)
			)
			(layer "F.SilkS")
		)
		(fp_line
			(start 1.524 -0.762)
			(end 1.524 0.762)
			(stroke
				(width 0.1524)
				(type default)
			)
			(layer "F.SilkS")
		)
		(fp_line
			(start 1.524 0.762)
			(end -1.524 0.762)
			(stroke
				(width 0.1524)
				(type default)
			)
			(layer "F.SilkS")
		)
		(fp_line
			(start -1.1049 -0.724916)
			(end -1.1049 0.724916)
			(stroke
				(width 0.1)
				(type default)
			)
			(layer "F.Fab")
		)
		(fp_line
			(start -1.1049 0.724916)
			(end 1.1049 0.724916)
			(stroke
				(width 0.1)
				(type default)
			)
			(layer "F.Fab")
		)
		(fp_line
			(start 1.1049 -0.724916)
			(end -1.1049 -0.724916)
			(stroke
				(width 0.1)
				(type default)
			)
			(layer "F.Fab")
		)
		(fp_line
			(start 1.1049 0.724916)
			(end 1.1049 -0.724916)
			(stroke
				(width 0.1)
				(type default)
			)
			(layer "F.Fab")
		)
		(pad "1" smd rect
			(at -0.889 0 180)
			(size 1.016 1.27)
			(layers "F.Cu" "F.Mask" "F.Paste")
			(net "P5V_STBY_DEBUG")
		)
		(pad "2" smd rect
			(at 0.889 0 180)
			(size 1.016 1.27)
			(layers "F.Cu" "F.Mask" "F.Paste")
			(net "GND")
		)
	)
	(footprint ""
		(layer "F.Cu")
		(at 5.969 -60.325 180)
		(property "Reference" "C6"
			(at 3.175 -0.40767 0)
			(unlocked yes)
			(layer "F.SilkS")
			(effects
				(font
					(size 0.7874 0.5842)
					(thickness 0.1524)
				)
			)
		)
		(property "Value" ""
			(at 0 0 180)
			(layer "F.Fab")
			(effects
				(font
					(size 1.27 1.27)
				)
			)
		)
		(duplicate_pad_numbers_are_jumpers no)
		(fp_line
			(start 0.7874 0.4064)
			(end -0.7874 0.4064)
			(stroke
				(width 0.1524)
				(type default)
			)
			(layer "F.SilkS")
		)
		(fp_line
			(start 0.7874 -0.4064)
			(end 0.7874 0.4064)
			(stroke
				(width 0.1524)
				(type default)
			)
			(layer "F.SilkS")
		)
		(fp_line
			(start -0.7874 0.4064)
			(end -0.7874 -0.4064)
			(stroke
				(width 0.1524)
				(type default)
			)
			(layer "F.SilkS")
		)
		(fp_line
			(start -0.7874 -0.4064)
			(end 0.7874 -0.4064)
			(stroke
				(width 0.1524)
				(type default)
			)
			(layer "F.SilkS")
		)
		(fp_line
			(start 0.67945 0.3048)
			(end 0.120396 0.3048)
			(stroke
				(width 0.1)
				(type default)
			)
			(layer "F.Fab")
		)
		(fp_line
			(start 0.67945 -0.3048)
			(end 0.67945 0.3048)
			(stroke
				(width 0.1)
				(type default)
			)
			(layer "F.Fab")
		)
		(fp_line
			(start 0.12065 -0.2794)
			(end 0.12065 -0.3048)
			(stroke
				(width 0.1)
				(type default)
			)
			(layer "F.Fab")
		)
		(fp_line
			(start 0.12065 -0.3048)
			(end 0.67945 -0.3048)
			(stroke
				(width 0.1)
				(type default)
			)
			(layer "F.Fab")
		)
		(fp_line
			(start 0.120396 0.3048)
			(end 0.120396 0.2794)
			(stroke
				(width 0.1)
				(type default)
			)
			(layer "F.Fab")
		)
		(fp_line
			(start 0.120396 0.2794)
			(end -0.12065 0.2794)
			(stroke
				(width 0.1)
				(type default)
			)
			(layer "F.Fab")
		)
		(fp_line
			(start -0.12065 0.3048)
			(end -0.67945 0.3048)
			(stroke
				(width 0.1)
				(type default)
			)
			(layer "F.Fab")
		)
		(fp_line
			(start -0.12065 0.2794)
			(end -0.12065 0.3048)
			(stroke
				(width 0.1)
				(type default)
			)
			(layer "F.Fab")
		)
		(fp_line
			(start -0.12065 -0.2794)
			(end 0.12065 -0.2794)
			(stroke
				(width 0.1)
				(type default)
			)
			(layer "F.Fab")
		)
		(fp_line
			(start -0.12065 -0.305054)
			(end -0.12065 -0.2794)
			(stroke
				(width 0.1)
				(type default)
			)
			(layer "F.Fab")
		)
		(fp_line
			(start -0.67945 0.3048)
			(end -0.67945 -0.305054)
			(stroke
				(width 0.1)
				(type default)
			)
			(layer "F.Fab")
		)
		(fp_line
			(start -0.67945 -0.305054)
			(end -0.12065 -0.305054)
			(stroke
				(width 0.1)
				(type default)
			)
			(layer "F.Fab")
		)
		(pad "1" smd circle
			(at -0.40005 0 180)
			(size 0 0)
			(layers "F.Cu" "F.Mask" "F.Paste")
			(net "RST_SMB_R_N")
		)
		(pad "2" smd circle
			(at 0.40005 0 180)
			(size 0 0)
			(layers "F.Cu" "F.Mask" "F.Paste")
			(net "GND")
		)
	)
	(footprint ""
		(layer "F.Cu")
		(at 15.491206 -33.504124)
		(property "Reference" "H2"
			(at -4.061206 -0.886206 0)
			(unlocked yes)
			(layer "F.SilkS")
			(effects
				(font
					(size 0.7874 0.5842)
					(thickness 0.1524)
				)
				(justify left)
			)
		)
		(property "Value" ""
			(at 0 0 0)
			(layer "F.Fab")
			(effects
				(font
					(size 1.27 1.27)
				)
			)
		)
		(duplicate_pad_numbers_are_jumpers no)
		(fp_circle
			(center 0 0)
			(end 2.4003 0)
			(stroke
				(width 0.1524)
				(type default)
			)
			(fill no)
			(layer "F.SilkS")
		)
		(fp_arc
			(start 5.208524 4.039108)
			(mid -6.591207 -0.031941)
			(end 5.247132 -3.989324)
			(stroke
				(width 0.1524)
				(type default)
			)
			(layer "B.SilkS")
		)
		(fp_circle
			(center 0 0)
			(end 6.5913 0)
			(stroke
				(width 0.1)
				(type default)
			)
			(fill no)
			(layer "B.Fab")
		)
		(fp_circle
			(center 0 0)
			(end 2.4003 0)
			(stroke
				(width 0.1)
				(type default)
			)
			(fill no)
			(layer "F.Fab")
		)
		(pad "" np_thru_hole circle
			(at 0 0)
			(size 3.175 3.175)
			(drill 3.175)
			(layers "*.Cu" "*.Mask")
			(clearance 0.381)
			(thermal_gap 0.381)
		)
		(zone
			(layers "F.Cu" "B.Cu" "In1.Cu" "In2.Cu")
			(hatch none 0.5)
			(connect_pads
				(clearance 0)
			)
			(min_thickness 0.25)
			(keepout
				(tracks not_allowed)
				(vias allowed)
				(pads allowed)
				(copperpour not_allowed)
				(footprints allowed)
			)
			(placement
				(enabled no)
				(sheetname "")
			)
			(fill
				(thermal_gap 0.5)
				(thermal_bridge_width 0.5)
				(island_removal_mode 0)
			)
			(polygon
				(pts
					(arc
						(start 17.586706 -33.504124)
						(mid 13.395706 -33.504124)
						(end 17.586706 -33.504124)
					)
				)
			)
		)
	)
	(footprint ""
		(layer "F.Cu")
		(at 19.49577 -10.967974 -90)
		(property "Reference" "R3"
			(at 2.839974 -1.2319 90)
			(unlocked yes)
			(layer "F.SilkS")
			(effects
				(font
					(size 0.7874 0.5842)
					(thickness 0.1524)
				)
				(justify left)
			)
		)
		(property "Value" ""
			(at 0 0 270)
			(layer "F.Fab")
			(effects
				(font
					(size 1.27 1.27)
				)
			)
		)
		(duplicate_pad_numbers_are_jumpers no)
		(fp_line
			(start -1.651 0.8382)
			(end -1.651 -0.8382)
			(stroke
				(width 0.1524)
				(type default)
			)
			(layer "F.SilkS")
		)
		(fp_line
			(start 1.651 0.8382)
			(end -1.651 0.8382)
			(stroke
				(width 0.1524)
				(type default)
			)
			(layer "F.SilkS")
		)
		(fp_line
			(start -1.651 -0.8382)
			(end 1.651 -0.8382)
			(stroke
				(width 0.1524)
				(type default)
			)
			(layer "F.SilkS")
		)
		(fp_line
			(start 1.651 -0.8382)
			(end 1.651 0.8382)
			(stroke
				(width 0.1524)
				(type default)
			)
			(layer "F.SilkS")
		)
		(fp_line
			(start -1.559814 0.7366)
			(end -1.524 0.7366)
			(stroke
				(width 0.1)
				(type default)
			)
			(layer "F.Fab")
		)
		(fp_line
			(start -1.524 0.7366)
			(end 1.524 0.7366)
			(stroke
				(width 0.1)
				(type default)
			)
			(layer "F.Fab")
		)
		(fp_line
			(start 1.524 0.7366)
			(end 1.560576 0.7366)
			(stroke
				(width 0.1)
				(type default)
			)
			(layer "F.Fab")
		)
		(fp_line
			(start 1.560576 0.7366)
			(end 1.560576 -0.7366)
			(stroke
				(width 0.1)
				(type default)
			)
			(layer "F.Fab")
		)
		(fp_line
			(start -1.559814 -0.7366)
			(end -1.559814 0.7366)
			(stroke
				(width 0.1)
				(type default)
			)
			(layer "F.Fab")
		)
		(fp_line
			(start -1.524 -0.7366)
			(end -1.559814 -0.7366)
			(stroke
				(width 0.1)
				(type default)
			)
			(layer "F.Fab")
		)
		(fp_line
			(start 1.524 -0.7366)
			(end -1.524 -0.7366)
			(stroke
				(width 0.1)
				(type default)
			)
			(layer "F.Fab")
		)
		(fp_line
			(start 1.560576 -0.7366)
			(end 1.524 -0.7366)
			(stroke
				(width 0.1)
				(type default)
			)
			(layer "F.Fab")
		)
		(pad "1" smd rect
			(at -0.94996 0 90)
			(size 1.1176 1.3716)
			(layers "F.Cu" "F.Mask" "F.Paste")
			(net "P5V_STBY")
		)
		(pad "2" smd rect
			(at 0.94996 0 90)
			(size 1.1176 1.3716)
			(layers "F.Cu" "F.Mask" "F.Paste")
			(net "FM_PFR_LED_BLUE_R")
		)
	)
	(footprint ""
		(layer "F.Cu")
		(at 17.399 -17.145)
		(property "Reference" "R4"
			(at -1.651 0.02667 0)
			(unlocked yes)
			(layer "F.SilkS")
			(effects
				(font
					(size 0.7874 0.5842)
					(thickness 0.1524)
				)
			)
		)
		(property "Value" ""
			(at 0 0 0)
			(layer "F.Fab")
			(effects
				(font
					(size 1.27 1.27)
				)
			)
		)
		(duplicate_pad_numbers_are_jumpers no)
		(fp_line
			(start -0.7874 -0.4064)
			(end 0.7874 -0.4064)
			(stroke
				(width 0.1524)
				(type default)
			)
			(layer "F.SilkS")
		)
		(fp_line
			(start -0.7874 0.4064)
			(end -0.7874 -0.4064)
			(stroke
				(width 0.1524)
				(type default)
			)
			(layer "F.SilkS")
		)
		(fp_line
			(start 0.7874 -0.4064)
			(end 0.7874 0.4064)
			(stroke
				(width 0.1524)
				(type default)
			)
			(layer "F.SilkS")
		)
		(fp_line
			(start 0.7874 0.4064)
			(end -0.7874 0.4064)
			(stroke
				(width 0.1524)
				(type default)
			)
			(layer "F.SilkS")
		)
		(fp_line
			(start -0.67945 -0.305054)
			(end -0.12065 -0.305054)
			(stroke
				(width 0.1)
				(type default)
			)
			(layer "F.Fab")
		)
		(fp_line
			(start -0.67945 0.3048)
			(end -0.67945 -0.305054)
			(stroke
				(width 0.1)
				(type default)
			)
			(layer "F.Fab")
		)
		(fp_line
			(start -0.12065 -0.305054)
			(end -0.12065 -0.2794)
			(stroke
				(width 0.1)
				(type default)
			)
			(layer "F.Fab")
		)
		(fp_line
			(start -0.12065 -0.2794)
			(end 0.12065 -0.2794)
			(stroke
				(width 0.1)
				(type default)
			)
			(layer "F.Fab")
		)
		(fp_line
			(start -0.12065 0.2794)
			(end -0.12065 0.3048)
			(stroke
				(width 0.1)
				(type default)
			)
			(layer "F.Fab")
		)
		(fp_line
			(start -0.12065 0.3048)
			(end -0.67945 0.3048)
			(stroke
				(width 0.1)
				(type default)
			)
			(layer "F.Fab")
		)
		(fp_line
			(start 0.120396 0.2794)
			(end -0.12065 0.2794)
			(stroke
				(width 0.1)
				(type default)
			)
			(layer "F.Fab")
		)
		(fp_line
			(start 0.120396 0.3048)
			(end 0.120396 0.2794)
			(stroke
				(width 0.1)
				(type default)
			)
			(layer "F.Fab")
		)
		(fp_line
			(start 0.12065 -0.3048)
			(end 0.67945 -0.3048)
			(stroke
				(width 0.1)
				(type default)
			)
			(layer "F.Fab")
		)
		(fp_line
			(start 0.12065 -0.2794)
			(end 0.12065 -0.3048)
			(stroke
				(width 0.1)
				(type default)
			)
			(layer "F.Fab")
		)
		(fp_line
			(start 0.67945 -0.3048)
			(end 0.67945 0.3048)
			(stroke
				(width 0.1)
				(type default)
			)
			(layer "F.Fab")
		)
		(fp_line
			(start 0.67945 0.3048)
			(end 0.120396 0.3048)
			(stroke
				(width 0.1)
				(type default)
			)
			(layer "F.Fab")
		)
		(pad "1" smd circle
			(at -0.40005 0)
			(size 0 0)
			(layers "F.Cu" "F.Mask" "F.Paste")
			(net "FM_PFR_LED_BLUE_N")
		)
		(pad "2" smd circle
			(at 0.40005 0)
			(size 0 0)
			(layers "F.Cu" "F.Mask" "F.Paste")
			(net "FM_PFR_LED_BLUE_R_N")
		)
	)
	(footprint ""
		(layer "F.Cu")
		(at 36.703 -21.336 180)
		(property "Reference" "R33"
			(at 2.032 -0.02667 0)
			(unlocked yes)
			(layer "F.SilkS")
			(effects
				(font
					(size 0.7874 0.5842)
					(thickness 0.1524)
				)
			)
		)
		(property "Value" ""
			(at 0 0 180)
			(layer "F.Fab")
			(effects
				(font
					(size 1.27 1.27)
				)
			)
		)
		(duplicate_pad_numbers_are_jumpers no)
		(fp_line
			(start 0.7874 0.4064)
			(end -0.7874 0.4064)
			(stroke
				(width 0.1524)
				(type default)
			)
			(layer "F.SilkS")
		)
		(fp_line
			(start 0.7874 -0.4064)
			(end 0.7874 0.4064)
			(stroke
				(width 0.1524)
				(type default)
			)
			(layer "F.SilkS")
		)
		(fp_line
			(start -0.7874 0.4064)
			(end -0.7874 -0.4064)
			(stroke
				(width 0.1524)
				(type default)
			)
			(layer "F.SilkS")
		)
		(fp_line
			(start -0.7874 -0.4064)
			(end 0.7874 -0.4064)
			(stroke
				(width 0.1524)
				(type default)
			)
			(layer "F.SilkS")
		)
		(fp_line
			(start 0.67945 0.3048)
			(end 0.120396 0.3048)
			(stroke
				(width 0.1)
				(type default)
			)
			(layer "F.Fab")
		)
		(fp_line
			(start 0.67945 -0.3048)
			(end 0.67945 0.3048)
			(stroke
				(width 0.1)
				(type default)
			)
			(layer "F.Fab")
		)
		(fp_line
			(start 0.12065 -0.2794)
			(end 0.12065 -0.3048)
			(stroke
				(width 0.1)
				(type default)
			)
			(layer "F.Fab")
		)
		(fp_line
			(start 0.12065 -0.3048)
			(end 0.67945 -0.3048)
			(stroke
				(width 0.1)
				(type default)
			)
			(layer "F.Fab")
		)
		(fp_line
			(start 0.120396 0.3048)
			(end 0.120396 0.2794)
			(stroke
				(width 0.1)
				(type default)
			)
			(layer "F.Fab")
		)
		(fp_line
			(start 0.120396 0.2794)
			(end -0.12065 0.2794)
			(stroke
				(width 0.1)
				(type default)
			)
			(layer "F.Fab")
		)
		(fp_line
			(start -0.12065 0.3048)
			(end -0.67945 0.3048)
			(stroke
				(width 0.1)
				(type default)
			)
			(layer "F.Fab")
		)
		(fp_line
			(start -0.12065 0.2794)
			(end -0.12065 0.3048)
			(stroke
				(width 0.1)
				(type default)
			)
			(layer "F.Fab")
		)
		(fp_line
			(start -0.12065 -0.2794)
			(end 0.12065 -0.2794)
			(stroke
				(width 0.1)
				(type default)
			)
			(layer "F.Fab")
		)
		(fp_line
			(start -0.12065 -0.305054)
			(end -0.12065 -0.2794)
			(stroke
				(width 0.1)
				(type default)
			)
			(layer "F.Fab")
		)
		(fp_line
			(start -0.67945 0.3048)
			(end -0.67945 -0.305054)
			(stroke
				(width 0.1)
				(type default)
			)
			(layer "F.Fab")
		)
		(fp_line
			(start -0.67945 -0.305054)
			(end -0.12065 -0.305054)
			(stroke
				(width 0.1)
				(type default)
			)
			(layer "F.Fab")
		)
		(pad "1" smd circle
			(at -0.40005 0 180)
			(size 0 0)
			(layers "F.Cu" "F.Mask" "F.Paste")
			(net "P3V3_STBY")
		)
		(pad "2" smd circle
			(at 0.40005 0 180)
			(size 0 0)
			(layers "F.Cu" "F.Mask" "F.Paste")
			(net "THERMAL_ADDR_A1")
		)
	)
	(footprint ""
		(layer "F.Cu")
		(at 12.192 -57.912)
		(property "Reference" "U5"
			(at -3.429 -5.81533 0)
			(unlocked yes)
			(layer "F.SilkS")
			(effects
				(font
					(size 0.7874 0.5842)
					(thickness 0.1524)
				)
				(justify left)
			)
		)
		(property "Value" ""
			(at 0 0 0)
			(layer "F.Fab")
			(effects
				(font
					(size 1.27 1.27)
				)
			)
		)
		(duplicate_pad_numbers_are_jumpers no)
		(fp_line
			(start -2.097532 -3.949954)
			(end -2.097532 3.949954)
			(stroke
				(width 0.1524)
				(type default)
			)
			(layer "F.SilkS")
		)
		(fp_line
			(start -2.097532 3.949954)
			(end 2.097532 3.949954)
			(stroke
				(width 0.1524)
				(type default)
			)
			(layer "F.SilkS")
		)
		(fp_line
			(start -1.409954 -3.949954)
			(end -2.097532 -3.949954)
			(stroke
				(width 0.1524)
				(type default)
			)
			(layer "F.SilkS")
		)
		(fp_line
			(start 0 -2.54)
			(end -1.409954 -3.949954)
			(stroke
				(width 0.1524)
				(type default)
			)
			(layer "F.SilkS")
		)
		(fp_line
			(start 1.409954 -3.949954)
			(end 0 -2.54)
			(stroke
				(width 0.1524)
				(type default)
			)
			(layer "F.SilkS")
		)
		(fp_line
			(start 2.097532 -3.949954)
			(end 1.409954 -3.949954)
			(stroke
				(width 0.1524)
				(type default)
			)
			(layer "F.SilkS")
		)
		(fp_line
			(start 2.097532 3.949954)
			(end 2.097532 -3.949954)
			(stroke
				(width 0.1524)
				(type default)
			)
			(layer "F.SilkS")
		)
		(fp_poly
			(pts
				(xy -2.421128 -5.1308) (xy -3.437128 -5.1308) (xy -2.929128 -4.1148)
			)
			(stroke
				(width 0)
				(type default)
			)
			(fill yes)
			(layer "F.SilkS")
		)
		(fp_line
			(start -2.249932 -3.949954)
			(end -2.249932 3.949954)
			(stroke
				(width 0.1)
				(type default)
			)
			(layer "F.Fab")
		)
		(fp_line
			(start -2.249932 3.949954)
			(end 2.249932 3.949954)
			(stroke
				(width 0.1)
				(type default)
			)
			(layer "F.Fab")
		)
		(fp_line
			(start 2.249932 -3.949954)
			(end -2.249932 -3.949954)
			(stroke
				(width 0.1)
				(type default)
			)
			(layer "F.Fab")
		)
		(fp_line
			(start 2.249932 3.949954)
			(end 2.249932 -3.949954)
			(stroke
				(width 0.1)
				(type default)
			)
			(layer "F.Fab")
		)
		(fp_poly
			(pts
				(xy -4.7498 -4.182872) (xy -4.7498 -3.166872) (xy -3.7338 -3.674872)
			)
			(stroke
				(width 0)
				(type default)
			)
			(fill yes)
			(layer "F.Fab")
		)
		(pad "1" smd rect
			(at -2.925064 -3.674872 270)
			(size 0.6096 1.3716)
			(layers "F.Cu" "F.Mask" "F.Paste")
			(net "Net_87")
		)
		(pad "2" smd rect
			(at -2.925064 -2.925064 270)
			(size 0.4064 1.3716)
			(layers "F.Cu" "F.Mask" "F.Paste")
			(net "PCA9539_A1")
		)
		(pad "3" smd rect
			(at -2.925064 -2.275078 270)
			(size 0.4064 1.3716)
			(layers "F.Cu" "F.Mask" "F.Paste")
			(net "RST_SMB_R_N")
		)
		(pad "4" smd rect
			(at -2.925064 -1.625092 270)
			(size 0.4064 1.3716)
			(layers "F.Cu" "F.Mask" "F.Paste")
			(net "Net_86")
		)
		(pad "5" smd rect
			(at -2.925064 -0.975106 270)
			(size 0.4064 1.3716)
			(layers "F.Cu" "F.Mask" "F.Paste")
			(net "Net_85")
		)
		(pad "6" smd rect
			(at -2.925064 -0.32512 270)
			(size 0.4064 1.3716)
			(layers "F.Cu" "F.Mask" "F.Paste")
			(net "Net_84")
		)
		(pad "7" smd rect
			(at -2.925064 0.32512 270)
			(size 0.4064 1.3716)
			(layers "F.Cu" "F.Mask" "F.Paste")
			(net "Net_83")
		)
		(pad "8" smd rect
			(at -2.925064 0.975106 270)
			(size 0.4064 1.3716)
			(layers "F.Cu" "F.Mask" "F.Paste")
			(net "Net_82")
		)
		(pad "9" smd rect
			(at -2.925064 1.625092 270)
			(size 0.4064 1.3716)
			(layers "F.Cu" "F.Mask" "F.Paste")
			(net "REV_ID<2>")
		)
		(pad "10" smd rect
			(at -2.925064 2.275078 270)
			(size 0.4064 1.3716)
			(layers "F.Cu" "F.Mask" "F.Paste")
			(net "REV_ID<1>")
		)
		(pad "11" smd rect
			(at -2.925064 2.925064 270)
			(size 0.4064 1.3716)
			(layers "F.Cu" "F.Mask" "F.Paste")
			(net "REV_ID<0>")
		)
		(pad "12" smd rect
			(at -2.925064 3.674872 270)
			(size 0.6096 1.3716)
			(layers "F.Cu" "F.Mask" "F.Paste")
			(net "GND")
		)
		(pad "13" smd rect
			(at 2.925064 3.674872 270)
			(size 0.6096 1.3716)
			(layers "F.Cu" "F.Mask" "F.Paste")
			(net "Net_81")
		)
		(pad "14" smd rect
			(at 2.925064 2.925064 270)
			(size 0.4064 1.3716)
			(layers "F.Cu" "F.Mask" "F.Paste")
			(net "Net_80")
		)
		(pad "15" smd rect
			(at 2.925064 2.275078 270)
			(size 0.4064 1.3716)
			(layers "F.Cu" "F.Mask" "F.Paste")
			(net "Net_79")
		)
		(pad "16" smd rect
			(at 2.925064 1.625092 270)
			(size 0.4064 1.3716)
			(layers "F.Cu" "F.Mask" "F.Paste")
			(net "Net_78")
		)
		(pad "17" smd rect
			(at 2.925064 0.975106 270)
			(size 0.4064 1.3716)
			(layers "F.Cu" "F.Mask" "F.Paste")
			(net "Net_77")
		)
		(pad "18" smd rect
			(at 2.925064 0.32512 270)
			(size 0.4064 1.3716)
			(layers "F.Cu" "F.Mask" "F.Paste")
			(net "Net_76")
		)
		(pad "19" smd rect
			(at 2.925064 -0.32512 270)
			(size 0.4064 1.3716)
			(layers "F.Cu" "F.Mask" "F.Paste")
			(net "SYSTEM_FAULT_ID_LED")
		)
		(pad "20" smd rect
			(at 2.925064 -0.975106 270)
			(size 0.4064 1.3716)
			(layers "F.Cu" "F.Mask" "F.Paste")
			(net "PWR_LED")
		)
		(pad "21" smd rect
			(at 2.925064 -1.625092 270)
			(size 0.4064 1.3716)
			(layers "F.Cu" "F.Mask" "F.Paste")
			(net "PCA9539_A0")
		)
		(pad "22" smd rect
			(at 2.925064 -2.275078 270)
			(size 0.4064 1.3716)
			(layers "F.Cu" "F.Mask" "F.Paste")
			(net "SMB_EXP_SCL")
		)
		(pad "23" smd rect
			(at 2.925064 -2.925064 270)
			(size 0.4064 1.3716)
			(layers "F.Cu" "F.Mask" "F.Paste")
			(net "SMB_EXP_SDA")
		)
		(pad "24" smd rect
			(at 2.925064 -3.674872 270)
			(size 0.6096 1.3716)
			(layers "F.Cu" "F.Mask" "F.Paste")
			(net "P3V3_STBY")
		)
	)
	(footprint ""
		(layer "F.Cu")
		(at 14.605 -51.181)
		(property "Reference" "C11"
			(at 2.032 -0.35433 0)
			(unlocked yes)
			(layer "F.SilkS")
			(effects
				(font
					(size 0.7874 0.5842)
					(thickness 0.1524)
				)
			)
		)
		(property "Value" ""
			(at 0 0 0)
			(layer "F.Fab")
			(effects
				(font
					(size 1.27 1.27)
				)
			)
		)
		(duplicate_pad_numbers_are_jumpers no)
		(fp_line
			(start -0.7874 -0.4064)
			(end 0.7874 -0.4064)
			(stroke
				(width 0.1524)
				(type default)
			)
			(layer "F.SilkS")
		)
		(fp_line
			(start -0.7874 0.4064)
			(end -0.7874 -0.4064)
			(stroke
				(width 0.1524)
				(type default)
			)
			(layer "F.SilkS")
		)
		(fp_line
			(start 0.7874 -0.4064)
			(end 0.7874 0.4064)
			(stroke
				(width 0.1524)
				(type default)
			)
			(layer "F.SilkS")
		)
		(fp_line
			(start 0.7874 0.4064)
			(end -0.7874 0.4064)
			(stroke
				(width 0.1524)
				(type default)
			)
			(layer "F.SilkS")
		)
		(fp_line
			(start -0.67945 -0.305054)
			(end -0.12065 -0.305054)
			(stroke
				(width 0.1)
				(type default)
			)
			(layer "F.Fab")
		)
		(fp_line
			(start -0.67945 0.3048)
			(end -0.67945 -0.305054)
			(stroke
				(width 0.1)
				(type default)
			)
			(layer "F.Fab")
		)
		(fp_line
			(start -0.12065 -0.305054)
			(end -0.12065 -0.2794)
			(stroke
				(width 0.1)
				(type default)
			)
			(layer "F.Fab")
		)
		(fp_line
			(start -0.12065 -0.2794)
			(end 0.12065 -0.2794)
			(stroke
				(width 0.1)
				(type default)
			)
			(layer "F.Fab")
		)
		(fp_line
			(start -0.12065 0.2794)
			(end -0.12065 0.3048)
			(stroke
				(width 0.1)
				(type default)
			)
			(layer "F.Fab")
		)
		(fp_line
			(start -0.12065 0.3048)
			(end -0.67945 0.3048)
			(stroke
				(width 0.1)
				(type default)
			)
			(layer "F.Fab")
		)
		(fp_line
			(start 0.120396 0.2794)
			(end -0.12065 0.2794)
			(stroke
				(width 0.1)
				(type default)
			)
			(layer "F.Fab")
		)
		(fp_line
			(start 0.120396 0.3048)
			(end 0.120396 0.2794)
			(stroke
				(width 0.1)
				(type default)
			)
			(layer "F.Fab")
		)
		(fp_line
			(start 0.12065 -0.3048)
			(end 0.67945 -0.3048)
			(stroke
				(width 0.1)
				(type default)
			)
			(layer "F.Fab")
		)
		(fp_line
			(start 0.12065 -0.2794)
			(end 0.12065 -0.3048)
			(stroke
				(width 0.1)
				(type default)
			)
			(layer "F.Fab")
		)
		(fp_line
			(start 0.67945 -0.3048)
			(end 0.67945 0.3048)
			(stroke
				(width 0.1)
				(type default)
			)
			(layer "F.Fab")
		)
		(fp_line
			(start 0.67945 0.3048)
			(end 0.120396 0.3048)
			(stroke
				(width 0.1)
				(type default)
			)
			(layer "F.Fab")
		)
		(pad "1" smd circle
			(at -0.40005 0)
			(size 0 0)
			(layers "F.Cu" "F.Mask" "F.Paste")
			(net "P3V3_STBY")
		)
		(pad "2" smd circle
			(at 0.40005 0)
			(size 0 0)
			(layers "F.Cu" "F.Mask" "F.Paste")
			(net "GND")
		)
	)
	(footprint ""
		(layer "F.Cu")
		(at 19.558 -22.098)
		(property "Reference" "R30"
			(at 0.381 -4.16433 0)
			(unlocked yes)
			(layer "F.SilkS")
			(effects
				(font
					(size 0.7874 0.5842)
					(thickness 0.1524)
				)
			)
		)
		(property "Value" ""
			(at 0 0 0)
			(layer "F.Fab")
			(effects
				(font
					(size 1.27 1.27)
				)
			)
		)
		(duplicate_pad_numbers_are_jumpers no)
		(fp_line
			(start -0.7874 -0.4064)
			(end 0.7874 -0.4064)
			(stroke
				(width 0.1524)
				(type default)
			)
			(layer "F.SilkS")
		)
		(fp_line
			(start -0.7874 0.4064)
			(end -0.7874 -0.4064)
			(stroke
				(width 0.1524)
				(type default)
			)
			(layer "F.SilkS")
		)
		(fp_line
			(start 0.7874 -0.4064)
			(end 0.7874 0.4064)
			(stroke
				(width 0.1524)
				(type default)
			)
			(layer "F.SilkS")
		)
		(fp_line
			(start 0.7874 0.4064)
			(end -0.7874 0.4064)
			(stroke
				(width 0.1524)
				(type default)
			)
			(layer "F.SilkS")
		)
		(fp_line
			(start -0.67945 -0.305054)
			(end -0.12065 -0.305054)
			(stroke
				(width 0.1)
				(type default)
			)
			(layer "F.Fab")
		)
		(fp_line
			(start -0.67945 0.3048)
			(end -0.67945 -0.305054)
			(stroke
				(width 0.1)
				(type default)
			)
			(layer "F.Fab")
		)
		(fp_line
			(start -0.12065 -0.305054)
			(end -0.12065 -0.2794)
			(stroke
				(width 0.1)
				(type default)
			)
			(layer "F.Fab")
		)
		(fp_line
			(start -0.12065 -0.2794)
			(end 0.12065 -0.2794)
			(stroke
				(width 0.1)
				(type default)
			)
			(layer "F.Fab")
		)
		(fp_line
			(start -0.12065 0.2794)
			(end -0.12065 0.3048)
			(stroke
				(width 0.1)
				(type default)
			)
			(layer "F.Fab")
		)
		(fp_line
			(start -0.12065 0.3048)
			(end -0.67945 0.3048)
			(stroke
				(width 0.1)
				(type default)
			)
			(layer "F.Fab")
		)
		(fp_line
			(start 0.120396 0.2794)
			(end -0.12065 0.2794)
			(stroke
				(width 0.1)
				(type default)
			)
			(layer "F.Fab")
		)
		(fp_line
			(start 0.120396 0.3048)
			(end 0.120396 0.2794)
			(stroke
				(width 0.1)
				(type default)
			)
			(layer "F.Fab")
		)
		(fp_line
			(start 0.12065 -0.3048)
			(end 0.67945 -0.3048)
			(stroke
				(width 0.1)
				(type default)
			)
			(layer "F.Fab")
		)
		(fp_line
			(start 0.12065 -0.2794)
			(end 0.12065 -0.3048)
			(stroke
				(width 0.1)
				(type default)
			)
			(layer "F.Fab")
		)
		(fp_line
			(start 0.67945 -0.3048)
			(end 0.67945 0.3048)
			(stroke
				(width 0.1)
				(type default)
			)
			(layer "F.Fab")
		)
		(fp_line
			(start 0.67945 0.3048)
			(end 0.120396 0.3048)
			(stroke
				(width 0.1)
				(type default)
			)
			(layer "F.Fab")
		)
		(pad "1" smd circle
			(at -0.40005 0)
			(size 0 0)
			(layers "F.Cu" "F.Mask" "F.Paste")
			(net "P3V3_STBY")
		)
		(pad "2" smd circle
			(at 0.40005 0)
			(size 0 0)
			(layers "F.Cu" "F.Mask" "F.Paste")
			(net "SMB_TMP75_SCL")
		)
	)
	(footprint ""
		(layer "F.Cu")
		(at 94.02953 -62.894972 90)
		(property "Reference" "X1"
			(at 4.388358 -1.82753 0)
			(unlocked yes)
			(layer "F.SilkS")
			(effects
				(font
					(size 0.7874 0.5842)
					(thickness 0.1524)
				)
				(justify left)
			)
		)
		(property "Value" ""
			(at 0 0 90)
			(layer "F.Fab")
			(effects
				(font
					(size 1.27 1.27)
				)
			)
		)
		(property "Device Type" "TP_TDR_4P_FTS_MPKT4_H025P0200_IO_TP15_TP_TDR_4P_DIP"
			(at 1.30175 1.27 180)
			(unlocked yes)
			(layer "F.Fab")
			(hide yes)
			(effects
				(font
					(size 0.635 0.4064)
					(thickness 0.1524)
				)
			)
		)
		(property "User Part Number" "TP15"
			(at 1.30175 1.27 180)
			(unlocked yes)
			(layer "Cmts.User")
			(hide yes)
			(effects
				(font
					(size 0.635 0.4064)
					(thickness 0.1524)
				)
			)
		)
		(duplicate_pad_numbers_are_jumpers no)
		(fp_line
			(start 2.54 -1.27)
			(end 0 -1.27)
			(stroke
				(width 0.1524)
				(type default)
			)
			(layer "F.SilkS")
		)
		(fp_line
			(start 0 -1.27)
			(end 0 -0.635)
			(stroke
				(width 0.1524)
				(type default)
			)
			(layer "F.SilkS")
		)
		(fp_line
			(start 2.54 -1.1303)
			(end 2.54 -1.27)
			(stroke
				(width 0.1524)
				(type default)
			)
			(layer "F.SilkS")
		)
		(fp_line
			(start 0 0.635)
			(end 0 1.905)
			(stroke
				(width 0.1524)
				(type default)
			)
			(layer "F.SilkS")
		)
		(fp_line
			(start 2.54 1.4097)
			(end 2.54 1.1303)
			(stroke
				(width 0.1524)
				(type default)
			)
			(layer "F.SilkS")
		)
		(fp_line
			(start 0 3.175)
			(end 0 3.81)
			(stroke
				(width 0.1524)
				(type default)
			)
			(layer "F.SilkS")
		)
		(fp_line
			(start 2.54 3.81)
			(end 2.54 3.6703)
			(stroke
				(width 0.1524)
				(type default)
			)
			(layer "F.SilkS")
		)
		(fp_line
			(start 0 3.81)
			(end 2.54 3.81)
			(stroke
				(width 0.1524)
				(type default)
			)
			(layer "F.SilkS")
		)
		(fp_poly
			(pts
				(xy -0.761746 0) (xy -2.285746 -0.762) (xy -2.285746 0.762)
			)
			(stroke
				(width 0)
				(type default)
			)
			(fill yes)
			(layer "F.SilkS")
		)
		(fp_line
			(start 2.54 -1.27)
			(end 0 -1.27)
			(stroke
				(width 0.1)
				(type default)
			)
			(layer "F.Fab")
		)
		(fp_line
			(start 0 -1.27)
			(end 0 3.81)
			(stroke
				(width 0.1)
				(type default)
			)
			(layer "F.Fab")
		)
		(fp_line
			(start 2.54 3.81)
			(end 2.54 -1.27)
			(stroke
				(width 0.1)
				(type default)
			)
			(layer "F.Fab")
		)
		(fp_line
			(start 0 3.81)
			(end 2.54 3.81)
			(stroke
				(width 0.1)
				(type default)
			)
			(layer "F.Fab")
		)
		(fp_poly
			(pts
				(xy -0.761746 0) (xy -2.285746 -0.762) (xy -2.285746 0.762)
			)
			(stroke
				(width 0)
				(type default)
			)
			(fill yes)
			(layer "F.Fab")
		)
		(pad "1" thru_hole circle
			(at 0 0 90)
			(size 1.0033 1.0033)
			(drill 0.249936)
			(layers "*.Cu" "*.Mask")
			(remove_unused_layers no)
			(net "TDR_DIFF_85_TOP_DP")
			(clearance 0.10795)
			(thermal_gap 0.10795)
			(padstack
				(mode front_inner_back)
				(layer "Inner"
					(shape circle)
					(size 0.8001 0.8001)
					(clearance 0.1524)
				)
				(layer "B.Cu"
					(shape circle)
					(size 1.0033 1.0033)
					(clearance 0.10795)
				)
			)
		)
		(pad "2" thru_hole circle
			(at 2.54 0 90)
			(size 1.9939 1.9939)
			(drill 0.249936)
			(layers "*.Cu" "*.Mask")
			(remove_unused_layers no)
			(net "GND_TDR")
			(clearance 0.10795)
			(thermal_gap 0.10795)
			(padstack
				(mode front_inner_back)
				(layer "Inner"
					(shape circle)
					(size 0.8001 0.8001)
					(clearance 0.1524)
				)
				(layer "B.Cu"
					(shape circle)
					(size 1.9939 1.9939)
					(clearance 0.10795)
				)
			)
		)
		(pad "3" thru_hole circle
			(at 2.54 2.54 90)
			(size 1.9939 1.9939)
			(drill 0.249936)
			(layers "*.Cu" "*.Mask")
			(remove_unused_layers no)
			(net "GND_TDR")
			(clearance 0.10795)
			(thermal_gap 0.10795)
			(padstack
				(mode front_inner_back)
				(layer "Inner"
					(shape circle)
					(size 0.8001 0.8001)
					(clearance 0.1524)
				)
				(layer "B.Cu"
					(shape circle)
					(size 1.9939 1.9939)
					(clearance 0.10795)
				)
			)
		)
		(pad "4" thru_hole circle
			(at 0 2.54 90)
			(size 1.0033 1.0033)
			(drill 0.249936)
			(layers "*.Cu" "*.Mask")
			(remove_unused_layers no)
			(net "TDR_DIFF_85_TOP_DN")
			(clearance 0.10795)
			(thermal_gap 0.10795)
			(padstack
				(mode front_inner_back)
				(layer "Inner"
					(shape circle)
					(size 0.8001 0.8001)
					(clearance 0.1524)
				)
				(layer "B.Cu"
					(shape circle)
					(size 1.0033 1.0033)
					(clearance 0.10795)
				)
			)
		)
	)
	(footprint ""
		(layer "F.Cu")
		(at 24.003 -28.067 180)
		(property "Reference" "U10"
			(at 2.00533 -0.762 90)
			(unlocked yes)
			(layer "F.SilkS")
			(effects
				(font
					(size 0.7874 0.5842)
					(thickness 0.1524)
				)
				(justify left)
			)
		)
		(property "Value" ""
			(at 0 0 180)
			(layer "F.Fab")
			(effects
				(font
					(size 1.27 1.27)
				)
			)
		)
		(duplicate_pad_numbers_are_jumpers no)
		(fp_line
			(start 0.517398 1.500124)
			(end -0.517398 1.500124)
			(stroke
				(width 0.1524)
				(type default)
			)
			(layer "F.SilkS")
		)
		(fp_line
			(start 0.517398 -1.500124)
			(end 0.517398 1.500124)
			(stroke
				(width 0.1524)
				(type default)
			)
			(layer "F.SilkS")
		)
		(fp_line
			(start -0.517398 1.500124)
			(end -0.517398 -1.500124)
			(stroke
				(width 0.1524)
				(type default)
			)
			(layer "F.SilkS")
		)
		(fp_line
			(start -0.517398 -1.500124)
			(end 0.517398 -1.500124)
			(stroke
				(width 0.1524)
				(type default)
			)
			(layer "F.SilkS")
		)
		(fp_poly
			(pts
				(xy -1.5113 -0.750062) (xy -2.1463 -1.067562) (xy -2.1463 -0.432562)
			)
			(stroke
				(width 0)
				(type default)
			)
			(fill yes)
			(layer "F.SilkS")
		)
		(fp_line
			(start 0.700024 1.500124)
			(end -0.700024 1.500124)
			(stroke
				(width 0.1)
				(type default)
			)
			(layer "F.Fab")
		)
		(fp_line
			(start 0.700024 -1.500124)
			(end 0.700024 1.500124)
			(stroke
				(width 0.1)
				(type default)
			)
			(layer "F.Fab")
		)
		(fp_line
			(start -0.700024 1.500124)
			(end -0.700024 -1.500124)
			(stroke
				(width 0.1)
				(type default)
			)
			(layer "F.Fab")
		)
		(fp_line
			(start -0.700024 -1.500124)
			(end 0.700024 -1.500124)
			(stroke
				(width 0.1)
				(type default)
			)
			(layer "F.Fab")
		)
		(fp_poly
			(pts
				(xy -1.5113 -0.750062) (xy -2.1463 -1.067562) (xy -2.1463 -0.432562)
			)
			(stroke
				(width 0)
				(type default)
			)
			(fill yes)
			(layer "F.Fab")
		)
		(pad "1" smd rect
			(at -0.999998 -0.750062 180)
			(size 0.7112 1.016)
			(layers "F.Cu" "F.Mask" "F.Paste")
			(net "GND")
		)
		(pad "2" smd rect
			(at -0.999998 0.94996 90)
			(size 0.6096 0.7112)
			(layers "F.Cu" "F.Mask" "F.Paste")
			(net "UART_DEBUG_R_TX")
		)
		(pad "3" smd rect
			(at 0.999998 0.94996 90)
			(size 0.6096 0.7112)
			(layers "F.Cu" "F.Mask" "F.Paste")
			(net "UART_DEBUG_R_RX")
		)
		(pad "4" smd rect
			(at 0.999998 -0.94996 90)
			(size 0.6096 0.7112)
			(layers "F.Cu" "F.Mask" "F.Paste")
			(net "P5V_STBY_DEBUG")
		)
	)
	(footprint ""
		(layer "F.Cu")
		(at 15.875 -49.149 180)
		(property "Reference" "R55"
			(at -2.54 -0.02667 0)
			(unlocked yes)
			(layer "F.SilkS")
			(effects
				(font
					(size 0.7874 0.5842)
					(thickness 0.1524)
				)
			)
		)
		(property "Value" ""
			(at 0 0 180)
			(layer "F.Fab")
			(effects
				(font
					(size 1.27 1.27)
				)
			)
		)
		(duplicate_pad_numbers_are_jumpers no)
		(fp_line
			(start 0.7874 0.4064)
			(end -0.7874 0.4064)
			(stroke
				(width 0.1524)
				(type default)
			)
			(layer "F.SilkS")
		)
		(fp_line
			(start 0.7874 -0.4064)
			(end 0.7874 0.4064)
			(stroke
				(width 0.1524)
				(type default)
			)
			(layer "F.SilkS")
		)
		(fp_line
			(start -0.7874 0.4064)
			(end -0.7874 -0.4064)
			(stroke
				(width 0.1524)
				(type default)
			)
			(layer "F.SilkS")
		)
		(fp_line
			(start -0.7874 -0.4064)
			(end 0.7874 -0.4064)
			(stroke
				(width 0.1524)
				(type default)
			)
			(layer "F.SilkS")
		)
		(fp_line
			(start 0.67945 0.3048)
			(end 0.120396 0.3048)
			(stroke
				(width 0.1)
				(type default)
			)
			(layer "F.Fab")
		)
		(fp_line
			(start 0.67945 -0.3048)
			(end 0.67945 0.3048)
			(stroke
				(width 0.1)
				(type default)
			)
			(layer "F.Fab")
		)
		(fp_line
			(start 0.12065 -0.2794)
			(end 0.12065 -0.3048)
			(stroke
				(width 0.1)
				(type default)
			)
			(layer "F.Fab")
		)
		(fp_line
			(start 0.12065 -0.3048)
			(end 0.67945 -0.3048)
			(stroke
				(width 0.1)
				(type default)
			)
			(layer "F.Fab")
		)
		(fp_line
			(start 0.120396 0.3048)
			(end 0.120396 0.2794)
			(stroke
				(width 0.1)
				(type default)
			)
			(layer "F.Fab")
		)
		(fp_line
			(start 0.120396 0.2794)
			(end -0.12065 0.2794)
			(stroke
				(width 0.1)
				(type default)
			)
			(layer "F.Fab")
		)
		(fp_line
			(start -0.12065 0.3048)
			(end -0.67945 0.3048)
			(stroke
				(width 0.1)
				(type default)
			)
			(layer "F.Fab")
		)
		(fp_line
			(start -0.12065 0.2794)
			(end -0.12065 0.3048)
			(stroke
				(width 0.1)
				(type default)
			)
			(layer "F.Fab")
		)
		(fp_line
			(start -0.12065 -0.2794)
			(end 0.12065 -0.2794)
			(stroke
				(width 0.1)
				(type default)
			)
			(layer "F.Fab")
		)
		(fp_line
			(start -0.12065 -0.305054)
			(end -0.12065 -0.2794)
			(stroke
				(width 0.1)
				(type default)
			)
			(layer "F.Fab")
		)
		(fp_line
			(start -0.67945 0.3048)
			(end -0.67945 -0.305054)
			(stroke
				(width 0.1)
				(type default)
			)
			(layer "F.Fab")
		)
		(fp_line
			(start -0.67945 -0.305054)
			(end -0.12065 -0.305054)
			(stroke
				(width 0.1)
				(type default)
			)
			(layer "F.Fab")
		)
		(pad "1" smd circle
			(at -0.40005 0 180)
			(size 0 0)
			(layers "F.Cu" "F.Mask" "F.Paste")
			(net "P3V3_STBY")
		)
		(pad "2" smd circle
			(at 0.40005 0 180)
			(size 0 0)
			(layers "F.Cu" "F.Mask" "F.Paste")
			(net "PD_FRU_WP")
		)
	)
	(footprint ""
		(layer "F.Cu")
		(at 2.62001 -5.100066)
		(property "Reference" "D2"
			(at -1.98501 -2.64922 0)
			(unlocked yes)
			(layer "F.SilkS")
			(effects
				(font
					(size 0.7874 0.5842)
					(thickness 0.1524)
				)
				(justify left)
			)
		)
		(property "Value" ""
			(at 0 0 0)
			(layer "F.Fab")
			(effects
				(font
					(size 1.27 1.27)
				)
			)
		)
		(duplicate_pad_numbers_are_jumpers no)
		(fp_line
			(start -1.080008 -1.999996)
			(end 3.620008 -1.999996)
			(stroke
				(width 0.1524)
				(type default)
			)
			(layer "F.SilkS")
		)
		(fp_line
			(start -1.080008 3.999992)
			(end -1.080008 -1.999996)
			(stroke
				(width 0.1524)
				(type default)
			)
			(layer "F.SilkS")
		)
		(fp_line
			(start -0.230124 3.999992)
			(end -1.080008 3.999992)
			(stroke
				(width 0.1524)
				(type default)
			)
			(layer "F.SilkS")
		)
		(fp_line
			(start -0.230124 5.199888)
			(end -0.230124 3.999992)
			(stroke
				(width 0.1524)
				(type default)
			)
			(layer "F.SilkS")
		)
		(fp_line
			(start 2.770124 3.999992)
			(end 2.770124 5.199888)
			(stroke
				(width 0.1524)
				(type default)
			)
			(layer "F.SilkS")
		)
		(fp_line
			(start 3.620008 -1.999996)
			(end 3.620008 3.999992)
			(stroke
				(width 0.1524)
				(type default)
			)
			(layer "F.SilkS")
		)
		(fp_line
			(start 3.620008 3.999992)
			(end 2.770124 3.999992)
			(stroke
				(width 0.1524)
				(type default)
			)
			(layer "F.SilkS")
		)
		(fp_arc
			(start 1.27 6.700012)
			(mid 0.209252 6.260636)
			(end -0.230124 5.199888)
			(stroke
				(width 0.1524)
				(type default)
			)
			(layer "F.SilkS")
		)
		(fp_arc
			(start 2.770124 5.199888)
			(mid 2.330748 6.260636)
			(end 1.27 6.700012)
			(stroke
				(width 0.1524)
				(type default)
			)
			(layer "F.SilkS")
		)
		(fp_line
			(start -1.080008 -1.999996)
			(end 3.620008 -1.999996)
			(stroke
				(width 0.1)
				(type default)
			)
			(layer "F.Fab")
		)
		(fp_line
			(start -1.080008 3.999992)
			(end -1.080008 -1.999996)
			(stroke
				(width 0.1)
				(type default)
			)
			(layer "F.Fab")
		)
		(fp_line
			(start -0.230124 3.999992)
			(end -1.080008 3.999992)
			(stroke
				(width 0.1)
				(type default)
			)
			(layer "F.Fab")
		)
		(fp_line
			(start -0.230124 5.199888)
			(end -0.230124 3.999992)
			(stroke
				(width 0.1)
				(type default)
			)
			(layer "F.Fab")
		)
		(fp_line
			(start 2.770124 3.999992)
			(end 2.770124 5.199888)
			(stroke
				(width 0.1)
				(type default)
			)
			(layer "F.Fab")
		)
		(fp_line
			(start 3.620008 -1.999996)
			(end 3.620008 3.999992)
			(stroke
				(width 0.1)
				(type default)
			)
			(layer "F.Fab")
		)
		(fp_line
			(start 3.620008 3.999992)
			(end 2.770124 3.999992)
			(stroke
				(width 0.1)
				(type default)
			)
			(layer "F.Fab")
		)
		(fp_arc
			(start 1.27 6.700012)
			(mid 0.209252 6.260636)
			(end -0.230124 5.199888)
			(stroke
				(width 0.1)
				(type default)
			)
			(layer "F.Fab")
		)
		(fp_arc
			(start 2.770124 5.199888)
			(mid 2.330748 6.260636)
			(end 1.27 6.700012)
			(stroke
				(width 0.1)
				(type default)
			)
			(layer "F.Fab")
		)
		(pad "A" thru_hole rect
			(at 0 0)
			(size 1.2192 1.2192)
			(drill 0.8128)
			(layers "*.Cu" "*.Mask")
			(remove_unused_layers no)
			(net "P5V_STBY")
			(clearance 0.0508)
			(thermal_gap 0.0508)
			(padstack
				(mode front_inner_back)
				(layer "Inner"
					(shape circle)
					(size 1.2192 1.2192)
					(clearance 0.0508)
				)
				(layer "B.Cu"
					(shape rect)
					(size 1.2192 1.2192)
					(clearance 0.0508)
				)
			)
		)
		(pad "C" thru_hole circle
			(at 2.54 0)
			(size 1.2192 1.2192)
			(drill 0.8128)
			(layers "*.Cu" "*.Mask")
			(remove_unused_layers no)
			(net "SYSTEM_FAULT_ID_LED_R2_N")
			(clearance 0.0508)
			(thermal_gap 0.0508)
		)
	)
	(footprint ""
		(layer "B.Cu")
		(at 20.862544 -27.396694 -90)
		(property "Reference" "ME8"
			(at 0 0 90)
			(layer "B.SilkS")
			(hide yes)
			(effects
				(font
					(size 1.27 1.27)
				)
				(justify mirror)
			)
		)
		(property "Value" ""
			(at 0 0 90)
			(layer "B.Fab")
			(effects
				(font
					(size 1.27 1.27)
				)
				(justify mirror)
			)
		)
		(duplicate_pad_numbers_are_jumpers no)
		(fp_line
			(start -39.500048 0)
			(end -37.976048 0)
			(stroke
				(width 0.1524)
				(type default)
			)
			(layer "B.SilkS")
		)
		(fp_line
			(start 0 0)
			(end -1.524 0)
			(stroke
				(width 0.1524)
				(type default)
			)
			(layer "B.SilkS")
		)
		(fp_line
			(start -39.500048 -1.524)
			(end -39.500048 0)
			(stroke
				(width 0.1524)
				(type default)
			)
			(layer "B.SilkS")
		)
		(fp_line
			(start 0 -1.524)
			(end 0 0)
			(stroke
				(width 0.1524)
				(type default)
			)
			(layer "B.SilkS")
		)
		(fp_line
			(start -39.500048 -6.500114)
			(end -39.500048 -4.976114)
			(stroke
				(width 0.1524)
				(type default)
			)
			(layer "B.SilkS")
		)
		(fp_line
			(start -37.976048 -6.500114)
			(end -39.500048 -6.500114)
			(stroke
				(width 0.1524)
				(type default)
			)
			(layer "B.SilkS")
		)
		(fp_line
			(start -1.524 -6.500114)
			(end 0 -6.500114)
			(stroke
				(width 0.1524)
				(type default)
			)
			(layer "B.SilkS")
		)
		(fp_line
			(start 0 -6.500114)
			(end 0 -4.976114)
			(stroke
				(width 0.1524)
				(type default)
			)
			(layer "B.SilkS")
		)
		(fp_text user "Rework version"
			(at -6.656324 -3.15468 270)
			(unlocked yes)
			(layer "B.SilkS")
			(effects
				(font
					(size 1.905 1.4224)
					(thickness 0.1524)
				)
				(justify left mirror)
			)
		)
	)
	(footprint ""
		(layer "B.Cu")
		(at 4.318 -41.91)
		(property "Reference" "ME3"
			(at 0 0 0)
			(layer "B.SilkS")
			(hide yes)
			(effects
				(font
					(size 1.27 1.27)
				)
				(justify mirror)
			)
		)
		(property "Value" ""
			(at 0 0 0)
			(layer "B.Fab")
			(effects
				(font
					(size 1.27 1.27)
				)
				(justify mirror)
			)
		)
		(duplicate_pad_numbers_are_jumpers no)
		(fp_line
			(start -2.9337 2.4511)
			(end -2.9337 3.0861)
			(stroke
				(width 0.1524)
				(type default)
			)
			(layer "B.SilkS")
		)
		(fp_line
			(start -2.9337 3.0861)
			(end -3.1115 3.0734)
			(stroke
				(width 0.1524)
				(type default)
			)
			(layer "B.SilkS")
		)
		(fp_line
			(start -2.8194 2.667)
			(end -3.048 2.667)
			(stroke
				(width 0.1524)
				(type default)
			)
			(layer "B.SilkS")
		)
		(fp_line
			(start -2.5019 2.6797)
			(end -2.4638 2.667)
			(stroke
				(width 0.1524)
				(type default)
			)
			(layer "B.SilkS")
		)
		(fp_line
			(start -2.4638 2.667)
			(end -2.413 2.6543)
			(stroke
				(width 0.1524)
				(type default)
			)
			(layer "B.SilkS")
		)
		(fp_line
			(start -2.4384 3.0861)
			(end -2.5019 3.0607)
			(stroke
				(width 0.1524)
				(type default)
			)
			(layer "B.SilkS")
		)
		(fp_line
			(start -2.413 2.6543)
			(end -2.3749 2.6543)
			(stroke
				(width 0.1524)
				(type default)
			)
			(layer "B.SilkS")
		)
		(fp_line
			(start -2.3876 3.0861)
			(end -2.4384 3.0861)
			(stroke
				(width 0.1524)
				(type default)
			)
			(layer "B.SilkS")
		)
		(fp_line
			(start -2.3749 2.6543)
			(end -2.3241 2.667)
			(stroke
				(width 0.1524)
				(type default)
			)
			(layer "B.SilkS")
		)
		(fp_line
			(start -2.3241 2.667)
			(end -2.2987 2.6797)
			(stroke
				(width 0.1524)
				(type default)
			)
			(layer "B.SilkS")
		)
		(fp_line
			(start -2.3241 3.0734)
			(end -2.3876 3.0861)
			(stroke
				(width 0.1524)
				(type default)
			)
			(layer "B.SilkS")
		)
		(fp_line
			(start -2.2987 2.6797)
			(end -2.2606 2.7051)
			(stroke
				(width 0.1524)
				(type default)
			)
			(layer "B.SilkS")
		)
		(fp_line
			(start -2.2987 3.0607)
			(end -2.3241 3.0734)
			(stroke
				(width 0.1524)
				(type default)
			)
			(layer "B.SilkS")
		)
		(fp_line
			(start -2.2606 2.7051)
			(end -2.2352 2.7305)
			(stroke
				(width 0.1524)
				(type default)
			)
			(layer "B.SilkS")
		)
		(fp_line
			(start -2.2606 3.0353)
			(end -2.2987 3.0607)
			(stroke
				(width 0.1524)
				(type default)
			)
			(layer "B.SilkS")
		)
		(fp_line
			(start -2.2352 2.7305)
			(end -2.2098 2.7686)
			(stroke
				(width 0.1524)
				(type default)
			)
			(layer "B.SilkS")
		)
		(fp_line
			(start -2.2352 3.0099)
			(end -2.2606 3.0353)
			(stroke
				(width 0.1524)
				(type default)
			)
			(layer "B.SilkS")
		)
		(fp_line
			(start -2.2098 2.7686)
			(end -2.1971 2.794)
			(stroke
				(width 0.1524)
				(type default)
			)
			(layer "B.SilkS")
		)
		(fp_line
			(start -2.2098 2.9718)
			(end -2.2352 3.0099)
			(stroke
				(width 0.1524)
				(type default)
			)
			(layer "B.SilkS")
		)
		(fp_line
			(start -2.1971 2.794)
			(end -2.1844 2.8575)
			(stroke
				(width 0.1524)
				(type default)
			)
			(layer "B.SilkS")
		)
		(fp_line
			(start -2.1971 2.9464)
			(end -2.2098 2.9718)
			(stroke
				(width 0.1524)
				(type default)
			)
			(layer "B.SilkS")
		)
		(fp_line
			(start -2.1844 2.8575)
			(end -2.1844 2.8956)
			(stroke
				(width 0.1524)
				(type default)
			)
			(layer "B.SilkS")
		)
		(fp_line
			(start -2.1844 2.8956)
			(end -2.1971 2.9464)
			(stroke
				(width 0.1524)
				(type default)
			)
			(layer "B.SilkS")
		)
		(fp_line
			(start -1.8161 2.4511)
			(end -1.8161 3.0861)
			(stroke
				(width 0.1524)
				(type default)
			)
			(layer "B.SilkS")
		)
		(fp_line
			(start -1.8161 3.0861)
			(end -1.9939 3.0734)
			(stroke
				(width 0.1524)
				(type default)
			)
			(layer "B.SilkS")
		)
		(fp_line
			(start -1.7018 2.667)
			(end -1.9304 2.667)
			(stroke
				(width 0.1524)
				(type default)
			)
			(layer "B.SilkS")
		)
		(fp_line
			(start -1.4224 2.7686)
			(end -1.4224 3.0861)
			(stroke
				(width 0.1524)
				(type default)
			)
			(layer "B.SilkS")
		)
		(fp_line
			(start -1.397 2.7178)
			(end -1.4224 2.7686)
			(stroke
				(width 0.1524)
				(type default)
			)
			(layer "B.SilkS")
		)
		(fp_line
			(start -1.3589 2.667)
			(end -1.397 2.7178)
			(stroke
				(width 0.1524)
				(type default)
			)
			(layer "B.SilkS")
		)
		(fp_line
			(start -1.3081 2.6543)
			(end -1.3589 2.667)
			(stroke
				(width 0.1524)
				(type default)
			)
			(layer "B.SilkS")
		)
		(fp_line
			(start -1.27 2.6543)
			(end -1.3081 2.6543)
			(stroke
				(width 0.1524)
				(type default)
			)
			(layer "B.SilkS")
		)
		(fp_line
			(start -1.2192 2.667)
			(end -1.27 2.6543)
			(stroke
				(width 0.1524)
				(type default)
			)
			(layer "B.SilkS")
		)
		(fp_line
			(start -1.1938 2.6924)
			(end -1.2192 2.667)
			(stroke
				(width 0.1524)
				(type default)
			)
			(layer "B.SilkS")
		)
		(fp_line
			(start -1.1684 2.7305)
			(end -1.1938 2.6924)
			(stroke
				(width 0.1524)
				(type default)
			)
			(layer "B.SilkS")
		)
		(fp_line
			(start -1.143 2.6543)
			(end -1.143 3.0861)
			(stroke
				(width 0.1524)
				(type default)
			)
			(layer "B.SilkS")
		)
		(fp_line
			(start -1.143 2.7813)
			(end -1.1684 2.7305)
			(stroke
				(width 0.1524)
				(type default)
			)
			(layer "B.SilkS")
		)
		(fp_line
			(start -0.9144 4.191)
			(end -0.9144 5.461)
			(stroke
				(width 0.254)
				(type default)
			)
			(layer "B.SilkS")
		)
		(fp_line
			(start -0.7239 2.3495)
			(end -0.6985 2.3241)
			(stroke
				(width 0.1524)
				(type default)
			)
			(layer "B.SilkS")
		)
		(fp_line
			(start -0.7239 2.3749)
			(end -0.7239 2.3495)
			(stroke
				(width 0.1524)
				(type default)
			)
			(layer "B.SilkS")
		)
		(fp_line
			(start -0.6985 2.3241)
			(end -0.6731 2.3495)
			(stroke
				(width 0.1524)
				(type default)
			)
			(layer "B.SilkS")
		)
		(fp_line
			(start -0.6985 2.4003)
			(end -0.7239 2.3749)
			(stroke
				(width 0.1524)
				(type default)
			)
			(layer "B.SilkS")
		)
		(fp_line
			(start -0.6985 2.6416)
			(end -0.6985 3.0861)
			(stroke
				(width 0.1524)
				(type default)
			)
			(layer "B.SilkS")
		)
		(fp_line
			(start -0.6731 2.3495)
			(end -0.6731 2.3749)
			(stroke
				(width 0.1524)
				(type default)
			)
			(layer "B.SilkS")
		)
		(fp_line
			(start -0.6731 2.3749)
			(end -0.6985 2.4003)
			(stroke
				(width 0.1524)
				(type default)
			)
			(layer "B.SilkS")
		)
		(fp_line
			(start -0.635 4.3434)
			(end -0.9144 4.191)
			(stroke
				(width 0.254)
				(type default)
			)
			(layer "B.SilkS")
		)
		(fp_line
			(start -0.3556 -1.27)
			(end -0.3556 1.2954)
			(stroke
				(width 0.254)
				(type default)
			)
			(layer "B.SilkS")
		)
		(fp_line
			(start -0.3048 4.7752)
			(end -0.2794 4.5974)
			(stroke
				(width 0.254)
				(type default)
			)
			(layer "B.SilkS")
		)
		(fp_line
			(start -0.2794 4.5974)
			(end -0.254 4.5212)
			(stroke
				(width 0.254)
				(type default)
			)
			(layer "B.SilkS")
		)
		(fp_line
			(start -0.254 4.5212)
			(end -0.2032 4.4196)
			(stroke
				(width 0.254)
				(type default)
			)
			(layer "B.SilkS")
		)
		(fp_line
			(start -0.2032 4.4196)
			(end -0.127 4.318)
			(stroke
				(width 0.254)
				(type default)
			)
			(layer "B.SilkS")
		)
		(fp_line
			(start -0.127 4.318)
			(end 0 4.2164)
			(stroke
				(width 0.254)
				(type default)
			)
			(layer "B.SilkS")
		)
		(fp_line
			(start -0.1016 5.2578)
			(end -0.2032 5.1308)
			(stroke
				(width 0.254)
				(type default)
			)
			(layer "B.SilkS")
		)
		(fp_line
			(start 0 4.2164)
			(end 0.1016 4.1656)
			(stroke
				(width 0.254)
				(type default)
			)
			(layer "B.SilkS")
		)
		(fp_line
			(start 0.0381 2.4257)
			(end 0.0381 3.0861)
			(stroke
				(width 0.1524)
				(type default)
			)
			(layer "B.SilkS")
		)
		(fp_line
			(start 0.0508 5.3594)
			(end -0.1016 5.2578)
			(stroke
				(width 0.254)
				(type default)
			)
			(layer "B.SilkS")
		)
		(fp_line
			(start 0.1016 4.1656)
			(end 0.1778 4.1402)
			(stroke
				(width 0.254)
				(type default)
			)
			(layer "B.SilkS")
		)
		(fp_line
			(start 0.1016 5.3848)
			(end 0.0508 5.3594)
			(stroke
				(width 0.254)
				(type default)
			)
			(layer "B.SilkS")
		)
		(fp_line
			(start 0.1778 4.1402)
			(end 0.3048 4.1148)
			(stroke
				(width 0.254)
				(type default)
			)
			(layer "B.SilkS")
		)
		(fp_line
			(start 0.1778 5.4102)
			(end 0.1016 5.3848)
			(stroke
				(width 0.254)
				(type default)
			)
			(layer "B.SilkS")
		)
		(fp_line
			(start 0.3048 4.1148)
			(end 0.4064 4.1148)
			(stroke
				(width 0.254)
				(type default)
			)
			(layer "B.SilkS")
		)
		(fp_line
			(start 0.3556 5.4356)
			(end 0.1778 5.4102)
			(stroke
				(width 0.254)
				(type default)
			)
			(layer "B.SilkS")
		)
		(fp_line
			(start 0.381 5.4356)
			(end 0.3556 5.4356)
			(stroke
				(width 0.254)
				(type default)
			)
			(layer "B.SilkS")
		)
		(fp_line
			(start 0.4064 4.1148)
			(end 0.5334 4.1402)
			(stroke
				(width 0.254)
				(type default)
			)
			(layer "B.SilkS")
		)
		(fp_line
			(start 0.5334 4.1402)
			(end 0.6096 4.1656)
			(stroke
				(width 0.254)
				(type default)
			)
			(layer "B.SilkS")
		)
		(fp_line
			(start 0.5334 5.4102)
			(end 0.381 5.4356)
			(stroke
				(width 0.254)
				(type default)
			)
			(layer "B.SilkS")
		)
		(fp_line
			(start 0.5588 0)
			(end 1.1938 0)
			(stroke
				(width 0.254)
				(type default)
			)
			(layer "B.SilkS")
		)
		(fp_line
			(start 0.5969 3.0861)
			(end 0.4191 2.6543)
			(stroke
				(width 0.1524)
				(type default)
			)
			(layer "B.SilkS")
		)
		(fp_line
			(start 0.6096 4.1656)
			(end 0.7112 4.2164)
			(stroke
				(width 0.254)
				(type default)
			)
			(layer "B.SilkS")
		)
		(fp_line
			(start 0.6096 5.3848)
			(end 0.5334 5.4102)
			(stroke
				(width 0.254)
				(type default)
			)
			(layer "B.SilkS")
		)
		(fp_line
			(start 0.7112 4.2164)
			(end 0.8128 4.2926)
			(stroke
				(width 0.254)
				(type default)
			)
			(layer "B.SilkS")
		)
		(fp_line
			(start 0.7112 5.334)
			(end 0.6096 5.3848)
			(stroke
				(width 0.254)
				(type default)
			)
			(layer "B.SilkS")
		)
		(fp_line
			(start 0.7747 2.6543)
			(end 0.5969 3.0861)
			(stroke
				(width 0.1524)
				(type default)
			)
			(layer "B.SilkS")
		)
		(fp_line
			(start 0.8128 4.2926)
			(end 0.8382 4.318)
			(stroke
				(width 0.254)
				(type default)
			)
			(layer "B.SilkS")
		)
		(fp_line
			(start 0.8382 4.318)
			(end 0.9144 4.4196)
			(stroke
				(width 0.254)
				(type default)
			)
			(layer "B.SilkS")
		)
		(fp_line
			(start 0.8382 5.2324)
			(end 0.7112 5.334)
			(stroke
				(width 0.254)
				(type default)
			)
			(layer "B.SilkS")
		)
		(fp_line
			(start 0.9144 4.4196)
			(end 0.9652 4.5212)
			(stroke
				(width 0.254)
				(type default)
			)
			(layer "B.SilkS")
		)
		(fp_line
			(start 0.9144 5.1308)
			(end 0.8382 5.2324)
			(stroke
				(width 0.254)
				(type default)
			)
			(layer "B.SilkS")
		)
		(fp_line
			(start 0.9652 4.5212)
			(end 0.9906 4.5974)
			(stroke
				(width 0.254)
				(type default)
			)
			(layer "B.SilkS")
		)
		(fp_line
			(start 0.9652 5.0292)
			(end 0.9144 5.1308)
			(stroke
				(width 0.254)
				(type default)
			)
			(layer "B.SilkS")
		)
		(fp_line
			(start 0.9906 4.5974)
			(end 1.016 4.7498)
			(stroke
				(width 0.254)
				(type default)
			)
			(layer "B.SilkS")
		)
		(fp_line
			(start 0.9906 4.953)
			(end 0.9652 5.0292)
			(stroke
				(width 0.254)
				(type default)
			)
			(layer "B.SilkS")
		)
		(fp_line
			(start 1.016 4.7498)
			(end 1.016 4.826)
			(stroke
				(width 0.254)
				(type default)
			)
			(layer "B.SilkS")
		)
		(fp_line
			(start 1.016 4.7752)
			(end -0.3048 4.7752)
			(stroke
				(width 0.254)
				(type default)
			)
			(layer "B.SilkS")
		)
		(fp_line
			(start 1.016 4.826)
			(end 0.9906 4.953)
			(stroke
				(width 0.254)
				(type default)
			)
			(layer "B.SilkS")
		)
		(fp_line
			(start 1.1557 2.4257)
			(end 1.1557 3.0861)
			(stroke
				(width 0.1524)
				(type default)
			)
			(layer "B.SilkS")
		)
		(fp_line
			(start 1.1938 -1.27)
			(end 0.5588 -1.27)
			(stroke
				(width 0.254)
				(type default)
			)
			(layer "B.SilkS")
		)
		(fp_line
			(start 1.1938 -1.27)
			(end 1.1938 1.2954)
			(stroke
				(width 0.254)
				(type default)
			)
			(layer "B.SilkS")
		)
		(fp_line
			(start 1.3208 -1.524)
			(end -1.4732 1.397)
			(stroke
				(width 0.1524)
				(type default)
			)
			(layer "B.SilkS")
		)
		(fp_line
			(start 1.7526 2.4384)
			(end 1.7526 3.0861)
			(stroke
				(width 0.1524)
				(type default)
			)
			(layer "B.SilkS")
		)
		(fp_line
			(start 1.7526 2.7813)
			(end 1.778 2.7559)
			(stroke
				(width 0.1524)
				(type default)
			)
			(layer "B.SilkS")
		)
		(fp_line
			(start 1.778 2.7559)
			(end 1.8161 2.7305)
			(stroke
				(width 0.1524)
				(type default)
			)
			(layer "B.SilkS")
		)
		(fp_line
			(start 1.778 3.0353)
			(end 1.7526 3.0099)
			(stroke
				(width 0.1524)
				(type default)
			)
			(layer "B.SilkS")
		)
		(fp_line
			(start 1.8161 2.7305)
			(end 1.8542 2.7178)
			(stroke
				(width 0.1524)
				(type default)
			)
			(layer "B.SilkS")
		)
		(fp_line
			(start 1.8161 3.0607)
			(end 1.778 3.0353)
			(stroke
				(width 0.1524)
				(type default)
			)
			(layer "B.SilkS")
		)
		(fp_line
			(start 1.8542 2.7178)
			(end 1.9177 2.7178)
			(stroke
				(width 0.1524)
				(type default)
			)
			(layer "B.SilkS")
		)
		(fp_line
			(start 1.8796 3.0734)
			(end 1.8161 3.0607)
			(stroke
				(width 0.1524)
				(type default)
			)
			(layer "B.SilkS")
		)
		(fp_line
			(start 1.9177 2.7178)
			(end 1.9685 2.7305)
			(stroke
				(width 0.1524)
				(type default)
			)
			(layer "B.SilkS")
		)
		(fp_line
			(start 1.9304 3.0734)
			(end 1.8796 3.0734)
			(stroke
				(width 0.1524)
				(type default)
			)
			(layer "B.SilkS")
		)
		(fp_line
			(start 1.9685 2.7305)
			(end 2.0066 2.7559)
			(stroke
				(width 0.1524)
				(type default)
			)
			(layer "B.SilkS")
		)
		(fp_line
			(start 1.9685 3.0607)
			(end 1.9304 3.0734)
			(stroke
				(width 0.1524)
				(type default)
			)
			(layer "B.SilkS")
		)
		(fp_line
			(start 2.0066 2.7559)
			(end 2.0447 2.794)
			(stroke
				(width 0.1524)
				(type default)
			)
			(layer "B.SilkS")
		)
		(fp_line
			(start 2.0066 3.0353)
			(end 1.9685 3.0607)
			(stroke
				(width 0.1524)
				(type default)
			)
			(layer "B.SilkS")
		)
		(fp_line
			(start 2.032 3.0099)
			(end 2.0066 3.0353)
			(stroke
				(width 0.1524)
				(type default)
			)
			(layer "B.SilkS")
		)
		(fp_line
			(start 2.0447 2.794)
			(end 2.0574 2.8194)
			(stroke
				(width 0.1524)
				(type default)
			)
			(layer "B.SilkS")
		)
		(fp_line
			(start 2.0574 2.8194)
			(end 2.0701 2.8575)
			(stroke
				(width 0.1524)
				(type default)
			)
			(layer "B.SilkS")
		)
		(fp_line
			(start 2.0574 2.9718)
			(end 2.032 3.0099)
			(stroke
				(width 0.1524)
				(type default)
			)
			(layer "B.SilkS")
		)
		(fp_line
			(start 2.0701 2.8575)
			(end 2.0701 2.9083)
			(stroke
				(width 0.1524)
				(type default)
			)
			(layer "B.SilkS")
		)
		(fp_line
			(start 2.0701 2.9083)
			(end 2.0574 2.9718)
			(stroke
				(width 0.1524)
				(type default)
			)
			(layer "B.SilkS")
		)
		(fp_line
			(start 2.3114 2.7686)
			(end 2.3114 3.0861)
			(stroke
				(width 0.1524)
				(type default)
			)
			(layer "B.SilkS")
		)
		(fp_line
			(start 2.3368 2.7178)
			(end 2.3114 2.7686)
			(stroke
				(width 0.1524)
				(type default)
			)
			(layer "B.SilkS")
		)
		(fp_line
			(start 2.3749 2.667)
			(end 2.3368 2.7178)
			(stroke
				(width 0.1524)
				(type default)
			)
			(layer "B.SilkS")
		)
		(fp_line
			(start 2.4257 2.6543)
			(end 2.3749 2.667)
			(stroke
				(width 0.1524)
				(type default)
			)
			(layer "B.SilkS")
		)
		(fp_line
			(start 2.4638 2.6543)
			(end 2.4257 2.6543)
			(stroke
				(width 0.1524)
				(type default)
			)
			(layer "B.SilkS")
		)
		(fp_line
			(start 2.5146 2.667)
			(end 2.4638 2.6543)
			(stroke
				(width 0.1524)
				(type default)
			)
			(layer "B.SilkS")
		)
		(fp_line
			(start 2.54 2.6924)
			(end 2.5146 2.667)
			(stroke
				(width 0.1524)
				(type default)
			)
			(layer "B.SilkS")
		)
		(fp_line
			(start 2.5654 2.7305)
			(end 2.54 2.6924)
			(stroke
				(width 0.1524)
				(type default)
			)
			(layer "B.SilkS")
		)
		(fp_line
			(start 2.5908 2.6543)
			(end 2.5908 3.0861)
			(stroke
				(width 0.1524)
				(type default)
			)
			(layer "B.SilkS")
		)
		(fp_line
			(start 2.5908 2.7813)
			(end 2.5654 2.7305)
			(stroke
				(width 0.1524)
				(type default)
			)
			(layer "B.SilkS")
		)
		(fp_line
			(start 2.8575 2.5527)
			(end 2.8575 2.6416)
			(stroke
				(width 0.1524)
				(type default)
			)
			(layer "B.SilkS")
		)
		(fp_line
			(start 2.8575 2.6416)
			(end 2.8702 2.6797)
			(stroke
				(width 0.1524)
				(type default)
			)
			(layer "B.SilkS")
		)
		(fp_line
			(start 2.8702 2.5146)
			(end 2.8575 2.5527)
			(stroke
				(width 0.1524)
				(type default)
			)
			(layer "B.SilkS")
		)
		(fp_line
			(start 2.8702 2.6797)
			(end 2.8956 2.7178)
			(stroke
				(width 0.1524)
				(type default)
			)
			(layer "B.SilkS")
		)
		(fp_line
			(start 2.8956 2.7178)
			(end 2.921 2.7432)
			(stroke
				(width 0.1524)
				(type default)
			)
			(layer "B.SilkS")
		)
		(fp_line
			(start 2.921 2.7432)
			(end 2.9591 2.7686)
			(stroke
				(width 0.1524)
				(type default)
			)
			(layer "B.SilkS")
		)
		(fp_line
			(start 2.9337 2.4511)
			(end 2.8702 2.5146)
			(stroke
				(width 0.1524)
				(type default)
			)
			(layer "B.SilkS")
		)
		(fp_line
			(start 2.9591 2.7686)
			(end 3.0099 2.8067)
			(stroke
				(width 0.1524)
				(type default)
			)
			(layer "B.SilkS")
		)
		(fp_line
			(start 2.9972 2.4384)
			(end 2.9337 2.4511)
			(stroke
				(width 0.1524)
				(type default)
			)
			(layer "B.SilkS")
		)
		(fp_line
			(start 3.0099 2.8067)
			(end 3.048 2.8575)
			(stroke
				(width 0.1524)
				(type default)
			)
			(layer "B.SilkS")
		)
		(fp_line
			(start 3.048 2.4511)
			(end 2.9972 2.4384)
			(stroke
				(width 0.1524)
				(type default)
			)
			(layer "B.SilkS")
		)
		(fp_line
			(start 3.048 2.8575)
			(end 3.0734 2.8829)
			(stroke
				(width 0.1524)
				(type default)
			)
			(layer "B.SilkS")
		)
		(fp_line
			(start 3.0734 2.8829)
			(end 3.0988 2.921)
			(stroke
				(width 0.1524)
				(type default)
			)
			(layer "B.SilkS")
		)
		(fp_line
			(start 3.0861 2.4765)
			(end 3.048 2.4511)
			(stroke
				(width 0.1524)
				(type default)
			)
			(layer "B.SilkS")
		)
		(fp_line
			(start 3.0988 2.921)
			(end 3.1242 2.9972)
			(stroke
				(width 0.1524)
				(type default)
			)
			(layer "B.SilkS")
		)
		(fp_line
			(start 3.1115 2.5019)
			(end 3.0861 2.4765)
			(stroke
				(width 0.1524)
				(type default)
			)
			(layer "B.SilkS")
		)
		(fp_line
			(start 3.1242 2.9972)
			(end 3.1369 3.0861)
			(stroke
				(width 0.1524)
				(type default)
			)
			(layer "B.SilkS")
		)
		(fp_line
			(start 3.1369 2.5527)
			(end 3.1115 2.5019)
			(stroke
				(width 0.1524)
				(type default)
			)
			(layer "B.SilkS")
		)
		(fp_line
			(start 3.1369 3.0861)
			(end 2.8321 3.0861)
			(stroke
				(width 0.1524)
				(type default)
			)
			(layer "B.SilkS")
		)
		(fp_arc
			(start -1.5748 4.826)
			(mid -0.985639 3.82836)
			(end 0.127 3.5052)
			(stroke
				(width 0.1524)
				(type default)
			)
			(layer "B.SilkS")
		)
		(fp_arc
			(start -0.127 3.5052)
			(mid 0.985642 3.828357)
			(end 1.5748 4.826)
			(stroke
				(width 0.1524)
				(type default)
			)
			(layer "B.SilkS")
		)
		(fp_arc
			(start 0.1524 6.096)
			(mid -0.964559 5.805568)
			(end -1.5748 4.826)
			(stroke
				(width 0.1524)
				(type default)
			)
			(layer "B.SilkS")
		)
		(fp_arc
			(start 0.5588 0)
			(mid -0.0762 -0.635)
			(end 0.5588 -1.27)
			(stroke
				(width 0.254)
				(type default)
			)
			(layer "B.SilkS")
		)
		(fp_arc
			(start 1.5748 4.826)
			(mid 0.964558 5.805567)
			(end -0.1524 6.096)
			(stroke
				(width 0.1524)
				(type default)
			)
			(layer "B.SilkS")
		)
		(fp_circle
			(center -0.9652 0.6858)
			(end -0.35306 0.6858)
			(stroke
				(width 0.254)
				(type default)
			)
			(fill no)
			(layer "B.SilkS")
		)
		(fp_circle
			(center 0 0)
			(end 2.03454 0)
			(stroke
				(width 0.1524)
				(type default)
			)
			(fill no)
			(layer "B.SilkS")
		)
		(fp_circle
			(center 1.8923 2.8956)
			(end 2.07264 2.8956)
			(stroke
				(width 0.1524)
				(type default)
			)
			(fill no)
			(layer "B.SilkS")
		)
	)
	(footprint ""
		(layer "B.Cu")
		(at 12.192 -40.64)
		(property "Reference" "ME2"
			(at 0 0 0)
			(layer "B.SilkS")
			(hide yes)
			(effects
				(font
					(size 1.27 1.27)
				)
				(justify mirror)
			)
		)
		(property "Value" ""
			(at 0 0 0)
			(layer "B.Fab")
			(effects
				(font
					(size 1.27 1.27)
				)
				(justify mirror)
			)
		)
		(duplicate_pad_numbers_are_jumpers no)
		(fp_poly
			(pts
				(xy -1.32715 -3.4417) (xy -2.01295 -3.4417) (xy -2.01295 -3.2512) (xy -1.32715 -3.2512)
			)
			(stroke
				(width 0)
				(type default)
			)
			(fill yes)
			(layer "B.SilkS")
		)
		(fp_poly
			(pts
				(xy 0 -0.5842) (xy -3.3401 -0.5842) (xy -3.3401 0) (xy 0 0)
			)
			(stroke
				(width 0)
				(type default)
			)
			(fill yes)
			(layer "B.SilkS")
		)
		(fp_poly
			(pts
				(xy 0.070612 -0.681228) (xy 0.197612 -0.820928) (xy -0.852678 -1.91262) (xy -0.728472 -3.29184)
				(xy 0.248412 -4.300728) (xy 0.184912 -4.478528) (xy 0.007112 -4.503928) (xy -0.684022 -3.785616)
				(xy -0.65659 -4.0894) (xy -0.97155 -4.3434) (xy -1.22555 -4.3561) (xy -1.46685 -4.4704) (xy -2.01295 -4.4704)
				(xy -2.15265 -4.4069) (xy -2.44475 -4.191) (xy -2.49555 -4.191) (xy -2.59715 -4.2926) (xy -2.80035 -4.2672)
				(xy -2.88925 -4.1656) (xy -2.88925 -4.029456) (xy -3.345688 -4.503928) (xy -3.523488 -4.478528)
				(xy -3.586988 -4.300728) (xy -2.88925 -3.58013) (xy -2.88925 -3.3147) (xy -2.82575 -3.2385) (xy -2.67335 -3.2385)
				(xy -2.521966 -1.875282) (xy -2.545842 -1.85039)
				(arc
					(start -2.55905 -1.8415)
					(mid -2.648099 -1.766068)
					(end -2.717292 -1.672082)
				)
				(xy -3.536188 -0.820928) (xy -3.409188 -0.681228) (xy -3.244088 -0.693928)
				(arc
					(start -2.737612 -1.216914)
					(mid -2.31728 -0.925553)
					(end -1.86055 -1.1557)
				)
				(xy -0.92075 -1.1557) (xy -0.888492 -1.51384) (xy -0.094488 -0.693928)
			)
			(stroke
				(width 0)
				(type default)
			)
			(fill yes)
			(layer "B.SilkS")
		)
	)
	(footprint ""
		(layer "B.Cu")
		(at 28.575 -77.089)
		(property "Reference" "ME4"
			(at 0 0 0)
			(layer "B.SilkS")
			(hide yes)
			(effects
				(font
					(size 1.27 1.27)
				)
				(justify mirror)
			)
		)
		(property "Value" ""
			(at 0 0 0)
			(layer "B.Fab")
			(effects
				(font
					(size 1.27 1.27)
				)
				(justify mirror)
			)
		)
		(duplicate_pad_numbers_are_jumpers no)
	)
	(gr_poly
		(pts
			(xy 15.494 -67.691) (xy 15.494 -65.913) (xy 15.4178 -65.8368) (xy 14.1986 -65.8368) (xy 14.1478 -65.8876)
			(xy 14.1478 -66.4718) (xy 14.478 -66.802) (xy 14.478 -67.2592) (xy 15.0368 -67.818) (xy 15.367 -67.818)
		)
		(stroke
			(width 0)
			(type solid)
		)
		(fill yes)
		(layer "F.Cu")
		(net "GND")
	)
	(gr_poly
		(pts
			(xy 26.416 -9.144) (xy 26.416 -1.905) (xy 26.035 -1.524) (xy 20.32 -1.524) (xy 13.208 -1.524) (xy 12.7 -2.032)
			(xy 12.7 -4.699) (xy 13.208 -5.207) (xy 20.574 -5.207) (xy 21.1455 -5.7785) (xy 21.1455 -9.0805)
			(xy 21.717 -9.652) (xy 25.908 -9.652)
		)
		(stroke
			(width 0)
			(type solid)
		)
		(fill yes)
		(layer "F.Cu")
		(net "GND")
	)
	(gr_poly
		(pts
			(xy 18.415 -68.834) (xy 18.415 -68.326) (xy 19.812 -66.929) (xy 19.812 -65.913) (xy 19.685 -65.786)
			(xy 19.685 -65.405) (xy 19.558 -65.278) (xy 19.177 -65.278) (xy 18.923 -65.532) (xy 18.923 -66.675)
			(xy 18.415 -67.183) (xy 18.415 -67.818) (xy 18.034 -68.199) (xy 18.034 -68.834) (xy 18.161 -68.961)
			(xy 18.288 -68.961)
		)
		(stroke
			(width 0)
			(type solid)
		)
		(fill yes)
		(layer "F.Cu")
		(net "GND")
	)
	(gr_poly
		(pts
			(xy 38.58006 -64.676528) (xy 38.761416 -64.676528) (xy 38.791896 -64.646048) (xy 38.791896 -18.085816)
			(xy 38.37178 -18.085816)
			(arc
				(start 38.311836 -18.117566)
				(mid 38.29199 -18.13626)
				(end 38.284658 -18.162524)
			)
			(arc
				(start 38.284658 -64.468502)
				(mid 38.290089 -64.491611)
				(end 38.305486 -64.50965)
			)
			(arc
				(start 38.305486 -64.50965)
				(mid 38.419014 -64.593744)
				(end 38.531038 -64.67983)
			)
			(xy 38.576758 -64.67983)
		)
		(stroke
			(width 0)
			(type solid)
		)
		(fill yes)
		(layer "F.Cu")
		(net "GND")
	)
	(gr_poly
		(pts
			(xy 0.682498 -63.25997)
			(arc
				(start 0.69215 -63.246254)
				(mid 0.844712 -63.040047)
				(end 1.003808 -62.838838)
			)
			(arc
				(start 1.003808 -62.838838)
				(mid 1.012291 -62.823696)
				(end 1.015238 -62.80658)
			)
			(xy 1.015238 -46.227746) (xy 1.015238 -33.689798)
			(arc
				(start 1.015238 -22.159214)
				(mid 1.012137 -22.14148)
				(end 1.003046 -22.12594)
			)
			(arc
				(start 1.003046 -22.12594)
				(mid 0.901755 -21.999612)
				(end 0.810514 -21.865844)
			)
			(xy 0.508 -21.865844)
			(arc
				(start 0.508 -63.187326)
				(mid 0.517754 -63.217257)
				(end 0.543306 -63.235586)
			)
			(xy 0.651256 -63.270384)
		)
		(stroke
			(width 0)
			(type solid)
		)
		(fill yes)
		(layer "F.Cu")
		(net "GND")
	)
	(gr_poly
		(pts
			(arc
				(start 16.054578 -13.97)
				(mid 15.695422 -13.97)
				(end 16.054578 -13.97)
			)
		)
		(stroke
			(width 0)
			(type solid)
		)
		(fill yes)
		(layer "F.Cu")
		(net "GND")
	)
	(gr_poly
		(pts
			(arc
				(start 16.943578 -29.972)
				(mid 16.584422 -29.972)
				(end 16.943578 -29.972)
			)
		)
		(stroke
			(width 0)
			(type solid)
		)
		(fill yes)
		(layer "F.Cu")
		(net "GND")
	)
	(gr_poly
		(pts
			(arc
				(start 17.959578 -35.179)
				(mid 17.600422 -35.179)
				(end 17.959578 -35.179)
			)
		)
		(stroke
			(width 0)
			(type solid)
		)
		(fill yes)
		(layer "F.Cu")
		(net "GND")
	)
	(gr_poly
		(pts
			(arc
				(start 18.086578 -45.085)
				(mid 17.727422 -45.085)
				(end 18.086578 -45.085)
			)
		)
		(stroke
			(width 0)
			(type solid)
		)
		(fill yes)
		(layer "F.Cu")
		(net "GND")
	)
	(gr_poly
		(pts
			(arc
				(start 20.880578 -32.131)
				(mid 20.521422 -32.131)
				(end 20.880578 -32.131)
			)
		)
		(stroke
			(width 0)
			(type solid)
		)
		(fill yes)
		(layer "F.Cu")
		(net "GND")
	)
	(gr_poly
		(pts
			(arc
				(start 21.642578 -24.13)
				(mid 21.283422 -24.13)
				(end 21.642578 -24.13)
			)
		)
		(stroke
			(width 0)
			(type solid)
		)
		(fill yes)
		(layer "F.Cu")
		(net "GND")
	)
	(gr_poly
		(pts
			(arc
				(start 24.182578 -32.766)
				(mid 23.823422 -32.766)
				(end 24.182578 -32.766)
			)
		)
		(stroke
			(width 0)
			(type solid)
		)
		(fill yes)
		(layer "F.Cu")
		(net "GND")
	)
	(gr_poly
		(pts
			(arc
				(start 31.982918 -34.925)
				(mid 32.002441 -34.921099)
				(end 32.018986 -34.910014)
			)
			(arc
				(start 32.116014 -34.812986)
				(mid 32.127125 -34.796452)
				(end 32.131 -34.776918)
			)
			(arc
				(start 32.131 -31.898082)
				(mid 32.127099 -31.878559)
				(end 32.116014 -31.862014)
			)
			(arc
				(start 32.018986 -31.764986)
				(mid 32.002452 -31.753875)
				(end 31.982918 -31.75)
			)
			(arc
				(start 29.866082 -31.75)
				(mid 29.846559 -31.753901)
				(end 29.830014 -31.764986)
			)
			(arc
				(start 29.73324 -31.86176)
				(mid 29.722314 -31.878206)
				(end 29.718508 -31.897574)
			)
			(arc
				(start 29.718508 -34.650426)
				(mid 29.722341 -34.669783)
				(end 29.73324 -34.68624)
			)
			(arc
				(start 29.957014 -34.910014)
				(mid 29.973548 -34.921125)
				(end 29.993082 -34.925)
			)
		)
		(stroke
			(width 0)
			(type solid)
		)
		(fill yes)
		(layer "F.Cu")
		(net "GND")
	)
	(gr_poly
		(pts
			(arc
				(start 37.824918 -34.925)
				(mid 37.844441 -34.921099)
				(end 37.860986 -34.910014)
			)
			(arc
				(start 37.958014 -34.812986)
				(mid 37.969125 -34.796452)
				(end 37.973 -34.776918)
			)
			(arc
				(start 37.973 -28.215082)
				(mid 37.969099 -28.195559)
				(end 37.958014 -28.179014)
			)
			(arc
				(start 37.860986 -28.081986)
				(mid 37.844452 -28.070875)
				(end 37.824918 -28.067)
			)
			(arc
				(start 36.216082 -28.067)
				(mid 36.196559 -28.070901)
				(end 36.180014 -28.081986)
			)
			(arc
				(start 36.08324 -28.17876)
				(mid 36.072314 -28.195206)
				(end 36.068508 -28.214574)
			)
			(arc
				(start 36.068508 -34.777426)
				(mid 36.072341 -34.796783)
				(end 36.08324 -34.81324)
			)
			(arc
				(start 36.180014 -34.910014)
				(mid 36.196548 -34.921125)
				(end 36.216082 -34.925)
			)
		)
		(stroke
			(width 0)
			(type solid)
		)
		(fill yes)
		(layer "F.Cu")
		(net "GND")
	)
	(gr_poly
		(pts
			(arc
				(start 17.1704 -70.390512)
				(mid 17.206321 -70.375633)
				(end 17.2212 -70.339712)
			)
			(arc
				(start 17.2212 -65.248282)
				(mid 17.217299 -65.228759)
				(end 17.206214 -65.212214)
			)
			(arc
				(start 17.159986 -65.165986)
				(mid 17.143452 -65.154875)
				(end 17.123918 -65.151)
			)
			(arc
				(start 15.896082 -65.151)
				(mid 15.876559 -65.154901)
				(end 15.860014 -65.165986)
			)
			(arc
				(start 15.762986 -65.263014)
				(mid 15.751875 -65.279548)
				(end 15.748 -65.299082)
			)
			(xy 15.748 -65.807336) (xy 15.748508 -65.80759)
			(arc
				(start 15.748508 -67.549522)
				(mid 15.752341 -67.568879)
				(end 15.76324 -67.585336)
			)
			(arc
				(start 16.764508 -68.586858)
				(mid 16.861044 -68.731101)
				(end 16.895064 -68.90131)
			)
			(arc
				(start 16.895064 -69.799962)
				(mid 16.888381 -69.876541)
				(end 16.868648 -69.950838)
			)
			(xy 16.8656 -69.958966)
			(arc
				(start 16.8656 -70.339712)
				(mid 16.880479 -70.375633)
				(end 16.9164 -70.390512)
			)
		)
		(stroke
			(width 0)
			(type solid)
		)
		(fill yes)
		(layer "F.Cu")
		(net "P5V_STBY")
	)
	(gr_poly
		(pts
			(arc
				(start 35.665918 -34.925)
				(mid 35.685441 -34.921099)
				(end 35.701986 -34.910014)
			)
			(arc
				(start 35.799014 -34.812986)
				(mid 35.810125 -34.796452)
				(end 35.814 -34.776918)
			)
			(arc
				(start 35.814 -28.215082)
				(mid 35.810099 -28.195559)
				(end 35.799014 -28.179014)
			)
			(arc
				(start 35.701986 -28.081986)
				(mid 35.685452 -28.070875)
				(end 35.665918 -28.067)
			)
			(arc
				(start 34.057082 -28.067)
				(mid 34.037559 -28.070901)
				(end 34.021014 -28.081986)
			)
			(arc
				(start 33.923986 -28.179014)
				(mid 33.912875 -28.195548)
				(end 33.909 -28.215082)
			)
			(arc
				(start 33.909 -29.950918)
				(mid 33.905099 -29.970441)
				(end 33.894014 -29.986986)
			)
			(arc
				(start 33.796986 -30.084014)
				(mid 33.780452 -30.095125)
				(end 33.760918 -30.099)
			)
			(arc
				(start 32.660082 -30.099)
				(mid 32.640559 -30.102901)
				(end 32.624014 -30.113986)
			)
			(arc
				(start 32.526986 -30.211014)
				(mid 32.515875 -30.227548)
				(end 32.512 -30.247082)
			)
			(arc
				(start 32.512 -34.776918)
				(mid 32.515901 -34.796441)
				(end 32.526986 -34.812986)
			)
			(arc
				(start 32.624014 -34.910014)
				(mid 32.640548 -34.921125)
				(end 32.660082 -34.925)
			)
		)
		(stroke
			(width 0)
			(type solid)
		)
		(fill yes)
		(layer "F.Cu")
		(net "P5V_STBY_DEBUG")
	)
	(gr_poly
		(pts
			(arc
				(start 29.569918 -38.608)
				(mid 29.589441 -38.604099)
				(end 29.605986 -38.593014)
			)
			(arc
				(start 29.703014 -38.495986)
				(mid 29.714125 -38.479452)
				(end 29.718 -38.459918)
			)
			(arc
				(start 29.718 -35.200082)
				(mid 29.714099 -35.180559)
				(end 29.703014 -35.164014)
			)
			(arc
				(start 29.478986 -34.939986)
				(mid 29.467875 -34.923452)
				(end 29.464 -34.903918)
			)
			(arc
				(start 29.464 -31.390082)
				(mid 29.467901 -31.370559)
				(end 29.478986 -31.354014)
			)
			(arc
				(start 29.576014 -31.256986)
				(mid 29.592548 -31.245875)
				(end 29.612082 -31.242)
			)
			(arc
				(start 31.347918 -31.242)
				(mid 31.367441 -31.238099)
				(end 31.383986 -31.227014)
			)
			(arc
				(start 31.481014 -31.129986)
				(mid 31.492125 -31.113452)
				(end 31.496 -31.093918)
			)
			(arc
				(start 31.496 -30.247082)
				(mid 31.492099 -30.227559)
				(end 31.481014 -30.211014)
			)
			(arc
				(start 31.383986 -30.113986)
				(mid 31.367452 -30.102875)
				(end 31.347918 -30.099)
			)
			(arc
				(start 28.780232 -30.099)
				(mid 28.760709 -30.102901)
				(end 28.744164 -30.113986)
			)
			(arc
				(start 28.39593 -30.46222)
				(mid 28.385322 -30.477588)
				(end 28.380944 -30.495748)
			)
			(xy 28.067 -37.031168)
			(arc
				(start 28.067 -38.459918)
				(mid 28.070901 -38.479441)
				(end 28.081986 -38.495986)
			)
			(arc
				(start 28.179014 -38.593014)
				(mid 28.195548 -38.604125)
				(end 28.215082 -38.608)
			)
		)
		(stroke
			(width 0)
			(type solid)
		)
		(fill yes)
		(layer "F.Cu")
		(net "P5V_STBY")
	)
	(gr_poly
		(pts
			(arc
				(start 17.78 -70.390512)
				(mid 17.815921 -70.375633)
				(end 17.8308 -70.339712)
			)
			(xy 17.8308 -69.948806)
			(arc
				(start 17.82826 -69.940932)
				(mid 17.811141 -69.87137)
				(end 17.8054 -69.799962)
			)
			(arc
				(start 17.8054 -68.986146)
				(mid 17.801499 -68.966623)
				(end 17.790414 -68.950078)
			)
			(xy 17.787366 -68.94703) (xy 17.779492 -68.928488)
			(arc
				(start 17.779492 -68.114672)
				(mid 17.783442 -68.095285)
				(end 17.794478 -68.078858)
			)
			(arc
				(start 18.14576 -67.727576)
				(mid 18.156734 -67.711013)
				(end 18.160492 -67.691508)
			)
			(xy 18.160492 -67.07759) (xy 18.161 -67.077336)
			(arc
				(start 18.161 -67.077082)
				(mid 18.164901 -67.057559)
				(end 18.175986 -67.041014)
			)
			(arc
				(start 18.65376 -66.56324)
				(mid 18.664686 -66.546794)
				(end 18.668492 -66.527426)
			)
			(xy 18.668492 -65.42659) (xy 18.669 -65.426336)
			(arc
				(start 18.669 -65.299082)
				(mid 18.665099 -65.279559)
				(end 18.654014 -65.263014)
			)
			(arc
				(start 18.556986 -65.165986)
				(mid 18.540452 -65.154875)
				(end 18.520918 -65.151)
			)
			(arc
				(start 17.547082 -65.151)
				(mid 17.527559 -65.154901)
				(end 17.511014 -65.165986)
			)
			(arc
				(start 17.49044 -65.18656)
				(mid 17.479514 -65.203006)
				(end 17.475708 -65.222374)
			)
			(arc
				(start 17.475708 -70.339712)
				(mid 17.490497 -70.375798)
				(end 17.526508 -70.390512)
			)
		)
		(stroke
			(width 0)
			(type solid)
		)
		(fill yes)
		(layer "F.Cu")
		(net "P3V3_STBY")
	)
	(gr_poly
		(pts
			(arc
				(start 20.171918 -29.337)
				(mid 20.191441 -29.333099)
				(end 20.207986 -29.322014)
			)
			(arc
				(start 20.432014 -29.097986)
				(mid 20.443125 -29.081452)
				(end 20.447 -29.061918)
			)
			(arc
				(start 20.447 -26.183082)
				(mid 20.443099 -26.163559)
				(end 20.432014 -26.147014)
			)
			(arc
				(start 20.207986 -25.922986)
				(mid 20.191452 -25.911875)
				(end 20.171918 -25.908)
			)
			(arc
				(start 19.706082 -25.908)
				(mid 19.686559 -25.904099)
				(end 19.670014 -25.893014)
			)
			(arc
				(start 19.445986 -25.668986)
				(mid 19.434875 -25.652452)
				(end 19.431 -25.632918)
			)
			(xy 19.431 -25.444196) (xy 19.427952 -25.432258)
			(arc
				(start 19.425158 -25.426924)
				(mid 19.373339 -25.290692)
				(end 19.355816 -25.146)
			)
			(arc
				(start 19.355816 -24.837644)
				(mid 19.351866 -24.818257)
				(end 19.34083 -24.80183)
			)
			(arc
				(start 19.318986 -24.779986)
				(mid 19.302452 -24.768875)
				(end 19.282918 -24.765)
			)
			(arc
				(start 17.801082 -24.765)
				(mid 17.781559 -24.768901)
				(end 17.765014 -24.779986)
			)
			(arc
				(start 17.74317 -24.80183)
				(mid 17.732108 -24.818247)
				(end 17.728184 -24.837644)
			)
			(arc
				(start 17.728184 -25.146)
				(mid 17.71061 -25.290679)
				(end 17.658842 -25.426924)
			)
			(arc
				(start 17.658842 -25.426924)
				(mid 17.654493 -25.438381)
				(end 17.653 -25.450546)
			)
			(arc
				(start 17.653 -25.759918)
				(mid 17.649099 -25.779441)
				(end 17.638014 -25.795986)
			)
			(arc
				(start 17.540986 -25.893014)
				(mid 17.524452 -25.904125)
				(end 17.504918 -25.908)
			)
			(arc
				(start 16.912082 -25.908)
				(mid 16.892559 -25.904099)
				(end 16.876014 -25.893014)
			)
			(arc
				(start 16.270986 -25.287986)
				(mid 16.254452 -25.276875)
				(end 16.234918 -25.273)
			)
			(arc
				(start 14.880082 -25.273)
				(mid 14.860559 -25.276901)
				(end 14.844014 -25.287986)
			)
			(arc
				(start 14.619986 -25.512014)
				(mid 14.608875 -25.528548)
				(end 14.605 -25.548082)
			)
			(arc
				(start 14.605 -26.394918)
				(mid 14.601099 -26.414441)
				(end 14.590014 -26.430986)
			)
			(arc
				(start 13.603986 -27.417014)
				(mid 13.592875 -27.433548)
				(end 13.589 -27.453082)
			)
			(arc
				(start 13.589 -28.934918)
				(mid 13.592901 -28.954441)
				(end 13.603986 -28.970986)
			)
			(arc
				(start 13.955014 -29.322014)
				(mid 13.971548 -29.333125)
				(end 13.991082 -29.337)
			)
		)
		(stroke
			(width 0)
			(type solid)
		)
		(fill yes)
		(layer "F.Cu")
		(net "P3V3_STBY")
	)
	(gr_poly
		(pts
			(arc
				(start 38.791896 -1.999996)
				(mid 38.3549 -0.944996)
				(end 37.2999 -0.508)
			)
			(arc
				(start 1.999996 -0.508)
				(mid 0.944996 -0.944996)
				(end 0.508 -1.999996)
			)
			(arc
				(start 0.508 -3.318002)
				(mid 0.522879 -3.353923)
				(end 0.5588 -3.368802)
			)
			(arc
				(start 0.964438 -3.368802)
				(mid 1.000434 -3.353998)
				(end 1.015238 -3.318002)
			)
			(arc
				(start 1.015238 -1.999996)
				(mid 1.303667 -1.303667)
				(end 1.999996 -1.015238)
			)
			(arc
				(start 37.2999 -1.015238)
				(mid 37.996229 -1.303667)
				(end 38.284658 -1.999996)
			)
			(arc
				(start 38.284658 -3.897376)
				(mid 38.291978 -3.923647)
				(end 38.311836 -3.942334)
			)
			(xy 38.464998 -4.024884) (xy 38.791896 -4.024884)
		)
		(stroke
			(width 0)
			(type solid)
		)
		(fill yes)
		(layer "F.Cu")
		(net "GND")
	)
	(gr_poly
		(pts
			(xy 11.100054 -14.899894) (xy 11.099553 -14.79984) (xy 11.091547 -14.599893) (xy 11.075548 -14.400426)
			(xy 11.05158 -14.201758) (xy 11.019683 -14.004209) (xy 10.979908 -13.808094) (xy 10.932318 -13.613728)
			(xy 10.87699 -13.421421) (xy 10.814012 -13.231482) (xy 10.743485 -13.044215) (xy 10.665522 -12.859919)
			(xy 10.580248 -12.67889) (xy 10.487799 -12.501418) (xy 10.388324 -12.327787) (xy 10.281981 -12.158275)
			(xy 10.168942 -11.993154) (xy 10.049386 -11.832687) (xy 9.923506 -11.677132) (xy 9.791503 -11.526738)
			(xy 9.653589 -11.381746) (xy 9.509984 -11.242388) (xy 9.360918 -11.108887) (xy 9.20663 -10.981457)
			(xy 9.047368 -10.860302) (xy 8.883385 -10.745616) (xy 8.714946 -10.637583) (xy 8.542319 -10.536375)
			(xy 8.36578 -10.442155) (xy 8.185614 -10.355074) (xy 8.002107 -10.275271) (xy 7.815555 -10.202874)
			(xy 7.626256 -10.137999) (xy 7.434512 -10.080749) (xy 7.240631 -10.031217) (xy 7.044924 -9.989482)
			(xy 6.847704 -9.95561) (xy 6.649287 -9.929657) (xy 6.44999 -9.911662) (xy 6.250132 -9.901656) (xy 6.050035 -9.899654)
			(xy 5.850017 -9.905659) (xy 5.6504 -9.919662) (xy 5.451503 -9.941641) (xy 5.253644 -9.97156) (xy 5.057141 -10.009371)
			(xy 4.862308 -10.055014) (xy 4.669458 -10.108415) (xy 4.478898 -10.16949) (xy 4.290935 -10.238139)
			(xy 4.105868 -10.314255) (xy 3.923995 -10.397713) (xy 3.745607 -10.488382) (xy 3.57099 -10.586115)
			(xy 3.400422 -10.690756) (xy 3.234178 -10.802138) (xy 3.072523 -10.920082) (xy 2.915716 -11.0444)
			(xy 2.764009 -11.174891) (xy 2.617645 -11.311348) (xy 2.476857 -11.453552) (xy 2.341871 -11.601275)
			(xy 2.212904 -11.75428) (xy 2.090161 -11.912322) (xy 1.973841 -12.075149) (xy 1.864128 -12.242499)
			(xy 1.761198 -12.414105) (xy 1.665217 -12.589692) (xy 1.576337 -12.768978) (xy 1.494702 -12.951677)
			(xy 1.420443 -13.137496) (xy 1.353677 -13.326137) (xy 1.294512 -13.517298) (xy 1.243042 -13.710673)
			(xy 1.199351 -13.905953) (xy 1.163508 -14.102824) (xy 1.13557 -14.300972) (xy 1.115583 -14.500079)
			(xy 1.103577 -14.699826) (xy 1.099574 -14.899894) (xy 3.58242 -14.899894) (xy 3.586452 -14.757458)
			(xy 3.598536 -14.615479) (xy 3.618634 -14.47441) (xy 3.64668 -14.334704) (xy 3.682585 -14.196809)
			(xy 3.726234 -14.061166) (xy 3.777487 -13.92821) (xy 3.83618 -13.798367) (xy 3.902125 -13.672052)
			(xy 3.97511 -13.54967) (xy 4.054903 -13.431613) (xy 4.141247 -13.318259) (xy 4.233865 -13.209972)
			(xy 4.332461 -13.107099) (xy 4.43672 -13.009968) (xy 4.546307 -12.918891) (xy 4.660871 -12.83416)
			(xy 4.780045 -12.756046) (xy 4.903447 -12.6848) (xy 5.030683 -12.620649) (xy 5.161344 -12.563799)
			(xy 5.295012 -12.514433) (xy 5.431259 -12.472708) (xy 5.569648 -12.438757) (xy 5.709737 -12.412691)
			(xy 5.851076 -12.394592) (xy 5.993212 -12.384518) (xy 6.135691 -12.382502) (xy 6.278055 -12.388549)
			(xy 6.41985 -12.402641) (xy 6.56062 -12.424733) (xy 6.699914 -12.454753) (xy 6.837288 -12.492606)
			(xy 6.972299 -12.53817) (xy 7.104517 -12.5913) (xy 7.233517 -12.651824) (xy 7.358886 -12.71955) (xy 7.480223 -12.79426)
			(xy 7.597139 -12.875715) (xy 7.709259 -12.963654) (xy 7.816225 -13.057796) (xy 7.917693 -13.157838)
			(xy 8.013338 -13.263461) (xy 8.102855 -13.374325) (xy 8.185957 -13.490077) (xy 8.262376 -13.610344)
			(xy 8.331869 -13.734742) (xy 8.394213 -13.862873) (xy 8.449208 -13.994326) (xy 8.496679 -14.128679)
			(xy 8.536472 -14.265503) (xy 8.56846 -14.404359) (xy 8.592541 -14.544802) (xy 8.608639 -14.686383)
			(xy 8.6167 -14.828648) (xy 8.617204 -14.899894) (xy 8.6167 -14.97114) (xy 8.608639 -15.113405) (xy 8.592541 -15.254986)
			(xy 8.56846 -15.395429) (xy 8.536472 -15.534285) (xy 8.496679 -15.671109) (xy 8.449208 -15.805462)
			(xy 8.394213 -15.936915) (xy 8.331869 -16.065046) (xy 8.262376 -16.189444) (xy 8.185957 -16.309711)
			(xy 8.102855 -16.425463) (xy 8.013338 -16.536327) (xy 7.917693 -16.64195) (xy 7.816225 -16.741992)
			(xy 7.709259 -16.836134) (xy 7.597139 -16.924073) (xy 7.480223 -17.005528) (xy 7.358886 -17.080238)
			(xy 7.233517 -17.147964) (xy 7.104517 -17.208488) (xy 6.972299 -17.261618) (xy 6.837288 -17.307182)
			(xy 6.699914 -17.345035) (xy 6.56062 -17.375055) (xy 6.41985 -17.397147) (xy 6.278055 -17.411239)
			(xy 6.135691 -17.417286) (xy 5.993212 -17.41527) (xy 5.851076 -17.405196) (xy 5.709737 -17.387097)
			(xy 5.569648 -17.361031) (xy 5.431259 -17.32708) (xy 5.295012 -17.285355) (xy 5.161344 -17.235989)
			(xy 5.030683 -17.179139) (xy 4.903447 -17.114988) (xy 4.780045 -17.043742) (xy 4.660871 -16.965628)
			(xy 4.546307 -16.880897) (xy 4.43672 -16.78982) (xy 4.332461 -16.692689) (xy 4.233865 -16.589816)
			(xy 4.141247 -16.481529) (xy 4.054903 -16.368175) (xy 3.97511 -16.250118) (xy 3.902125 -16.127736)
			(xy 3.83618 -16.001421) (xy 3.777487 -15.871578) (xy 3.726234 -15.738622) (xy 3.682585 -15.602979)
			(xy 3.64668 -15.465084) (xy 3.618634 -15.325378) (xy 3.598536 -15.184309) (xy 3.586452 -15.04233)
			(xy 3.58242 -14.899894) (xy 1.099574 -14.899894) (xy 1.103577 -15.099962) (xy 1.115583 -15.299709)
			(xy 1.13557 -15.498816) (xy 1.163508 -15.696964) (xy 1.199351 -15.893835) (xy 1.243042 -16.089115)
			(xy 1.294512 -16.28249) (xy 1.353677 -16.473651) (xy 1.420443 -16.662292) (xy 1.494702 -16.848111)
			(xy 1.576337 -17.03081) (xy 1.665217 -17.210096) (xy 1.761198 -17.385683) (xy 1.864128 -17.557289)
			(xy 1.973841 -17.724639) (xy 2.090161 -17.887466) (xy 2.212904 -18.045508) (xy 2.341871 -18.198513)
			(xy 2.476857 -18.346236) (xy 2.617645 -18.48844) (xy 2.764009 -18.624897) (xy 2.915716 -18.755388)
			(xy 3.072523 -18.879706) (xy 3.234178 -18.99765) (xy 3.400422 -19.109032) (xy 3.57099 -19.213673)
			(xy 3.745607 -19.311406) (xy 3.923995 -19.402075) (xy 4.105868 -19.485533) (xy 4.290935 -19.561649)
			(xy 4.478898 -19.630298) (xy 4.669458 -19.691373) (xy 4.862308 -19.744774) (xy 5.057141 -19.790417)
			(xy 5.253644 -19.828228) (xy 5.451503 -19.858147) (xy 5.6504 -19.880126) (xy 5.850017 -19.894129)
			(xy 6.050035 -19.900134) (xy 6.250132 -19.898132) (xy 6.44999 -19.888126) (xy 6.649287 -19.870131)
			(xy 6.847704 -19.844178) (xy 7.044924 -19.810306) (xy 7.240631 -19.768571) (xy 7.434512 -19.719039)
			(xy 7.626256 -19.661789) (xy 7.815555 -19.596914) (xy 8.002107 -19.524517) (xy 8.185614 -19.444714)
			(xy 8.36578 -19.357633) (xy 8.542319 -19.263413) (xy 8.714946 -19.162205) (xy 8.883385 -19.054172)
			(xy 9.047368 -18.939486) (xy 9.20663 -18.818331) (xy 9.360918 -18.690901) (xy 9.509984 -18.5574)
			(xy 9.653589 -18.418042) (xy 9.791503 -18.27305) (xy 9.923506 -18.122656) (xy 10.049386 -17.967101)
			(xy 10.168942 -17.806634) (xy 10.281981 -17.641513) (xy 10.388324 -17.472001) (xy 10.487799 -17.29837)
			(xy 10.580248 -17.120898) (xy 10.665522 -16.939869) (xy 10.743485 -16.755573) (xy 10.814012 -16.568306)
			(xy 10.87699 -16.378367) (xy 10.932318 -16.18606) (xy 10.979908 -15.991694) (xy 11.019683 -15.795579)
			(xy 11.05158 -15.59803) (xy 11.075548 -15.399362) (xy 11.091547 -15.199895) (xy 11.099553 -14.999948)
		)
		(stroke
			(width 0)
			(type solid)
		)
		(fill yes)
		(layer "F.Cu")
		(net "GND")
	)
	(gr_poly
		(pts
			(xy 37.800026 -62.875922) (xy 37.799525 -62.775868) (xy 37.791519 -62.575921) (xy 37.77552 -62.376454)
			(xy 37.751552 -62.177786) (xy 37.719655 -61.980237) (xy 37.67988 -61.784122) (xy 37.63229 -61.589756)
			(xy 37.576962 -61.397449) (xy 37.513984 -61.20751) (xy 37.443457 -61.020243) (xy 37.365494 -60.835947)
			(xy 37.28022 -60.654918) (xy 37.187771 -60.477446) (xy 37.088296 -60.303815) (xy 36.981953 -60.134303)
			(xy 36.868914 -59.969182) (xy 36.749358 -59.808715) (xy 36.623478 -59.65316) (xy 36.491475 -59.502766)
			(xy 36.353561 -59.357774) (xy 36.209956 -59.218416) (xy 36.06089 -59.084915) (xy 35.906602 -58.957485)
			(xy 35.74734 -58.83633) (xy 35.583357 -58.721644) (xy 35.414918 -58.613611) (xy 35.242291 -58.512403)
			(xy 35.065752 -58.418183) (xy 34.885586 -58.331102) (xy 34.702079 -58.251299) (xy 34.515527 -58.178902)
			(xy 34.326228 -58.114027) (xy 34.134484 -58.056777) (xy 33.940603 -58.007245) (xy 33.744896 -57.96551)
			(xy 33.547676 -57.931638) (xy 33.349259 -57.905685) (xy 33.149962 -57.88769) (xy 32.950104 -57.877684)
			(xy 32.750007 -57.875682) (xy 32.549989 -57.881687) (xy 32.350372 -57.89569) (xy 32.151475 -57.917669)
			(xy 31.953616 -57.947588) (xy 31.757113 -57.985399) (xy 31.56228 -58.031042) (xy 31.36943 -58.084443)
			(xy 31.17887 -58.145518) (xy 30.990907 -58.214167) (xy 30.80584 -58.290283) (xy 30.623967 -58.373741)
			(xy 30.445579 -58.46441) (xy 30.270962 -58.562143) (xy 30.100394 -58.666784) (xy 29.93415 -58.778166)
			(xy 29.772495 -58.89611) (xy 29.615688 -59.020428) (xy 29.463981 -59.150919) (xy 29.317617 -59.287376)
			(xy 29.176829 -59.42958) (xy 29.041843 -59.577303) (xy 28.912876 -59.730308) (xy 28.790133 -59.88835)
			(xy 28.673813 -60.051177) (xy 28.5641 -60.218527) (xy 28.46117 -60.390133) (xy 28.365189 -60.56572)
			(xy 28.276309 -60.745006) (xy 28.194674 -60.927705) (xy 28.120415 -61.113524) (xy 28.053649 -61.302165)
			(xy 27.994484 -61.493326) (xy 27.943014 -61.686701) (xy 27.899323 -61.881981) (xy 27.86348 -62.078852)
			(xy 27.835542 -62.277) (xy 27.815555 -62.476107) (xy 27.803549 -62.675854) (xy 27.799546 -62.875922)
			(xy 30.282392 -62.875922) (xy 30.286424 -62.733486) (xy 30.298508 -62.591507) (xy 30.318606 -62.450438)
			(xy 30.346652 -62.310732) (xy 30.382557 -62.172837) (xy 30.426206 -62.037194) (xy 30.477459 -61.904238)
			(xy 30.536152 -61.774395) (xy 30.602097 -61.64808) (xy 30.675082 -61.525698) (xy 30.754875 -61.407641)
			(xy 30.841219 -61.294287) (xy 30.933837 -61.186) (xy 31.032433 -61.083127) (xy 31.136692 -60.985996)
			(xy 31.246279 -60.894919) (xy 31.360843 -60.810188) (xy 31.480017 -60.732074) (xy 31.603419 -60.660828)
			(xy 31.730655 -60.596677) (xy 31.861316 -60.539827) (xy 31.994984 -60.490461) (xy 32.131231 -60.448736)
			(xy 32.26962 -60.414785) (xy 32.409709 -60.388719) (xy 32.551048 -60.37062) (xy 32.693184 -60.360546)
			(xy 32.835663 -60.35853) (xy 32.978027 -60.364577) (xy 33.119822 -60.378669) (xy 33.260592 -60.400761)
			(xy 33.399886 -60.430781) (xy 33.53726 -60.468634) (xy 33.672271 -60.514198) (xy 33.804489 -60.567328)
			(xy 33.933489 -60.627852) (xy 34.058858 -60.695578) (xy 34.180195 -60.770288) (xy 34.297111 -60.851743)
			(xy 34.409231 -60.939682) (xy 34.516197 -61.033824) (xy 34.617665 -61.133866) (xy 34.71331 -61.239489)
			(xy 34.802827 -61.350353) (xy 34.885929 -61.466105) (xy 34.962348 -61.586372) (xy 35.031841 -61.71077)
			(xy 35.094185 -61.838901) (xy 35.14918 -61.970354) (xy 35.196651 -62.104707) (xy 35.236444 -62.241531)
			(xy 35.268432 -62.380387) (xy 35.292513 -62.52083) (xy 35.308611 -62.662411) (xy 35.316672 -62.804676)
			(xy 35.317176 -62.875922) (xy 35.316672 -62.947168) (xy 35.308611 -63.089433) (xy 35.292513 -63.231014)
			(xy 35.268432 -63.371457) (xy 35.236444 -63.510313) (xy 35.196651 -63.647137) (xy 35.14918 -63.78149)
			(xy 35.094185 -63.912943) (xy 35.031841 -64.041074) (xy 34.962348 -64.165472) (xy 34.885929 -64.285739)
			(xy 34.802827 -64.401491) (xy 34.71331 -64.512355) (xy 34.617665 -64.617978) (xy 34.516197 -64.71802)
			(xy 34.409231 -64.812162) (xy 34.297111 -64.900101) (xy 34.180195 -64.981556) (xy 34.058858 -65.056266)
			(xy 33.933489 -65.123992) (xy 33.804489 -65.184516) (xy 33.672271 -65.237646) (xy 33.53726 -65.28321)
			(xy 33.399886 -65.321063) (xy 33.260592 -65.351083) (xy 33.119822 -65.373175) (xy 32.978027 -65.387267)
			(xy 32.835663 -65.393314) (xy 32.693184 -65.391298) (xy 32.551048 -65.381224) (xy 32.409709 -65.363125)
			(xy 32.26962 -65.337059) (xy 32.131231 -65.303108) (xy 31.994984 -65.261383) (xy 31.861316 -65.212017)
			(xy 31.730655 -65.155167) (xy 31.603419 -65.091016) (xy 31.480017 -65.01977) (xy 31.360843 -64.941656)
			(xy 31.246279 -64.856925) (xy 31.136692 -64.765848) (xy 31.032433 -64.668717) (xy 30.933837 -64.565844)
			(xy 30.841219 -64.457557) (xy 30.754875 -64.344203) (xy 30.675082 -64.226146) (xy 30.602097 -64.103764)
			(xy 30.536152 -63.977449) (xy 30.477459 -63.847606) (xy 30.426206 -63.71465) (xy 30.382557 -63.579007)
			(xy 30.346652 -63.441112) (xy 30.318606 -63.301406) (xy 30.298508 -63.160337) (xy 30.286424 -63.018358)
			(xy 30.282392 -62.875922) (xy 27.799546 -62.875922) (xy 27.803549 -63.07599) (xy 27.815555 -63.275737)
			(xy 27.835542 -63.474844) (xy 27.86348 -63.672992) (xy 27.899323 -63.869863) (xy 27.943014 -64.065143)
			(xy 27.994484 -64.258518) (xy 28.053649 -64.449679) (xy 28.120415 -64.63832) (xy 28.194674 -64.824139)
			(xy 28.276309 -65.006838) (xy 28.365189 -65.186124) (xy 28.46117 -65.361711) (xy 28.5641 -65.533317)
			(xy 28.673813 -65.700667) (xy 28.790133 -65.863494) (xy 28.912876 -66.021536) (xy 29.041843 -66.174541)
			(xy 29.176829 -66.322264) (xy 29.317617 -66.464468) (xy 29.463981 -66.600925) (xy 29.615688 -66.731416)
			(xy 29.772495 -66.855734) (xy 29.93415 -66.973678) (xy 30.100394 -67.08506) (xy 30.270962 -67.189701)
			(xy 30.445579 -67.287434) (xy 30.623967 -67.378103) (xy 30.80584 -67.461561) (xy 30.990907 -67.537677)
			(xy 31.17887 -67.606326) (xy 31.36943 -67.667401) (xy 31.56228 -67.720802) (xy 31.757113 -67.766445)
			(xy 31.953616 -67.804256) (xy 32.151475 -67.834175) (xy 32.350372 -67.856154) (xy 32.549989 -67.870157)
			(xy 32.750007 -67.876162) (xy 32.950104 -67.87416) (xy 33.149962 -67.864154) (xy 33.349259 -67.846159)
			(xy 33.547676 -67.820206) (xy 33.744896 -67.786334) (xy 33.940603 -67.744599) (xy 34.134484 -67.695067)
			(xy 34.326228 -67.637817) (xy 34.515527 -67.572942) (xy 34.702079 -67.500545) (xy 34.885586 -67.420742)
			(xy 35.065752 -67.333661) (xy 35.242291 -67.239441) (xy 35.414918 -67.138233) (xy 35.583357 -67.0302)
			(xy 35.74734 -66.915514) (xy 35.906602 -66.794359) (xy 36.06089 -66.666929) (xy 36.209956 -66.533428)
			(xy 36.353561 -66.39407) (xy 36.491475 -66.249078) (xy 36.623478 -66.098684) (xy 36.749358 -65.943129)
			(xy 36.868914 -65.782662) (xy 36.981953 -65.617541) (xy 37.088296 -65.448029) (xy 37.187771 -65.274398)
			(xy 37.28022 -65.096926) (xy 37.365494 -64.915897) (xy 37.443457 -64.731601) (xy 37.513984 -64.544334)
			(xy 37.576962 -64.354395) (xy 37.63229 -64.162088) (xy 37.67988 -63.967722) (xy 37.719655 -63.771607)
			(xy 37.751552 -63.574058) (xy 37.77552 -63.37539) (xy 37.791519 -63.175923) (xy 37.799525 -62.975976)
		)
		(stroke
			(width 0)
			(type solid)
		)
		(fill yes)
		(layer "F.Cu")
		(net "GND")
	)
	(gr_poly
		(pts
			(xy 2.599944 -74.480166) (xy 2.600261 -74.536579) (xy 3.589526 -74.536579) (xy 3.590621 -74.380827)
			(xy 3.599769 -74.225341) (xy 3.616944 -74.070535) (xy 3.642102 -73.916825) (xy 3.675174 -73.764621)
			(xy 3.716073 -73.614331) (xy 3.764689 -73.466357) (xy 3.820892 -73.321095) (xy 3.88453 -73.178934)
			(xy 3.955435 -73.040254) (xy 4.033417 -72.905425) (xy 4.118266 -72.77481) (xy 4.209756 -72.648757)
			(xy 4.25831 -72.587866) (xy 4.293252 -72.543781) (xy 4.357152 -72.451189) (xy 4.413885 -72.35404)
			(xy 4.463128 -72.252888) (xy 4.5046 -72.14831) (xy 4.538065 -72.040901) (xy 4.563332 -71.931274)
			(xy 4.580257 -71.820053) (xy 4.588744 -71.707873) (xy 4.589272 -71.651622) (xy 4.589272 -70.980046)
			(xy 4.589768 -70.916874) (xy 4.597701 -70.790779) (xy 4.613536 -70.665431) (xy 4.637211 -70.541325)
			(xy 4.668631 -70.41895) (xy 4.707674 -70.29879) (xy 4.754184 -70.181318) (xy 4.807979 -70.066998)
			(xy 4.868846 -69.956282) (xy 4.936544 -69.849606) (xy 5.010807 -69.747392) (xy 5.091342 -69.650042)
			(xy 5.177831 -69.557941) (xy 5.269932 -69.471452) (xy 5.367282 -69.390917) (xy 5.469496 -69.316654)
			(xy 5.576172 -69.248956) (xy 5.686888 -69.188089) (xy 5.801208 -69.134294) (xy 5.91868 -69.087784)
			(xy 6.03884 -69.048741) (xy 6.161215 -69.017321) (xy 6.285321 -68.993646) (xy 6.410669 -68.977811)
			(xy 6.536764 -68.969878) (xy 6.663108 -68.969878) (xy 6.789203 -68.977811) (xy 6.914551 -68.993646)
			(xy 7.038657 -69.017321) (xy 7.161032 -69.048741) (xy 7.281192 -69.087784) (xy 7.398664 -69.134294)
			(xy 7.512984 -69.188089) (xy 7.6237 -69.248956) (xy 7.730376 -69.316654) (xy 7.83259 -69.390917)
			(xy 7.92994 -69.471452) (xy 8.022041 -69.557941) (xy 8.10853 -69.650042) (xy 8.189065 -69.747392)
			(xy 8.263328 -69.849606) (xy 8.331026 -69.956282) (xy 8.391893 -70.066998) (xy 8.445688 -70.181318)
			(xy 8.492198 -70.29879) (xy 8.531241 -70.41895) (xy 8.562661 -70.541325) (xy 8.586336 -70.665431)
			(xy 8.602171 -70.790779) (xy 8.610104 -70.916874) (xy 8.6106 -70.980046) (xy 8.6106 -71.651622) (xy 8.611105 -71.707859)
			(xy 8.619605 -71.820013) (xy 8.636542 -71.931205) (xy 8.661817 -72.040803) (xy 8.695286 -72.148183)
			(xy 8.736761 -72.252732) (xy 8.786003 -72.353855) (xy 8.842732 -72.450975) (xy 8.906626 -72.54354)
			(xy 8.941562 -72.587612) (xy 8.990123 -72.648497) (xy 9.081627 -72.77454) (xy 9.16649 -72.905146)
			(xy 9.244486 -73.039966) (xy 9.315406 -73.178639) (xy 9.379061 -73.320793) (xy 9.435279 -73.466049)
			(xy 9.483911 -73.614018) (xy 9.524826 -73.764303) (xy 9.557915 -73.916504) (xy 9.583089 -74.070211)
			(xy 9.600282 -74.225015) (xy 9.609446 -74.380501) (xy 9.610558 -74.536252) (xy 9.603614 -74.691853)
			(xy 9.588634 -74.846886) (xy 9.565656 -75.000937) (xy 9.534743 -75.153594) (xy 9.495978 -75.304449)
			(xy 9.449463 -75.453097) (xy 9.395325 -75.59914) (xy 9.333706 -75.742189) (xy 9.264773 -75.88186)
			(xy 9.18871 -76.01778) (xy 9.10572 -76.149584) (xy 9.016025 -76.276921) (xy 8.919865 -76.399449)
			(xy 8.817499 -76.51684) (xy 8.709198 -76.628781) (xy 8.595254 -76.734973) (xy 8.475972 -76.835129)
			(xy 8.351669 -76.928984) (xy 8.22268 -77.016286) (xy 8.089349 -77.0968) (xy 7.952033 -77.170312)
			(xy 7.811099 -77.236625) (xy 7.666924 -77.295562) (xy 7.519895 -77.346964) (xy 7.370405 -77.390694)
			(xy 7.218853 -77.426636) (xy 7.065645 -77.454693) (xy 6.911192 -77.47479) (xy 6.755906 -77.486873)
			(xy 6.600203 -77.49091) (xy 6.444499 -77.48689) (xy 6.289212 -77.474824) (xy 6.134756 -77.454744)
			(xy 5.981545 -77.426703) (xy 5.829989 -77.390778) (xy 5.680494 -77.347064) (xy 5.533459 -77.295678)
			(xy 5.389279 -77.236757) (xy 5.248338 -77.170459) (xy 5.111013 -77.096962) (xy 4.977674 -77.016462)
			(xy 4.848675 -76.929174) (xy 4.724362 -76.835333) (xy 4.605069 -76.735189) (xy 4.491113 -76.629011)
			(xy 4.382801 -76.517081) (xy 4.280421 -76.399701) (xy 4.184248 -76.277183) (xy 4.09454 -76.149856)
			(xy 4.011535 -76.018061) (xy 3.935457 -75.882149) (xy 3.866509 -75.742486) (xy 3.804875 -75.599444)
			(xy 3.75072 -75.453406) (xy 3.70419 -75.304763) (xy 3.665408 -75.153913) (xy 3.634479 -75.00126)
			(xy 3.611484 -74.847211) (xy 3.596487 -74.692179) (xy 3.589526 -74.536579) (xy 2.600261 -74.536579)
			(xy 2.600448 -74.569929) (xy 2.608502 -74.749275) (xy 2.624595 -74.928079) (xy 2.648693 -75.105981)
			(xy 2.680749 -75.282623) (xy 2.720697 -75.457649) (xy 2.768458 -75.630706) (xy 2.823935 -75.801446)
			(xy 2.887016 -75.969525) (xy 2.957575 -76.134605) (xy 3.035468 -76.296353) (xy 3.120541 -76.454443)
			(xy 3.21262 -76.608558) (xy 3.31152 -76.758386) (xy 3.417044 -76.903626) (xy 3.528977 -77.043986)
			(xy 3.647094 -77.179182) (xy 3.771159 -77.308943) (xy 3.90092 -77.433008) (xy 4.036116 -77.551125)
			(xy 4.176476 -77.663058) (xy 4.321716 -77.768582) (xy 4.471544 -77.867482) (xy 4.625659 -77.959561)
			(xy 4.783749 -78.044634) (xy 4.945497 -78.122527) (xy 5.110577 -78.193086) (xy 5.278656 -78.256167)
			(xy 5.449396 -78.311644) (xy 5.622453 -78.359405) (xy 5.797479 -78.399353) (xy 5.974121 -78.431409)
			(xy 6.152023 -78.455507) (xy 6.330827 -78.4716) (xy 6.510173 -78.479654) (xy 6.689699 -78.479654)
			(xy 6.869045 -78.4716) (xy 7.047849 -78.455507) (xy 7.225751 -78.431409) (xy 7.402393 -78.399353)
			(xy 7.577419 -78.359405) (xy 7.750476 -78.311644) (xy 7.921216 -78.256167) (xy 8.089295 -78.193086)
			(xy 8.254375 -78.122527) (xy 8.416123 -78.044634) (xy 8.574213 -77.959561) (xy 8.728328 -77.867482)
			(xy 8.878156 -77.768582) (xy 9.023396 -77.663058) (xy 9.163756 -77.551125) (xy 9.298952 -77.433008)
			(xy 9.428713 -77.308943) (xy 9.552778 -77.179182) (xy 9.670895 -77.043986) (xy 9.782828 -76.903626)
			(xy 9.888352 -76.758386) (xy 9.987252 -76.608558) (xy 10.079331 -76.454443) (xy 10.164404 -76.296353)
			(xy 10.242297 -76.134605) (xy 10.312856 -75.969525) (xy 10.375937 -75.801446) (xy 10.431414 -75.630706)
			(xy 10.479175 -75.457649) (xy 10.519123 -75.282623) (xy 10.551179 -75.105981) (xy 10.575277 -74.928079)
			(xy 10.59137 -74.749275) (xy 10.599424 -74.569929) (xy 10.599928 -74.480166) (xy 10.599928 -70.980046)
			(xy 10.599424 -70.890283) (xy 10.59137 -70.710937) (xy 10.575277 -70.532133) (xy 10.551179 -70.354231)
			(xy 10.519123 -70.177589) (xy 10.479175 -70.002563) (xy 10.431414 -69.829506) (xy 10.375937 -69.658766)
			(xy 10.312856 -69.490687) (xy 10.242297 -69.325607) (xy 10.164404 -69.163859) (xy 10.079331 -69.005769)
			(xy 9.987252 -68.851654) (xy 9.888352 -68.701826) (xy 9.782828 -68.556586) (xy 9.670895 -68.416226)
			(xy 9.552778 -68.28103) (xy 9.428713 -68.151269) (xy 9.298952 -68.027204) (xy 9.163756 -67.909087)
			(xy 9.023396 -67.797154) (xy 8.878156 -67.69163) (xy 8.728328 -67.59273) (xy 8.574213 -67.500651)
			(xy 8.416123 -67.415578) (xy 8.254375 -67.337685) (xy 8.089295 -67.267126) (xy 7.921216 -67.204045)
			(xy 7.750476 -67.148568) (xy 7.577419 -67.100807) (xy 7.402393 -67.060859) (xy 7.225751 -67.028803)
			(xy 7.047849 -67.004705) (xy 6.869045 -66.988612) (xy 6.689699 -66.980558) (xy 6.510173 -66.980558)
			(xy 6.330827 -66.988612) (xy 6.152023 -67.004705) (xy 5.974121 -67.028803) (xy 5.797479 -67.060859)
			(xy 5.622453 -67.100807) (xy 5.449396 -67.148568) (xy 5.278656 -67.204045) (xy 5.110577 -67.267126)
			(xy 4.945497 -67.337685) (xy 4.783749 -67.415578) (xy 4.625659 -67.500651) (xy 4.471544 -67.59273)
			(xy 4.321716 -67.69163) (xy 4.176476 -67.797154) (xy 4.036116 -67.909087) (xy 3.90092 -68.027204)
			(xy 3.771159 -68.151269) (xy 3.647094 -68.28103) (xy 3.528977 -68.416226) (xy 3.417044 -68.556586)
			(xy 3.31152 -68.701826) (xy 3.21262 -68.851654) (xy 3.120541 -69.005769) (xy 3.035468 -69.163859)
			(xy 2.957575 -69.325607) (xy 2.887016 -69.490687) (xy 2.823935 -69.658766) (xy 2.768458 -69.829506)
			(xy 2.720697 -70.002563) (xy 2.680749 -70.177589) (xy 2.648693 -70.354231) (xy 2.624595 -70.532133)
			(xy 2.608502 -70.710937) (xy 2.600448 -70.890283) (xy 2.599944 -70.980046)
		)
		(stroke
			(width 0)
			(type solid)
		)
		(fill yes)
		(layer "F.Cu")
		(net "GND")
	)
	(gr_poly
		(pts
			(xy 30.600142 -14.53007) (xy 30.600459 -14.586486) (xy 31.589723 -14.586486) (xy 31.590818 -14.430735)
			(xy 31.599965 -14.275248) (xy 31.617141 -14.120442) (xy 31.642299 -13.966731) (xy 31.675371 -13.814527)
			(xy 31.71627 -13.664237) (xy 31.764886 -13.516263) (xy 31.821089 -13.371001) (xy 31.884728 -13.228839)
			(xy 31.955633 -13.090158) (xy 32.033614 -12.95533) (xy 32.118464 -12.824714) (xy 32.209954 -12.698661)
			(xy 32.258508 -12.63777) (xy 32.293443 -12.59368) (xy 32.357343 -12.501088) (xy 32.414076 -12.40394)
			(xy 32.463319 -12.302789) (xy 32.504792 -12.198211) (xy 32.538258 -12.090803) (xy 32.563526 -11.981177)
			(xy 32.580453 -11.869957) (xy 32.588941 -11.757776) (xy 32.58947 -11.701526) (xy 32.58947 -11.02995)
			(xy 32.589966 -10.966778) (xy 32.597899 -10.840683) (xy 32.613734 -10.715335) (xy 32.637409 -10.591229)
			(xy 32.668829 -10.468854) (xy 32.707872 -10.348694) (xy 32.754382 -10.231222) (xy 32.808177 -10.116902)
			(xy 32.869044 -10.006186) (xy 32.936742 -9.89951) (xy 33.011005 -9.797296) (xy 33.09154 -9.699946)
			(xy 33.178029 -9.607845) (xy 33.27013 -9.521356) (xy 33.36748 -9.440821) (xy 33.469694 -9.366558)
			(xy 33.57637 -9.29886) (xy 33.687086 -9.237993) (xy 33.801406 -9.184198) (xy 33.918878 -9.137688)
			(xy 34.039038 -9.098645) (xy 34.161413 -9.067225) (xy 34.285519 -9.04355) (xy 34.410867 -9.027715)
			(xy 34.536962 -9.019782) (xy 34.663306 -9.019782) (xy 34.789401 -9.027715) (xy 34.914749 -9.04355)
			(xy 35.038855 -9.067225) (xy 35.16123 -9.098645) (xy 35.28139 -9.137688) (xy 35.398862 -9.184198)
			(xy 35.513182 -9.237993) (xy 35.623898 -9.29886) (xy 35.730574 -9.366558) (xy 35.832788 -9.440821)
			(xy 35.930138 -9.521356) (xy 36.022239 -9.607845) (xy 36.108728 -9.699946) (xy 36.189263 -9.797296)
			(xy 36.263526 -9.89951) (xy 36.331224 -10.006186) (xy 36.392091 -10.116902) (xy 36.445886 -10.231222)
			(xy 36.492396 -10.348694) (xy 36.531439 -10.468854) (xy 36.562859 -10.591229) (xy 36.586534 -10.715335)
			(xy 36.602369 -10.840683) (xy 36.610302 -10.966778) (xy 36.610798 -11.02995) (xy 36.610798 -11.701526)
			(xy 36.611301 -11.757763) (xy 36.619802 -11.869917) (xy 36.636738 -11.981109) (xy 36.662013 -12.090707)
			(xy 36.695484 -12.198087) (xy 36.736958 -12.302636) (xy 36.7862 -12.403759) (xy 36.84293 -12.500879)
			(xy 36.906823 -12.593444) (xy 36.94176 -12.637516) (xy 36.990325 -12.698398) (xy 37.081829 -12.824441)
			(xy 37.166693 -12.955048) (xy 37.244689 -13.089868) (xy 37.315609 -13.228541) (xy 37.379264 -13.370695)
			(xy 37.435483 -13.515951) (xy 37.484115 -13.66392) (xy 37.52503 -13.814206) (xy 37.558119 -13.966406)
			(xy 37.583294 -14.120114) (xy 37.600487 -14.274918) (xy 37.609651 -14.430404) (xy 37.610763 -14.586156)
			(xy 37.60382 -14.741757) (xy 37.588839 -14.89679) (xy 37.565862 -15.050842) (xy 37.534949 -15.203499)
			(xy 37.496184 -15.354354) (xy 37.449669 -15.503002) (xy 37.395531 -15.649046) (xy 37.333912 -15.792095)
			(xy 37.264979 -15.931766) (xy 37.188916 -16.067686) (xy 37.105926 -16.199491) (xy 37.016231 -16.326828)
			(xy 36.920071 -16.449356) (xy 36.817705 -16.566748) (xy 36.709404 -16.67869) (xy 36.59546 -16.784881)
			(xy 36.476177 -16.885038) (xy 36.351875 -16.978893) (xy 36.222885 -17.066195) (xy 36.089554 -17.146709)
			(xy 35.952238 -17.220222) (xy 35.811304 -17.286535) (xy 35.667129 -17.345472) (xy 35.5201 -17.396874)
			(xy 35.370609 -17.440605) (xy 35.219057 -17.476547) (xy 35.065849 -17.504604) (xy 34.911395 -17.524701)
			(xy 34.756109 -17.536784) (xy 34.600405 -17.540821) (xy 34.444702 -17.536801) (xy 34.289414 -17.524735)
			(xy 34.134958 -17.504655) (xy 33.981747 -17.476615) (xy 33.830191 -17.44069) (xy 33.680695 -17.396975)
			(xy 33.53366 -17.345589) (xy 33.389479 -17.286668) (xy 33.248538 -17.22037) (xy 33.111213 -17.146873)
			(xy 32.977873 -17.066373) (xy 32.848874 -16.979086) (xy 32.724562 -16.885244) (xy 32.605268 -16.7851)
			(xy 32.491312 -16.678921) (xy 32.382999 -16.566992) (xy 32.28062 -16.449611) (xy 32.184447 -16.327093)
			(xy 32.094738 -16.199766) (xy 32.011733 -16.067971) (xy 31.935655 -15.932059) (xy 31.866706 -15.792395)
			(xy 31.805072 -15.649353) (xy 31.750917 -15.503315) (xy 31.704387 -15.354672) (xy 31.665605 -15.203822)
			(xy 31.634675 -15.051168) (xy 31.611681 -14.897119) (xy 31.596684 -14.742087) (xy 31.589723 -14.586486)
			(xy 30.600459 -14.586486) (xy 30.600646 -14.619833) (xy 30.6087 -14.799179) (xy 30.624793 -14.977983)
			(xy 30.648891 -15.155885) (xy 30.680947 -15.332527) (xy 30.720895 -15.507553) (xy 30.768656 -15.68061)
			(xy 30.824133 -15.85135) (xy 30.887214 -16.019429) (xy 30.957773 -16.184509) (xy 31.035666 -16.346257)
			(xy 31.120739 -16.504347) (xy 31.212818 -16.658462) (xy 31.311718 -16.80829) (xy 31.417242 -16.95353)
			(xy 31.529175 -17.09389) (xy 31.647292 -17.229086) (xy 31.771357 -17.358847) (xy 31.901118 -17.482912)
			(xy 32.036314 -17.601029) (xy 32.176674 -17.712962) (xy 32.321914 -17.818486) (xy 32.471742 -17.917386)
			(xy 32.625857 -18.009465) (xy 32.783947 -18.094538) (xy 32.945695 -18.172431) (xy 33.110775 -18.24299)
			(xy 33.278854 -18.306071) (xy 33.449594 -18.361548) (xy 33.622651 -18.409309) (xy 33.797677 -18.449257)
			(xy 33.974319 -18.481313) (xy 34.152221 -18.505411) (xy 34.331025 -18.521504) (xy 34.510371 -18.529558)
			(xy 34.689897 -18.529558) (xy 34.869243 -18.521504) (xy 35.048047 -18.505411) (xy 35.225949 -18.481313)
			(xy 35.402591 -18.449257) (xy 35.577617 -18.409309) (xy 35.750674 -18.361548) (xy 35.921414 -18.306071)
			(xy 36.089493 -18.24299) (xy 36.254573 -18.172431) (xy 36.416321 -18.094538) (xy 36.574411 -18.009465)
			(xy 36.728526 -17.917386) (xy 36.878354 -17.818486) (xy 37.023594 -17.712962) (xy 37.163954 -17.601029)
			(xy 37.29915 -17.482912) (xy 37.428911 -17.358847) (xy 37.552976 -17.229086) (xy 37.671093 -17.09389)
			(xy 37.783026 -16.95353) (xy 37.88855 -16.80829) (xy 37.98745 -16.658462) (xy 38.079529 -16.504347)
			(xy 38.164602 -16.346257) (xy 38.242495 -16.184509) (xy 38.313054 -16.019429) (xy 38.376135 -15.85135)
			(xy 38.431612 -15.68061) (xy 38.479373 -15.507553) (xy 38.519321 -15.332527) (xy 38.551377 -15.155885)
			(xy 38.575475 -14.977983) (xy 38.591568 -14.799179) (xy 38.599622 -14.619833) (xy 38.600126 -14.53007)
			(xy 38.600126 -11.02995) (xy 38.599622 -10.940187) (xy 38.591568 -10.760841) (xy 38.575475 -10.582037)
			(xy 38.551377 -10.404135) (xy 38.519321 -10.227493) (xy 38.479373 -10.052467) (xy 38.431612 -9.87941)
			(xy 38.376135 -9.70867) (xy 38.313054 -9.540591) (xy 38.242495 -9.375511) (xy 38.164602 -9.213763)
			(xy 38.079529 -9.055673) (xy 37.98745 -8.901558) (xy 37.88855 -8.75173) (xy 37.783026 -8.60649) (xy 37.671093 -8.46613)
			(xy 37.552976 -8.330934) (xy 37.428911 -8.201173) (xy 37.29915 -8.077108) (xy 37.163954 -7.958991)
			(xy 37.023594 -7.847058) (xy 36.878354 -7.741534) (xy 36.728526 -7.642634) (xy 36.574411 -7.550555)
			(xy 36.416321 -7.465482) (xy 36.254573 -7.387589) (xy 36.089493 -7.31703) (xy 35.921414 -7.253949)
			(xy 35.750674 -7.198472) (xy 35.577617 -7.150711) (xy 35.402591 -7.110763) (xy 35.225949 -7.078707)
			(xy 35.048047 -7.054609) (xy 34.869243 -7.038516) (xy 34.689897 -7.030462) (xy 34.510371 -7.030462)
			(xy 34.331025 -7.038516) (xy 34.152221 -7.054609) (xy 33.974319 -7.078707) (xy 33.797677 -7.110763)
			(xy 33.622651 -7.150711) (xy 33.449594 -7.198472) (xy 33.278854 -7.253949) (xy 33.110775 -7.31703)
			(xy 32.945695 -7.387589) (xy 32.783947 -7.465482) (xy 32.625857 -7.550555) (xy 32.471742 -7.642634)
			(xy 32.321914 -7.741534) (xy 32.176674 -7.847058) (xy 32.036314 -7.958991) (xy 31.901118 -8.077108)
			(xy 31.771357 -8.201173) (xy 31.647292 -8.330934) (xy 31.529175 -8.46613) (xy 31.417242 -8.60649)
			(xy 31.311718 -8.75173) (xy 31.212818 -8.901558) (xy 31.120739 -9.055673) (xy 31.035666 -9.213763)
			(xy 30.957773 -9.375511) (xy 30.887214 -9.540591) (xy 30.824133 -9.70867) (xy 30.768656 -9.87941)
			(xy 30.720895 -10.052467) (xy 30.680947 -10.227493) (xy 30.648891 -10.404135) (xy 30.624793 -10.582037)
			(xy 30.6087 -10.760841) (xy 30.600646 -10.940187) (xy 30.600142 -11.02995)
		)
		(stroke
			(width 0)
			(type solid)
		)
		(fill yes)
		(layer "F.Cu")
		(net "GND")
	)
	(gr_poly
		(pts
			(arc
				(start 28.850082 -85.641942)
				(mid 29.905082 -85.204946)
				(end 30.342078 -84.149946)
			)
			(arc
				(start 30.342078 -82.00009)
				(mid 31.076653 -80.226669)
				(end 32.850074 -79.492094)
			)
			(arc
				(start 36.20008 -79.492094)
				(mid 37.25508 -79.055098)
				(end 37.692076 -78.000098)
			)
			(arc
				(start 37.692076 -77.94371)
				(mid 37.677197 -77.907789)
				(end 37.641276 -77.89291)
			)
			(xy 37.62756 -77.89291)
			(arc
				(start 37.615876 -77.899768)
				(mid 37.408893 -78.015895)
				(end 37.198554 -78.125828)
			)
			(arc
				(start 37.171376 -78.162658)
				(mid 36.83631 -78.751599)
				(end 36.20008 -78.984602)
			)
			(arc
				(start 32.850074 -78.984602)
				(mid 30.717802 -79.867818)
				(end 29.834586 -82.00009)
			)
			(arc
				(start 29.834586 -84.149946)
				(mid 29.554711 -84.837512)
				(end 28.874212 -85.134196)
			)
			(xy 28.8417 -85.166708) (xy 15.472156 -85.166708) (xy 15.201392 -85.166708) (xy 15.107158 -85.166708)
			(xy 15.0749 -85.13445) (xy 14.938248 -85.13445) (xy 14.93774 -85.13445)
			(arc
				(start 14.849856 -85.13445)
				(mid 14.153617 -84.846111)
				(end 13.865098 -84.149946)
			)
			(arc
				(start 13.865098 -81.999582)
				(mid 12.981867 -79.867654)
				(end 10.849864 -78.984602)
			)
			(arc
				(start 3.10007 -78.984602)
				(mid 2.403921 -78.696247)
				(end 2.115566 -78.000098)
			)
			(arc
				(start 2.115566 -74.100944)
				(mid 2.110756 -74.079367)
				(end 2.097278 -74.061828)
			)
			(arc
				(start 2.097278 -74.061828)
				(mid 1.936052 -73.924744)
				(end 1.778508 -73.783444)
			)
			(xy 1.767332 -73.77303) (xy 1.737868 -73.768204)
			(arc
				(start 1.638554 -73.811892)
				(mid 1.616422 -73.830601)
				(end 1.608074 -73.858374)
			)
			(arc
				(start 1.608074 -78.000098)
				(mid 2.04507 -79.055098)
				(end 3.10007 -79.492094)
			)
			(arc
				(start 10.849864 -79.492094)
				(mid 12.623285 -80.226669)
				(end 13.35786 -82.00009)
			)
			(arc
				(start 13.35786 -84.149946)
				(mid 13.794856 -85.204946)
				(end 14.849856 -85.641942)
			)
		)
		(stroke
			(width 0)
			(type solid)
		)
		(fill yes)
		(layer "F.Cu")
		(net "GND")
	)
	(gr_poly
		(pts
			(arc
				(start 1.026414 -69.342)
				(mid 1.018051 -69.268296)
				(end 1.015238 -69.194172)
			)
			(xy 1.015238 -21.24202) (xy 0.508 -21.24202)
			(arc
				(start 0.508 -69.194426)
				(mid 0.509855 -69.268304)
				(end 0.515366 -69.342)
			)
		)
		(stroke
			(width 0)
			(type solid)
		)
		(fill yes)
		(layer "B.Cu")
		(net "GND")
	)
	(gr_poly
		(pts
			(arc
				(start 25.325578 -16.637)
				(mid 24.966422 -16.637)
				(end 25.325578 -16.637)
			)
		)
		(stroke
			(width 0)
			(type solid)
		)
		(fill yes)
		(layer "B.Cu")
		(net "GND")
	)
	(gr_poly
		(pts
			(arc
				(start 22.584918 -6.604)
				(mid 22.604441 -6.600099)
				(end 22.620986 -6.589014)
			)
			(arc
				(start 26.401014 -2.808986)
				(mid 26.412125 -2.792452)
				(end 26.416 -2.772918)
			)
			(arc
				(start 26.416 -1.926082)
				(mid 26.412099 -1.906559)
				(end 26.401014 -1.890014)
			)
			(arc
				(start 26.049986 -1.538986)
				(mid 26.033452 -1.527875)
				(end 26.013918 -1.524)
			)
			(arc
				(start 20.341082 -1.524)
				(mid 20.321559 -1.527901)
				(end 20.305014 -1.538986)
			)
			(arc
				(start 19.953986 -1.890014)
				(mid 19.942875 -1.906548)
				(end 19.939 -1.926082)
			)
			(arc
				(start 19.939 -4.550918)
				(mid 19.942901 -4.570441)
				(end 19.953986 -4.586986)
			)
			(arc
				(start 21.956014 -6.589014)
				(mid 21.972548 -6.600125)
				(end 21.992082 -6.604)
			)
		)
		(stroke
			(width 0)
			(type solid)
		)
		(fill yes)
		(layer "B.Cu")
		(net "GND")
	)
	(gr_poly
		(pts
			(arc
				(start 37.824918 -57.023)
				(mid 37.844441 -57.019099)
				(end 37.860986 -57.008014)
			)
			(arc
				(start 37.982144 -56.886856)
				(mid 37.993255 -56.870322)
				(end 37.99713 -56.850788)
			)
			(arc
				(start 37.99713 -44.876212)
				(mid 37.993229 -44.856689)
				(end 37.982144 -44.840144)
			)
			(arc
				(start 37.733986 -44.591986)
				(mid 37.717452 -44.580875)
				(end 37.697918 -44.577)
			)
			(arc
				(start 35.559746 -44.577)
				(mid 35.540359 -44.58095)
				(end 35.523932 -44.591986)
			)
			(arc
				(start 32.40024 -47.715424)
				(mid 32.389266 -47.731987)
				(end 32.385508 -47.751492)
			)
			(xy 32.385508 -55.73141) (xy 32.385 -55.731664)
			(arc
				(start 32.385 -56.747918)
				(mid 32.388901 -56.767441)
				(end 32.399986 -56.783986)
			)
			(arc
				(start 32.624014 -57.008014)
				(mid 32.640548 -57.019125)
				(end 32.660082 -57.023)
			)
		)
		(stroke
			(width 0)
			(type solid)
		)
		(fill yes)
		(layer "B.Cu")
		(net "GND")
	)
	(gr_poly
		(pts
			(arc
				(start 38.453568 -70.140322)
				(mid 38.704709 -69.696698)
				(end 38.791896 -69.194426)
			)
			(arc
				(start 38.791896 -16.778224)
				(mid 38.783289 -16.750185)
				(end 38.760654 -16.731488)
			)
			(xy 38.746176 -16.725646) (xy 38.716204 -16.731488)
			(arc
				(start 38.29939 -17.148302)
				(mid 38.288416 -17.164865)
				(end 38.284658 -17.18437)
			)
			(xy 38.284658 -48.184054) (xy 38.284658 -53.772054)
			(arc
				(start 38.284658 -69.194172)
				(mid 38.214483 -69.559305)
				(end 38.013894 -69.872352)
			)
			(arc
				(start 37.998146 -69.888862)
				(mid 37.986098 -69.910539)
				(end 37.9857 -69.935344)
			)
			(arc
				(start 37.9857 -69.935344)
				(mid 38.008861 -70.037578)
				(end 38.029642 -70.140322)
			)
		)
		(stroke
			(width 0)
			(type solid)
		)
		(fill yes)
		(layer "B.Cu")
		(net "GND")
	)
	(gr_poly
		(pts
			(arc
				(start 1.015238 -1.999996)
				(mid 1.303667 -1.303667)
				(end 1.999996 -1.015238)
			)
			(xy 20.111974 -1.015238) (xy 27.22372 -1.015238) (xy 27.22372 -1.015492) (xy 27.223974 -1.015238)
			(arc
				(start 37.2999 -1.015238)
				(mid 37.996229 -1.303667)
				(end 38.284658 -1.999996)
			)
			(arc
				(start 38.284658 -8.317738)
				(mid 38.288559 -8.337261)
				(end 38.299644 -8.353806)
			)
			(arc
				(start 38.490398 -8.54456)
				(mid 38.506932 -8.555671)
				(end 38.526466 -8.559546)
			)
			(arc
				(start 38.741096 -8.559546)
				(mid 38.777017 -8.544667)
				(end 38.791896 -8.508746)
			)
			(arc
				(start 38.791896 -1.999996)
				(mid 38.3549 -0.944996)
				(end 37.2999 -0.508)
			)
			(arc
				(start 1.999996 -0.508)
				(mid 0.944996 -0.944996)
				(end 0.508 -1.999996)
			)
			(xy 0.508 -8.864092) (xy 1.015238 -8.864092)
		)
		(stroke
			(width 0)
			(type solid)
		)
		(fill yes)
		(layer "B.Cu")
		(net "GND")
	)
	(gr_poly
		(pts
			(xy 1.100074 -18.400014) (xy 1.100568 -18.499435) (xy 1.108473 -18.698119) (xy 1.124271 -18.896331)
			(xy 1.147937 -19.093759) (xy 1.179433 -19.29009) (xy 1.218709 -19.485013) (xy 1.265704 -19.678221)
			(xy 1.320344 -19.869408) (xy 1.38254 -20.058271) (xy 1.452197 -20.244512) (xy 1.529202 -20.427837)
			(xy 1.613435 -20.607955) (xy 1.704762 -20.784583) (xy 1.803039 -20.957439) (xy 1.908111 -21.126252)
			(xy 2.019811 -21.290754) (xy 2.137962 -21.450685) (xy 2.262379 -21.605793) (xy 2.392863 -21.755831)
			(xy 2.52921 -21.900564) (xy 2.671203 -22.039761) (xy 2.818617 -22.173203) (xy 2.97122 -22.300678)
			(xy 3.128771 -22.421987) (xy 3.29102 -22.536935) (xy 3.45771 -22.645342) (xy 3.628579 -22.747037)
			(xy 3.803355 -22.841857) (xy 3.981763 -22.929655) (xy 4.16352 -23.01029) (xy 4.34834 -23.083635)
			(xy 4.535929 -23.149575) (xy 4.725992 -23.208004) (xy 4.918227 -23.258831) (xy 5.112331 -23.301976)
			(xy 5.307997 -23.337369) (xy 5.504915 -23.364955) (xy 5.702775 -23.384691) (xy 5.901262 -23.396545)
			(xy 6.100064 -23.400499) (xy 6.298866 -23.396545) (xy 6.497353 -23.384691) (xy 6.695213 -23.364955)
			(xy 6.892131 -23.337369) (xy 7.087797 -23.301976) (xy 7.281901 -23.258831) (xy 7.474136 -23.208004)
			(xy 7.664199 -23.149575) (xy 7.851788 -23.083635) (xy 8.036608 -23.01029) (xy 8.218365 -22.929655)
			(xy 8.396773 -22.841857) (xy 8.571549 -22.747037) (xy 8.742418 -22.645342) (xy 8.909108 -22.536935)
			(xy 9.071357 -22.421987) (xy 9.228908 -22.300678) (xy 9.381511 -22.173203) (xy 9.528925 -22.039761)
			(xy 9.670918 -21.900564) (xy 9.807265 -21.755831) (xy 9.937749 -21.605793) (xy 10.062166 -21.450685)
			(xy 10.180317 -21.290754) (xy 10.292017 -21.126252) (xy 10.397089 -20.957439) (xy 10.495366 -20.784583)
			(xy 10.586693 -20.607955) (xy 10.670926 -20.427837) (xy 10.747931 -20.244512) (xy 10.817588 -20.058271)
			(xy 10.879784 -19.869408) (xy 10.934424 -19.678221) (xy 10.981419 -19.485013) (xy 11.020695 -19.29009)
			(xy 11.052191 -19.093759) (xy 11.075857 -18.896331) (xy 11.091655 -18.698119) (xy 11.09956 -18.499435)
			(xy 11.100054 -18.400014) (xy 11.100054 -14.899894) (xy 11.09956 -14.800473) (xy 11.091655 -14.601789)
			(xy 11.075857 -14.403577) (xy 11.052191 -14.206149) (xy 11.020695 -14.009818) (xy 10.981419 -13.814895)
			(xy 10.934424 -13.621687) (xy 10.879784 -13.4305) (xy 10.817588 -13.241637) (xy 10.747931 -13.055396)
			(xy 10.670926 -12.872071) (xy 10.586693 -12.691953) (xy 10.495366 -12.515325) (xy 10.397089 -12.342469)
			(xy 10.292017 -12.173656) (xy 10.180317 -12.009154) (xy 10.062166 -11.849223) (xy 9.937749 -11.694115)
			(xy 9.807265 -11.544077) (xy 9.670918 -11.399344) (xy 9.528925 -11.260147) (xy 9.381511 -11.126705)
			(xy 9.228908 -10.99923) (xy 9.071357 -10.877921) (xy 8.909108 -10.762973) (xy 8.742418 -10.654566)
			(xy 8.571549 -10.552871) (xy 8.396773 -10.458051) (xy 8.218365 -10.370253) (xy 8.036608 -10.289618)
			(xy 7.851788 -10.216273) (xy 7.664199 -10.150333) (xy 7.474136 -10.091904) (xy 7.281901 -10.041077)
			(xy 7.087797 -9.997932) (xy 6.892131 -9.962539) (xy 6.695213 -9.934953) (xy 6.497353 -9.915217) (xy 6.298866 -9.903363)
			(xy 6.100064 -9.89941) (xy 5.901262 -9.903363) (xy 5.702775 -9.915217) (xy 5.504915 -9.934953) (xy 5.307997 -9.962539)
			(xy 5.112331 -9.997932) (xy 4.918227 -10.041077) (xy 4.725992 -10.091904) (xy 4.535929 -10.150333)
			(xy 4.34834 -10.216273) (xy 4.16352 -10.289618) (xy 3.981763 -10.370253) (xy 3.803355 -10.458051)
			(xy 3.628579 -10.552871) (xy 3.45771 -10.654566) (xy 3.29102 -10.762973) (xy 3.128771 -10.877921)
			(xy 2.97122 -10.99923) (xy 2.818617 -11.126705) (xy 2.671203 -11.260147) (xy 2.52921 -11.399344)
			(xy 2.392863 -11.544077) (xy 2.262379 -11.694115) (xy 2.137962 -11.849223) (xy 2.019811 -12.009154)
			(xy 1.908111 -12.173656) (xy 1.803039 -12.342469) (xy 1.704762 -12.515325) (xy 1.613435 -12.691953)
			(xy 1.529202 -12.872071) (xy 1.452197 -13.055396) (xy 1.38254 -13.241637) (xy 1.320344 -13.4305)
			(xy 1.265704 -13.621687) (xy 1.218709 -13.814895) (xy 1.179433 -14.009818) (xy 1.147937 -14.206149)
			(xy 1.124271 -14.403577) (xy 1.108473 -14.601789) (xy 1.100568 -14.800473) (xy 1.100074 -14.899894)
			(xy 3.58242 -14.899894) (xy 3.586452 -14.757458) (xy 3.598536 -14.615479) (xy 3.618634 -14.47441)
			(xy 3.64668 -14.334704) (xy 3.682585 -14.196809) (xy 3.726234 -14.061166) (xy 3.777487 -13.92821)
			(xy 3.83618 -13.798367) (xy 3.902125 -13.672052) (xy 3.97511 -13.54967) (xy 4.054903 -13.431613)
			(xy 4.141247 -13.318259) (xy 4.233865 -13.209972) (xy 4.332461 -13.107099) (xy 4.43672 -13.009968)
			(xy 4.546307 -12.918891) (xy 4.660871 -12.83416) (xy 4.780045 -12.756046) (xy 4.903447 -12.6848)
			(xy 5.030683 -12.620649) (xy 5.161344 -12.563799) (xy 5.295012 -12.514433) (xy 5.431259 -12.472708)
			(xy 5.569648 -12.438757) (xy 5.709737 -12.412691) (xy 5.851076 -12.394592) (xy 5.993212 -12.384518)
			(xy 6.135691 -12.382502) (xy 6.278055 -12.388549) (xy 6.41985 -12.402641) (xy 6.56062 -12.424733)
			(xy 6.699914 -12.454753) (xy 6.837288 -12.492606) (xy 6.972299 -12.53817) (xy 7.104517 -12.5913)
			(xy 7.233517 -12.651824) (xy 7.358886 -12.71955) (xy 7.480223 -12.79426) (xy 7.597139 -12.875715)
			(xy 7.709259 -12.963654) (xy 7.816225 -13.057796) (xy 7.917693 -13.157838) (xy 8.013338 -13.263461)
			(xy 8.102855 -13.374325) (xy 8.185957 -13.490077) (xy 8.262376 -13.610344) (xy 8.331869 -13.734742)
			(xy 8.394213 -13.862873) (xy 8.449208 -13.994326) (xy 8.496679 -14.128679) (xy 8.536472 -14.265503)
			(xy 8.56846 -14.404359) (xy 8.592541 -14.544802) (xy 8.608639 -14.686383) (xy 8.6167 -14.828648)
			(xy 8.617204 -14.899894) (xy 8.6167 -14.97114) (xy 8.608639 -15.113405) (xy 8.592541 -15.254986)
			(xy 8.56846 -15.395429) (xy 8.536472 -15.534285) (xy 8.496679 -15.671109) (xy 8.449208 -15.805462)
			(xy 8.394213 -15.936915) (xy 8.331869 -16.065046) (xy 8.262376 -16.189444) (xy 8.185957 -16.309711)
			(xy 8.102855 -16.425463) (xy 8.013338 -16.536327) (xy 7.917693 -16.64195) (xy 7.816225 -16.741992)
			(xy 7.709259 -16.836134) (xy 7.597139 -16.924073) (xy 7.480223 -17.005528) (xy 7.358886 -17.080238)
			(xy 7.233517 -17.147964) (xy 7.104517 -17.208488) (xy 6.972299 -17.261618) (xy 6.837288 -17.307182)
			(xy 6.699914 -17.345035) (xy 6.56062 -17.375055) (xy 6.41985 -17.397147) (xy 6.278055 -17.411239)
			(xy 6.135691 -17.417286) (xy 5.993212 -17.41527) (xy 5.851076 -17.405196) (xy 5.709737 -17.387097)
			(xy 5.569648 -17.361031) (xy 5.431259 -17.32708) (xy 5.295012 -17.285355) (xy 5.161344 -17.235989)
			(xy 5.030683 -17.179139) (xy 4.903447 -17.114988) (xy 4.780045 -17.043742) (xy 4.660871 -16.965628)
			(xy 4.546307 -16.880897) (xy 4.43672 -16.78982) (xy 4.332461 -16.692689) (xy 4.233865 -16.589816)
			(xy 4.141247 -16.481529) (xy 4.054903 -16.368175) (xy 3.97511 -16.250118) (xy 3.902125 -16.127736)
			(xy 3.83618 -16.001421) (xy 3.777487 -15.871578) (xy 3.726234 -15.738622) (xy 3.682585 -15.602979)
			(xy 3.64668 -15.465084) (xy 3.618634 -15.325378) (xy 3.598536 -15.184309) (xy 3.586452 -15.04233)
			(xy 3.58242 -14.899894) (xy 1.100074 -14.899894)
		)
		(stroke
			(width 0)
			(type solid)
		)
		(fill yes)
		(layer "B.Cu")
		(net "GND")
	)
	(gr_poly
		(pts
			(xy 27.800046 -66.376042) (xy 27.80054 -66.475463) (xy 27.808445 -66.674147) (xy 27.824243 -66.872359)
			(xy 27.847909 -67.069787) (xy 27.879405 -67.266118) (xy 27.918681 -67.461041) (xy 27.965676 -67.654249)
			(xy 28.020316 -67.845436) (xy 28.082512 -68.034299) (xy 28.152169 -68.22054) (xy 28.229174 -68.403865)
			(xy 28.313407 -68.583983) (xy 28.404734 -68.760611) (xy 28.503011 -68.933467) (xy 28.608083 -69.10228)
			(xy 28.719783 -69.266782) (xy 28.837934 -69.426713) (xy 28.962351 -69.581821) (xy 29.092835 -69.731859)
			(xy 29.229182 -69.876592) (xy 29.371175 -70.015789) (xy 29.518589 -70.149231) (xy 29.671192 -70.276706)
			(xy 29.828743 -70.398015) (xy 29.990992 -70.512963) (xy 30.157682 -70.62137) (xy 30.328551 -70.723065)
			(xy 30.503327 -70.817885) (xy 30.681735 -70.905683) (xy 30.863492 -70.986318) (xy 31.048312 -71.059663)
			(xy 31.235901 -71.125603) (xy 31.425964 -71.184032) (xy 31.618199 -71.234859) (xy 31.812303 -71.278004)
			(xy 32.007969 -71.313397) (xy 32.204887 -71.340983) (xy 32.402747 -71.360719) (xy 32.601234 -71.372573)
			(xy 32.800036 -71.376527) (xy 32.998838 -71.372573) (xy 33.197325 -71.360719) (xy 33.395185 -71.340983)
			(xy 33.592103 -71.313397) (xy 33.787769 -71.278004) (xy 33.981873 -71.234859) (xy 34.174108 -71.184032)
			(xy 34.364171 -71.125603) (xy 34.55176 -71.059663) (xy 34.73658 -70.986318) (xy 34.918337 -70.905683)
			(xy 35.096745 -70.817885) (xy 35.271521 -70.723065) (xy 35.44239 -70.62137) (xy 35.60908 -70.512963)
			(xy 35.771329 -70.398015) (xy 35.92888 -70.276706) (xy 36.081483 -70.149231) (xy 36.228897 -70.015789)
			(xy 36.37089 -69.876592) (xy 36.507237 -69.731859) (xy 36.637721 -69.581821) (xy 36.762138 -69.426713)
			(xy 36.880289 -69.266782) (xy 36.991989 -69.10228) (xy 37.097061 -68.933467) (xy 37.195338 -68.760611)
			(xy 37.286665 -68.583983) (xy 37.370898 -68.403865) (xy 37.447903 -68.22054) (xy 37.51756 -68.034299)
			(xy 37.579756 -67.845436) (xy 37.634396 -67.654249) (xy 37.681391 -67.461041) (xy 37.720667 -67.266118)
			(xy 37.752163 -67.069787) (xy 37.775829 -66.872359) (xy 37.791627 -66.674147) (xy 37.799532 -66.475463)
			(xy 37.800026 -66.376042) (xy 37.800026 -62.875922) (xy 37.799532 -62.776501) (xy 37.791627 -62.577817)
			(xy 37.775829 -62.379605) (xy 37.752163 -62.182177) (xy 37.720667 -61.985846) (xy 37.681391 -61.790923)
			(xy 37.634396 -61.597715) (xy 37.579756 -61.406528) (xy 37.51756 -61.217665) (xy 37.447903 -61.031424)
			(xy 37.370898 -60.848099) (xy 37.286665 -60.667981) (xy 37.195338 -60.491353) (xy 37.097061 -60.318497)
			(xy 36.991989 -60.149684) (xy 36.880289 -59.985182) (xy 36.762138 -59.825251) (xy 36.637721 -59.670143)
			(xy 36.507237 -59.520105) (xy 36.37089 -59.375372) (xy 36.228897 -59.236175) (xy 36.081483 -59.102733)
			(xy 35.92888 -58.975258) (xy 35.771329 -58.853949) (xy 35.60908 -58.739001) (xy 35.44239 -58.630594)
			(xy 35.271521 -58.528899) (xy 35.096745 -58.434079) (xy 34.918337 -58.346281) (xy 34.73658 -58.265646)
			(xy 34.55176 -58.192301) (xy 34.364171 -58.126361) (xy 34.174108 -58.067932) (xy 33.981873 -58.017105)
			(xy 33.787769 -57.97396) (xy 33.592103 -57.938567) (xy 33.395185 -57.910981) (xy 33.197325 -57.891245)
			(xy 32.998838 -57.879391) (xy 32.800036 -57.875438) (xy 32.601234 -57.879391) (xy 32.402747 -57.891245)
			(xy 32.204887 -57.910981) (xy 32.007969 -57.938567) (xy 31.812303 -57.97396) (xy 31.618199 -58.017105)
			(xy 31.425964 -58.067932) (xy 31.235901 -58.126361) (xy 31.048312 -58.192301) (xy 30.863492 -58.265646)
			(xy 30.681735 -58.346281) (xy 30.503327 -58.434079) (xy 30.328551 -58.528899) (xy 30.157682 -58.630594)
			(xy 29.990992 -58.739001) (xy 29.828743 -58.853949) (xy 29.671192 -58.975258) (xy 29.518589 -59.102733)
			(xy 29.371175 -59.236175) (xy 29.229182 -59.375372) (xy 29.092835 -59.520105) (xy 28.962351 -59.670143)
			(xy 28.837934 -59.825251) (xy 28.719783 -59.985182) (xy 28.608083 -60.149684) (xy 28.503011 -60.318497)
			(xy 28.404734 -60.491353) (xy 28.313407 -60.667981) (xy 28.229174 -60.848099) (xy 28.152169 -61.031424)
			(xy 28.082512 -61.217665) (xy 28.020316 -61.406528) (xy 27.965676 -61.597715) (xy 27.918681 -61.790923)
			(xy 27.879405 -61.985846) (xy 27.847909 -62.182177) (xy 27.824243 -62.379605) (xy 27.808445 -62.577817)
			(xy 27.80054 -62.776501) (xy 27.800046 -62.875922) (xy 30.282392 -62.875922) (xy 30.286424 -62.733486)
			(xy 30.298508 -62.591507) (xy 30.318606 -62.450438) (xy 30.346652 -62.310732) (xy 30.382557 -62.172837)
			(xy 30.426206 -62.037194) (xy 30.477459 -61.904238) (xy 30.536152 -61.774395) (xy 30.602097 -61.64808)
			(xy 30.675082 -61.525698) (xy 30.754875 -61.407641) (xy 30.841219 -61.294287) (xy 30.933837 -61.186)
			(xy 31.032433 -61.083127) (xy 31.136692 -60.985996) (xy 31.246279 -60.894919) (xy 31.360843 -60.810188)
			(xy 31.480017 -60.732074) (xy 31.603419 -60.660828) (xy 31.730655 -60.596677) (xy 31.861316 -60.539827)
			(xy 31.994984 -60.490461) (xy 32.131231 -60.448736) (xy 32.26962 -60.414785) (xy 32.409709 -60.388719)
			(xy 32.551048 -60.37062) (xy 32.693184 -60.360546) (xy 32.835663 -60.35853) (xy 32.978027 -60.364577)
			(xy 33.119822 -60.378669) (xy 33.260592 -60.400761) (xy 33.399886 -60.430781) (xy 33.53726 -60.468634)
			(xy 33.672271 -60.514198) (xy 33.804489 -60.567328) (xy 33.933489 -60.627852) (xy 34.058858 -60.695578)
			(xy 34.180195 -60.770288) (xy 34.297111 -60.851743) (xy 34.409231 -60.939682) (xy 34.516197 -61.033824)
			(xy 34.617665 -61.133866) (xy 34.71331 -61.239489) (xy 34.802827 -61.350353) (xy 34.885929 -61.466105)
			(xy 34.962348 -61.586372) (xy 35.031841 -61.71077) (xy 35.094185 -61.838901) (xy 35.14918 -61.970354)
			(xy 35.196651 -62.104707) (xy 35.236444 -62.241531) (xy 35.268432 -62.380387) (xy 35.292513 -62.52083)
			(xy 35.308611 -62.662411) (xy 35.316672 -62.804676) (xy 35.317176 -62.875922) (xy 35.316672 -62.947168)
			(xy 35.308611 -63.089433) (xy 35.292513 -63.231014) (xy 35.268432 -63.371457) (xy 35.236444 -63.510313)
			(xy 35.196651 -63.647137) (xy 35.14918 -63.78149) (xy 35.094185 -63.912943) (xy 35.031841 -64.041074)
			(xy 34.962348 -64.165472) (xy 34.885929 -64.285739) (xy 34.802827 -64.401491) (xy 34.71331 -64.512355)
			(xy 34.617665 -64.617978) (xy 34.516197 -64.71802) (xy 34.409231 -64.812162) (xy 34.297111 -64.900101)
			(xy 34.180195 -64.981556) (xy 34.058858 -65.056266) (xy 33.933489 -65.123992) (xy 33.804489 -65.184516)
			(xy 33.672271 -65.237646) (xy 33.53726 -65.28321) (xy 33.399886 -65.321063) (xy 33.260592 -65.351083)
			(xy 33.119822 -65.373175) (xy 32.978027 -65.387267) (xy 32.835663 -65.393314) (xy 32.693184 -65.391298)
			(xy 32.551048 -65.381224) (xy 32.409709 -65.363125) (xy 32.26962 -65.337059) (xy 32.131231 -65.303108)
			(xy 31.994984 -65.261383) (xy 31.861316 -65.212017) (xy 31.730655 -65.155167) (xy 31.603419 -65.091016)
			(xy 31.480017 -65.01977) (xy 31.360843 -64.941656) (xy 31.246279 -64.856925) (xy 31.136692 -64.765848)
			(xy 31.032433 -64.668717) (xy 30.933837 -64.565844) (xy 30.841219 -64.457557) (xy 30.754875 -64.344203)
			(xy 30.675082 -64.226146) (xy 30.602097 -64.103764) (xy 30.536152 -63.977449) (xy 30.477459 -63.847606)
			(xy 30.426206 -63.71465) (xy 30.382557 -63.579007) (xy 30.346652 -63.441112) (xy 30.318606 -63.301406)
			(xy 30.298508 -63.160337) (xy 30.286424 -63.018358) (xy 30.282392 -62.875922) (xy 27.800046 -62.875922)
		)
		(stroke
			(width 0)
			(type solid)
		)
		(fill yes)
		(layer "B.Cu")
		(net "GND")
	)
	(gr_poly
		(pts
			(xy 2.599944 -74.480166) (xy 2.600261 -74.536579) (xy 3.589526 -74.536579) (xy 3.590621 -74.380827)
			(xy 3.599769 -74.225341) (xy 3.616944 -74.070535) (xy 3.642102 -73.916825) (xy 3.675174 -73.764621)
			(xy 3.716073 -73.614331) (xy 3.764689 -73.466357) (xy 3.820892 -73.321095) (xy 3.88453 -73.178934)
			(xy 3.955435 -73.040254) (xy 4.033417 -72.905425) (xy 4.118266 -72.77481) (xy 4.209756 -72.648757)
			(xy 4.25831 -72.587866) (xy 4.293252 -72.543781) (xy 4.357152 -72.451189) (xy 4.413885 -72.35404)
			(xy 4.463128 -72.252888) (xy 4.5046 -72.14831) (xy 4.538065 -72.040901) (xy 4.563332 -71.931274)
			(xy 4.580257 -71.820053) (xy 4.588744 -71.707873) (xy 4.589272 -71.651622) (xy 4.589272 -70.980046)
			(xy 4.589768 -70.916874) (xy 4.597701 -70.790779) (xy 4.613536 -70.665431) (xy 4.637211 -70.541325)
			(xy 4.668631 -70.41895) (xy 4.707674 -70.29879) (xy 4.754184 -70.181318) (xy 4.807979 -70.066998)
			(xy 4.868846 -69.956282) (xy 4.936544 -69.849606) (xy 5.010807 -69.747392) (xy 5.091342 -69.650042)
			(xy 5.177831 -69.557941) (xy 5.269932 -69.471452) (xy 5.367282 -69.390917) (xy 5.469496 -69.316654)
			(xy 5.576172 -69.248956) (xy 5.686888 -69.188089) (xy 5.801208 -69.134294) (xy 5.91868 -69.087784)
			(xy 6.03884 -69.048741) (xy 6.161215 -69.017321) (xy 6.285321 -68.993646) (xy 6.410669 -68.977811)
			(xy 6.536764 -68.969878) (xy 6.663108 -68.969878) (xy 6.789203 -68.977811) (xy 6.914551 -68.993646)
			(xy 7.038657 -69.017321) (xy 7.161032 -69.048741) (xy 7.281192 -69.087784) (xy 7.398664 -69.134294)
			(xy 7.512984 -69.188089) (xy 7.6237 -69.248956) (xy 7.730376 -69.316654) (xy 7.83259 -69.390917)
			(xy 7.92994 -69.471452) (xy 8.022041 -69.557941) (xy 8.10853 -69.650042) (xy 8.189065 -69.747392)
			(xy 8.263328 -69.849606) (xy 8.331026 -69.956282) (xy 8.391893 -70.066998) (xy 8.445688 -70.181318)
			(xy 8.492198 -70.29879) (xy 8.531241 -70.41895) (xy 8.562661 -70.541325) (xy 8.586336 -70.665431)
			(xy 8.602171 -70.790779) (xy 8.610104 -70.916874) (xy 8.6106 -70.980046) (xy 8.6106 -71.651622) (xy 8.611105 -71.707859)
			(xy 8.619605 -71.820013) (xy 8.636542 -71.931205) (xy 8.661817 -72.040803) (xy 8.695286 -72.148183)
			(xy 8.736761 -72.252732) (xy 8.786003 -72.353855) (xy 8.842732 -72.450975) (xy 8.906626 -72.54354)
			(xy 8.941562 -72.587612) (xy 8.990123 -72.648497) (xy 9.081627 -72.77454) (xy 9.16649 -72.905146)
			(xy 9.244486 -73.039966) (xy 9.315406 -73.178639) (xy 9.379061 -73.320793) (xy 9.435279 -73.466049)
			(xy 9.483911 -73.614018) (xy 9.524826 -73.764303) (xy 9.557915 -73.916504) (xy 9.583089 -74.070211)
			(xy 9.600282 -74.225015) (xy 9.609446 -74.380501) (xy 9.610558 -74.536252) (xy 9.603614 -74.691853)
			(xy 9.588634 -74.846886) (xy 9.565656 -75.000937) (xy 9.534743 -75.153594) (xy 9.495978 -75.304449)
			(xy 9.449463 -75.453097) (xy 9.395325 -75.59914) (xy 9.333706 -75.742189) (xy 9.264773 -75.88186)
			(xy 9.18871 -76.01778) (xy 9.10572 -76.149584) (xy 9.016025 -76.276921) (xy 8.919865 -76.399449)
			(xy 8.817499 -76.51684) (xy 8.709198 -76.628781) (xy 8.595254 -76.734973) (xy 8.475972 -76.835129)
			(xy 8.351669 -76.928984) (xy 8.22268 -77.016286) (xy 8.089349 -77.0968) (xy 7.952033 -77.170312)
			(xy 7.811099 -77.236625) (xy 7.666924 -77.295562) (xy 7.519895 -77.346964) (xy 7.370405 -77.390694)
			(xy 7.218853 -77.426636) (xy 7.065645 -77.454693) (xy 6.911192 -77.47479) (xy 6.755906 -77.486873)
			(xy 6.600203 -77.49091) (xy 6.444499 -77.48689) (xy 6.289212 -77.474824) (xy 6.134756 -77.454744)
			(xy 5.981545 -77.426703) (xy 5.829989 -77.390778) (xy 5.680494 -77.347064) (xy 5.533459 -77.295678)
			(xy 5.389279 -77.236757) (xy 5.248338 -77.170459) (xy 5.111013 -77.096962) (xy 4.977674 -77.016462)
			(xy 4.848675 -76.929174) (xy 4.724362 -76.835333) (xy 4.605069 -76.735189) (xy 4.491113 -76.629011)
			(xy 4.382801 -76.517081) (xy 4.280421 -76.399701) (xy 4.184248 -76.277183) (xy 4.09454 -76.149856)
			(xy 4.011535 -76.018061) (xy 3.935457 -75.882149) (xy 3.866509 -75.742486) (xy 3.804875 -75.599444)
			(xy 3.75072 -75.453406) (xy 3.70419 -75.304763) (xy 3.665408 -75.153913) (xy 3.634479 -75.00126)
			(xy 3.611484 -74.847211) (xy 3.596487 -74.692179) (xy 3.589526 -74.536579) (xy 2.600261 -74.536579)
			(xy 2.600448 -74.569929) (xy 2.608502 -74.749275) (xy 2.624595 -74.928079) (xy 2.648693 -75.105981)
			(xy 2.680749 -75.282623) (xy 2.720697 -75.457649) (xy 2.768458 -75.630706) (xy 2.823935 -75.801446)
			(xy 2.887016 -75.969525) (xy 2.957575 -76.134605) (xy 3.035468 -76.296353) (xy 3.120541 -76.454443)
			(xy 3.21262 -76.608558) (xy 3.31152 -76.758386) (xy 3.417044 -76.903626) (xy 3.528977 -77.043986)
			(xy 3.647094 -77.179182) (xy 3.771159 -77.308943) (xy 3.90092 -77.433008) (xy 4.036116 -77.551125)
			(xy 4.176476 -77.663058) (xy 4.321716 -77.768582) (xy 4.471544 -77.867482) (xy 4.625659 -77.959561)
			(xy 4.783749 -78.044634) (xy 4.945497 -78.122527) (xy 5.110577 -78.193086) (xy 5.278656 -78.256167)
			(xy 5.449396 -78.311644) (xy 5.622453 -78.359405) (xy 5.797479 -78.399353) (xy 5.974121 -78.431409)
			(xy 6.152023 -78.455507) (xy 6.330827 -78.4716) (xy 6.510173 -78.479654) (xy 6.689699 -78.479654)
			(xy 6.869045 -78.4716) (xy 7.047849 -78.455507) (xy 7.225751 -78.431409) (xy 7.402393 -78.399353)
			(xy 7.577419 -78.359405) (xy 7.750476 -78.311644) (xy 7.921216 -78.256167) (xy 8.089295 -78.193086)
			(xy 8.254375 -78.122527) (xy 8.416123 -78.044634) (xy 8.574213 -77.959561) (xy 8.728328 -77.867482)
			(xy 8.878156 -77.768582) (xy 9.023396 -77.663058) (xy 9.163756 -77.551125) (xy 9.298952 -77.433008)
			(xy 9.428713 -77.308943) (xy 9.552778 -77.179182) (xy 9.670895 -77.043986) (xy 9.782828 -76.903626)
			(xy 9.888352 -76.758386) (xy 9.987252 -76.608558) (xy 10.079331 -76.454443) (xy 10.164404 -76.296353)
			(xy 10.242297 -76.134605) (xy 10.312856 -75.969525) (xy 10.375937 -75.801446) (xy 10.431414 -75.630706)
			(xy 10.479175 -75.457649) (xy 10.519123 -75.282623) (xy 10.551179 -75.105981) (xy 10.575277 -74.928079)
			(xy 10.59137 -74.749275) (xy 10.599424 -74.569929) (xy 10.599928 -74.480166) (xy 10.599928 -70.980046)
			(xy 10.599424 -70.890283) (xy 10.59137 -70.710937) (xy 10.575277 -70.532133) (xy 10.551179 -70.354231)
			(xy 10.519123 -70.177589) (xy 10.479175 -70.002563) (xy 10.431414 -69.829506) (xy 10.375937 -69.658766)
			(xy 10.312856 -69.490687) (xy 10.242297 -69.325607) (xy 10.164404 -69.163859) (xy 10.079331 -69.005769)
			(xy 9.987252 -68.851654) (xy 9.888352 -68.701826) (xy 9.782828 -68.556586) (xy 9.670895 -68.416226)
			(xy 9.552778 -68.28103) (xy 9.428713 -68.151269) (xy 9.298952 -68.027204) (xy 9.163756 -67.909087)
			(xy 9.023396 -67.797154) (xy 8.878156 -67.69163) (xy 8.728328 -67.59273) (xy 8.574213 -67.500651)
			(xy 8.416123 -67.415578) (xy 8.254375 -67.337685) (xy 8.089295 -67.267126) (xy 7.921216 -67.204045)
			(xy 7.750476 -67.148568) (xy 7.577419 -67.100807) (xy 7.402393 -67.060859) (xy 7.225751 -67.028803)
			(xy 7.047849 -67.004705) (xy 6.869045 -66.988612) (xy 6.689699 -66.980558) (xy 6.510173 -66.980558)
			(xy 6.330827 -66.988612) (xy 6.152023 -67.004705) (xy 5.974121 -67.028803) (xy 5.797479 -67.060859)
			(xy 5.622453 -67.100807) (xy 5.449396 -67.148568) (xy 5.278656 -67.204045) (xy 5.110577 -67.267126)
			(xy 4.945497 -67.337685) (xy 4.783749 -67.415578) (xy 4.625659 -67.500651) (xy 4.471544 -67.59273)
			(xy 4.321716 -67.69163) (xy 4.176476 -67.797154) (xy 4.036116 -67.909087) (xy 3.90092 -68.027204)
			(xy 3.771159 -68.151269) (xy 3.647094 -68.28103) (xy 3.528977 -68.416226) (xy 3.417044 -68.556586)
			(xy 3.31152 -68.701826) (xy 3.21262 -68.851654) (xy 3.120541 -69.005769) (xy 3.035468 -69.163859)
			(xy 2.957575 -69.325607) (xy 2.887016 -69.490687) (xy 2.823935 -69.658766) (xy 2.768458 -69.829506)
			(xy 2.720697 -70.002563) (xy 2.680749 -70.177589) (xy 2.648693 -70.354231) (xy 2.624595 -70.532133)
			(xy 2.608502 -70.710937) (xy 2.600448 -70.890283) (xy 2.599944 -70.980046)
		)
		(stroke
			(width 0)
			(type solid)
		)
		(fill yes)
		(layer "B.Cu")
		(net "GND")
	)
	(gr_poly
		(pts
			(xy 30.600142 -14.53007) (xy 30.600459 -14.586486) (xy 31.589723 -14.586486) (xy 31.590818 -14.430735)
			(xy 31.599965 -14.275248) (xy 31.617141 -14.120442) (xy 31.642299 -13.966731) (xy 31.675371 -13.814527)
			(xy 31.71627 -13.664237) (xy 31.764886 -13.516263) (xy 31.821089 -13.371001) (xy 31.884728 -13.228839)
			(xy 31.955633 -13.090158) (xy 32.033614 -12.95533) (xy 32.118464 -12.824714) (xy 32.209954 -12.698661)
			(xy 32.258508 -12.63777) (xy 32.293443 -12.59368) (xy 32.357343 -12.501088) (xy 32.414076 -12.40394)
			(xy 32.463319 -12.302789) (xy 32.504792 -12.198211) (xy 32.538258 -12.090803) (xy 32.563526 -11.981177)
			(xy 32.580453 -11.869957) (xy 32.588941 -11.757776) (xy 32.58947 -11.701526) (xy 32.58947 -11.02995)
			(xy 32.589966 -10.966778) (xy 32.597899 -10.840683) (xy 32.613734 -10.715335) (xy 32.637409 -10.591229)
			(xy 32.668829 -10.468854) (xy 32.707872 -10.348694) (xy 32.754382 -10.231222) (xy 32.808177 -10.116902)
			(xy 32.869044 -10.006186) (xy 32.936742 -9.89951) (xy 33.011005 -9.797296) (xy 33.09154 -9.699946)
			(xy 33.178029 -9.607845) (xy 33.27013 -9.521356) (xy 33.36748 -9.440821) (xy 33.469694 -9.366558)
			(xy 33.57637 -9.29886) (xy 33.687086 -9.237993) (xy 33.801406 -9.184198) (xy 33.918878 -9.137688)
			(xy 34.039038 -9.098645) (xy 34.161413 -9.067225) (xy 34.285519 -9.04355) (xy 34.410867 -9.027715)
			(xy 34.536962 -9.019782) (xy 34.663306 -9.019782) (xy 34.789401 -9.027715) (xy 34.914749 -9.04355)
			(xy 35.038855 -9.067225) (xy 35.16123 -9.098645) (xy 35.28139 -9.137688) (xy 35.398862 -9.184198)
			(xy 35.513182 -9.237993) (xy 35.623898 -9.29886) (xy 35.730574 -9.366558) (xy 35.832788 -9.440821)
			(xy 35.930138 -9.521356) (xy 36.022239 -9.607845) (xy 36.108728 -9.699946) (xy 36.189263 -9.797296)
			(xy 36.263526 -9.89951) (xy 36.331224 -10.006186) (xy 36.392091 -10.116902) (xy 36.445886 -10.231222)
			(xy 36.492396 -10.348694) (xy 36.531439 -10.468854) (xy 36.562859 -10.591229) (xy 36.586534 -10.715335)
			(xy 36.602369 -10.840683) (xy 36.610302 -10.966778) (xy 36.610798 -11.02995) (xy 36.610798 -11.701526)
			(xy 36.611301 -11.757763) (xy 36.619802 -11.869917) (xy 36.636738 -11.981109) (xy 36.662013 -12.090707)
			(xy 36.695484 -12.198087) (xy 36.736958 -12.302636) (xy 36.7862 -12.403759) (xy 36.84293 -12.500879)
			(xy 36.906823 -12.593444) (xy 36.94176 -12.637516) (xy 36.990325 -12.698398) (xy 37.081829 -12.824441)
			(xy 37.166693 -12.955048) (xy 37.244689 -13.089868) (xy 37.315609 -13.228541) (xy 37.379264 -13.370695)
			(xy 37.435483 -13.515951) (xy 37.484115 -13.66392) (xy 37.52503 -13.814206) (xy 37.558119 -13.966406)
			(xy 37.583294 -14.120114) (xy 37.600487 -14.274918) (xy 37.609651 -14.430404) (xy 37.610763 -14.586156)
			(xy 37.60382 -14.741757) (xy 37.588839 -14.89679) (xy 37.565862 -15.050842) (xy 37.534949 -15.203499)
			(xy 37.496184 -15.354354) (xy 37.449669 -15.503002) (xy 37.395531 -15.649046) (xy 37.333912 -15.792095)
			(xy 37.264979 -15.931766) (xy 37.188916 -16.067686) (xy 37.105926 -16.199491) (xy 37.016231 -16.326828)
			(xy 36.920071 -16.449356) (xy 36.817705 -16.566748) (xy 36.709404 -16.67869) (xy 36.59546 -16.784881)
			(xy 36.476177 -16.885038) (xy 36.351875 -16.978893) (xy 36.222885 -17.066195) (xy 36.089554 -17.146709)
			(xy 35.952238 -17.220222) (xy 35.811304 -17.286535) (xy 35.667129 -17.345472) (xy 35.5201 -17.396874)
			(xy 35.370609 -17.440605) (xy 35.219057 -17.476547) (xy 35.065849 -17.504604) (xy 34.911395 -17.524701)
			(xy 34.756109 -17.536784) (xy 34.600405 -17.540821) (xy 34.444702 -17.536801) (xy 34.289414 -17.524735)
			(xy 34.134958 -17.504655) (xy 33.981747 -17.476615) (xy 33.830191 -17.44069) (xy 33.680695 -17.396975)
			(xy 33.53366 -17.345589) (xy 33.389479 -17.286668) (xy 33.248538 -17.22037) (xy 33.111213 -17.146873)
			(xy 32.977873 -17.066373) (xy 32.848874 -16.979086) (xy 32.724562 -16.885244) (xy 32.605268 -16.7851)
			(xy 32.491312 -16.678921) (xy 32.382999 -16.566992) (xy 32.28062 -16.449611) (xy 32.184447 -16.327093)
			(xy 32.094738 -16.199766) (xy 32.011733 -16.067971) (xy 31.935655 -15.932059) (xy 31.866706 -15.792395)
			(xy 31.805072 -15.649353) (xy 31.750917 -15.503315) (xy 31.704387 -15.354672) (xy 31.665605 -15.203822)
			(xy 31.634675 -15.051168) (xy 31.611681 -14.897119) (xy 31.596684 -14.742087) (xy 31.589723 -14.586486)
			(xy 30.600459 -14.586486) (xy 30.600646 -14.619833) (xy 30.6087 -14.799179) (xy 30.624793 -14.977983)
			(xy 30.648891 -15.155885) (xy 30.680947 -15.332527) (xy 30.720895 -15.507553) (xy 30.768656 -15.68061)
			(xy 30.824133 -15.85135) (xy 30.887214 -16.019429) (xy 30.957773 -16.184509) (xy 31.035666 -16.346257)
			(xy 31.120739 -16.504347) (xy 31.212818 -16.658462) (xy 31.311718 -16.80829) (xy 31.417242 -16.95353)
			(xy 31.529175 -17.09389) (xy 31.647292 -17.229086) (xy 31.771357 -17.358847) (xy 31.901118 -17.482912)
			(xy 32.036314 -17.601029) (xy 32.176674 -17.712962) (xy 32.321914 -17.818486) (xy 32.471742 -17.917386)
			(xy 32.625857 -18.009465) (xy 32.783947 -18.094538) (xy 32.945695 -18.172431) (xy 33.110775 -18.24299)
			(xy 33.278854 -18.306071) (xy 33.449594 -18.361548) (xy 33.622651 -18.409309) (xy 33.797677 -18.449257)
			(xy 33.974319 -18.481313) (xy 34.152221 -18.505411) (xy 34.331025 -18.521504) (xy 34.510371 -18.529558)
			(xy 34.689897 -18.529558) (xy 34.869243 -18.521504) (xy 35.048047 -18.505411) (xy 35.225949 -18.481313)
			(xy 35.402591 -18.449257) (xy 35.577617 -18.409309) (xy 35.750674 -18.361548) (xy 35.921414 -18.306071)
			(xy 36.089493 -18.24299) (xy 36.254573 -18.172431) (xy 36.416321 -18.094538) (xy 36.574411 -18.009465)
			(xy 36.728526 -17.917386) (xy 36.878354 -17.818486) (xy 37.023594 -17.712962) (xy 37.163954 -17.601029)
			(xy 37.29915 -17.482912) (xy 37.428911 -17.358847) (xy 37.552976 -17.229086) (xy 37.671093 -17.09389)
			(xy 37.783026 -16.95353) (xy 37.88855 -16.80829) (xy 37.98745 -16.658462) (xy 38.079529 -16.504347)
			(xy 38.164602 -16.346257) (xy 38.242495 -16.184509) (xy 38.313054 -16.019429) (xy 38.376135 -15.85135)
			(xy 38.431612 -15.68061) (xy 38.479373 -15.507553) (xy 38.519321 -15.332527) (xy 38.551377 -15.155885)
			(xy 38.575475 -14.977983) (xy 38.591568 -14.799179) (xy 38.599622 -14.619833) (xy 38.600126 -14.53007)
			(xy 38.600126 -11.02995) (xy 38.599622 -10.940187) (xy 38.591568 -10.760841) (xy 38.575475 -10.582037)
			(xy 38.551377 -10.404135) (xy 38.519321 -10.227493) (xy 38.479373 -10.052467) (xy 38.431612 -9.87941)
			(xy 38.376135 -9.70867) (xy 38.313054 -9.540591) (xy 38.242495 -9.375511) (xy 38.164602 -9.213763)
			(xy 38.079529 -9.055673) (xy 37.98745 -8.901558) (xy 37.88855 -8.75173) (xy 37.783026 -8.60649) (xy 37.671093 -8.46613)
			(xy 37.552976 -8.330934) (xy 37.428911 -8.201173) (xy 37.29915 -8.077108) (xy 37.163954 -7.958991)
			(xy 37.023594 -7.847058) (xy 36.878354 -7.741534) (xy 36.728526 -7.642634) (xy 36.574411 -7.550555)
			(xy 36.416321 -7.465482) (xy 36.254573 -7.387589) (xy 36.089493 -7.31703) (xy 35.921414 -7.253949)
			(xy 35.750674 -7.198472) (xy 35.577617 -7.150711) (xy 35.402591 -7.110763) (xy 35.225949 -7.078707)
			(xy 35.048047 -7.054609) (xy 34.869243 -7.038516) (xy 34.689897 -7.030462) (xy 34.510371 -7.030462)
			(xy 34.331025 -7.038516) (xy 34.152221 -7.054609) (xy 33.974319 -7.078707) (xy 33.797677 -7.110763)
			(xy 33.622651 -7.150711) (xy 33.449594 -7.198472) (xy 33.278854 -7.253949) (xy 33.110775 -7.31703)
			(xy 32.945695 -7.387589) (xy 32.783947 -7.465482) (xy 32.625857 -7.550555) (xy 32.471742 -7.642634)
			(xy 32.321914 -7.741534) (xy 32.176674 -7.847058) (xy 32.036314 -7.958991) (xy 31.901118 -8.077108)
			(xy 31.771357 -8.201173) (xy 31.647292 -8.330934) (xy 31.529175 -8.46613) (xy 31.417242 -8.60649)
			(xy 31.311718 -8.75173) (xy 31.212818 -8.901558) (xy 31.120739 -9.055673) (xy 31.035666 -9.213763)
			(xy 30.957773 -9.375511) (xy 30.887214 -9.540591) (xy 30.824133 -9.70867) (xy 30.768656 -9.87941)
			(xy 30.720895 -10.052467) (xy 30.680947 -10.227493) (xy 30.648891 -10.404135) (xy 30.624793 -10.582037)
			(xy 30.6087 -10.760841) (xy 30.600646 -10.940187) (xy 30.600142 -11.02995)
		)
		(stroke
			(width 0)
			(type solid)
		)
		(fill yes)
		(layer "B.Cu")
		(net "GND")
	)
	(gr_poly
		(pts
			(arc
				(start 28.850082 -85.641942)
				(mid 29.905082 -85.204946)
				(end 30.342078 -84.149946)
			)
			(arc
				(start 30.342078 -82.00009)
				(mid 31.076653 -80.226669)
				(end 32.850074 -79.492094)
			)
			(arc
				(start 36.20008 -79.492094)
				(mid 37.25508 -79.055098)
				(end 37.692076 -78.000098)
			)
			(xy 37.692076 -76.886054) (xy 37.417756 -76.886054)
			(arc
				(start 37.404548 -76.899262)
				(mid 37.30285 -77.052275)
				(end 37.194998 -77.201014)
			)
			(xy 37.189918 -77.207618) (xy 37.184838 -77.223112)
			(arc
				(start 37.184838 -78.000098)
				(mid 36.896573 -78.696158)
				(end 36.200588 -78.984602)
			)
			(xy 33.791398 -78.984602)
			(arc
				(start 33.790128 -78.984856)
				(mid 33.695025 -78.987766)
				(end 33.599882 -78.988666)
			)
			(arc
				(start 33.599882 -78.988666)
				(mid 33.504739 -78.987764)
				(end 33.409636 -78.984856)
			)
			(xy 33.408366 -78.984602)
			(arc
				(start 32.850074 -78.984602)
				(mid 30.717802 -79.867818)
				(end 29.834586 -82.00009)
			)
			(arc
				(start 29.834586 -84.149946)
				(mid 29.546231 -84.846095)
				(end 28.850082 -85.13445)
			)
			(arc
				(start 14.849856 -85.13445)
				(mid 14.153617 -84.846111)
				(end 13.865098 -84.149946)
			)
			(arc
				(start 13.865098 -81.999582)
				(mid 12.981867 -79.867654)
				(end 10.849864 -78.984602)
			)
			(arc
				(start 3.10007 -78.984602)
				(mid 2.403921 -78.696247)
				(end 2.115566 -78.000098)
			)
			(xy 2.115566 -73.969372) (xy 1.608074 -73.969372)
			(arc
				(start 1.608074 -78.000098)
				(mid 2.04507 -79.055098)
				(end 3.10007 -79.492094)
			)
			(arc
				(start 10.849864 -79.492094)
				(mid 12.623285 -80.226669)
				(end 13.35786 -82.00009)
			)
			(arc
				(start 13.35786 -84.149946)
				(mid 13.794856 -85.204946)
				(end 14.849856 -85.641942)
			)
		)
		(stroke
			(width 0)
			(type solid)
		)
		(fill yes)
		(layer "B.Cu")
		(net "GND")
	)
	(gr_poly
		(pts
			(xy 34.777426 -35.051492) (xy 34.787391 -35.051013) (xy 34.805825 -35.043435) (xy 34.81324 -35.03676)
			(xy 35.03676 -34.81324) (xy 35.043455 -34.805834) (xy 35.051058 -34.787398) (xy 35.051492 -34.777426)
			(xy 35.051492 -25.928574) (xy 35.051013 -25.918609) (xy 35.043435 -25.900175) (xy 35.03676 -25.89276)
			(xy 27.446986 -18.302986) (xy 27.440132 -18.295591) (xy 27.43239 -18.276992) (xy 27.432 -18.266918)
			(xy 27.432 -18.196052) (xy 27.430476 -18.189956) (xy 27.425691 -18.169269) (xy 27.420602 -18.127113)
			(xy 27.420316 -18.105882) (xy 27.420316 -16.519144) (xy 27.419787 -16.509153) (xy 27.412086 -16.490708)
			(xy 27.40533 -16.48333) (xy 27.351482 -16.429482) (xy 27.328622 -16.421862) (xy 27.31643 -16.423894)
			(xy 27.302102 -16.425925) (xy 27.273242 -16.428087) (xy 27.258772 -16.428212) (xy 27.233692 -16.427836)
			(xy 27.18396 -16.421294) (xy 27.13552 -16.408275) (xy 27.112214 -16.399002) (xy 27.102816 -16.395192)
			(xy 26.67889 -16.395192) (xy 26.668923 -16.395668) (xy 26.650484 -16.40324) (xy 26.643076 -16.409924)
			(xy 26.430986 -16.622014) (xy 26.424132 -16.629409) (xy 26.41639 -16.648008) (xy 26.416 -16.658082)
			(xy 26.416 -16.867378) (xy 26.422096 -16.884142) (xy 26.427684 -16.891) (xy 26.452644 -16.921875)
			(xy 26.496051 -16.988355) (xy 26.531492 -17.059402) (xy 26.558492 -17.134065) (xy 26.576691 -17.211347)
			(xy 26.585846 -17.290214) (xy 26.586434 -17.329912) (xy 26.585913 -17.368091) (xy 26.577437 -17.443976)
			(xy 26.560593 -17.518452) (xy 26.535587 -17.590599) (xy 26.502729 -17.659525) (xy 26.462424 -17.724379)
			(xy 26.415172 -17.784359) (xy 26.361554 -17.838724) (xy 26.302235 -17.886804) (xy 26.237946 -17.928003)
			(xy 26.169482 -17.961813) (xy 26.097689 -17.987816) (xy 26.023453 -18.005691) (xy 25.947692 -18.015218)
			(xy 25.909524 -18.01622) (xy 25.899618 -18.01622) (xy 25.88133 -18.024094) (xy 25.635712 -18.269712)
			(xy 24.78786 -19.117818) (xy 24.78101 -19.125215) (xy 24.773273 -19.143813) (xy 24.772874 -19.153886)
			(xy 24.772874 -19.367091) (xy 25.214321 -19.367091) (xy 25.214321 -19.292725) (xy 25.222362 -19.218794)
			(xy 25.238348 -19.146166) (xy 25.262094 -19.075693) (xy 25.293319 -19.008199) (xy 25.331659 -18.944478)
			(xy 25.376664 -18.885275) (xy 25.427806 -18.831286) (xy 25.484485 -18.783142) (xy 25.546037 -18.741408)
			(xy 25.611741 -18.706574) (xy 25.680826 -18.679048) (xy 25.752482 -18.659153) (xy 25.825869 -18.647122)
			(xy 25.900126 -18.643096) (xy 25.974383 -18.647122) (xy 26.04777 -18.659153) (xy 26.119426 -18.679048)
			(xy 26.188511 -18.706574) (xy 26.254215 -18.741408) (xy 26.315767 -18.783142) (xy 26.372446 -18.831286)
			(xy 26.423588 -18.885275) (xy 26.468593 -18.944478) (xy 26.506933 -19.008199) (xy 26.538158 -19.075693)
			(xy 26.561904 -19.146166) (xy 26.57789 -19.218794) (xy 26.585931 -19.292725) (xy 26.586434 -19.329908)
			(xy 26.585931 -19.367091) (xy 26.57789 -19.441022) (xy 26.561904 -19.51365) (xy 26.538158 -19.584123)
			(xy 26.506933 -19.651617) (xy 26.468593 -19.715338) (xy 26.423588 -19.774541) (xy 26.372446 -19.82853)
			(xy 26.315767 -19.876674) (xy 26.254215 -19.918408) (xy 26.188511 -19.953242) (xy 26.119426 -19.980768)
			(xy 26.04777 -20.000663) (xy 25.974383 -20.012694) (xy 25.900126 -20.01672) (xy 25.825869 -20.012694)
			(xy 25.752482 -20.000663) (xy 25.680826 -19.980768) (xy 25.611741 -19.953242) (xy 25.546037 -19.918408)
			(xy 25.484485 -19.876674) (xy 25.427806 -19.82853) (xy 25.376664 -19.774541) (xy 25.331659 -19.715338)
			(xy 25.293319 -19.651617) (xy 25.262094 -19.584123) (xy 25.238348 -19.51365) (xy 25.222362 -19.441022)
			(xy 25.214321 -19.367091) (xy 24.772874 -19.367091) (xy 24.772874 -19.74469) (xy 24.772452 -19.75476)
			(xy 24.764737 -19.773365) (xy 24.757888 -19.780758) (xy 24.577294 -19.961352) (xy 24.571706 -19.955764)
			(xy 23.626318 -19.955764) (xy 23.616256 -19.956204) (xy 23.597679 -19.963946) (xy 23.59025 -19.97075)
			(xy 23.387558 -20.173442) (xy 23.384851 -20.176221) (xy 23.38026 -20.182475) (xy 23.378414 -20.185888)
			(xy 23.364003 -20.212483) (xy 23.330618 -20.262929) (xy 23.292345 -20.309774) (xy 23.271226 -20.33143)
			(xy 23.255986 -20.34667) (xy 23.249141 -20.354068) (xy 23.241419 -20.372667) (xy 23.241 -20.382738)
			(xy 23.241 -21.367087) (xy 25.214321 -21.367087) (xy 25.214321 -21.292721) (xy 25.222362 -21.21879)
			(xy 25.238348 -21.146162) (xy 25.262094 -21.075689) (xy 25.293319 -21.008195) (xy 25.331659 -20.944474)
			(xy 25.376664 -20.885271) (xy 25.427806 -20.831282) (xy 25.484485 -20.783138) (xy 25.546037 -20.741404)
			(xy 25.611741 -20.70657) (xy 25.680826 -20.679044) (xy 25.752482 -20.659149) (xy 25.825869 -20.647118)
			(xy 25.900126 -20.643092) (xy 25.974383 -20.647118) (xy 26.04777 -20.659149) (xy 26.119426 -20.679044)
			(xy 26.188511 -20.70657) (xy 26.254215 -20.741404) (xy 26.315767 -20.783138) (xy 26.372446 -20.831282)
			(xy 26.423588 -20.885271) (xy 26.468593 -20.944474) (xy 26.506933 -21.008195) (xy 26.538158 -21.075689)
			(xy 26.561904 -21.146162) (xy 26.57789 -21.21879) (xy 26.585931 -21.292721) (xy 26.586434 -21.329904)
			(xy 26.585931 -21.367087) (xy 26.57789 -21.441018) (xy 26.561904 -21.513646) (xy 26.538158 -21.584119)
			(xy 26.506933 -21.651613) (xy 26.468593 -21.715334) (xy 26.423588 -21.774537) (xy 26.372446 -21.828526)
			(xy 26.315767 -21.87667) (xy 26.254215 -21.918404) (xy 26.188511 -21.953238) (xy 26.119426 -21.980764)
			(xy 26.04777 -22.000659) (xy 25.974383 -22.01269) (xy 25.900126 -22.016716) (xy 25.825869 -22.01269)
			(xy 25.752482 -22.000659) (xy 25.680826 -21.980764) (xy 25.611741 -21.953238) (xy 25.546037 -21.918404)
			(xy 25.484485 -21.87667) (xy 25.427806 -21.828526) (xy 25.376664 -21.774537) (xy 25.331659 -21.715334)
			(xy 25.293319 -21.651613) (xy 25.262094 -21.584119) (xy 25.238348 -21.513646) (xy 25.222362 -21.441018)
			(xy 25.214321 -21.367087) (xy 23.241 -21.367087) (xy 23.241 -23.34768) (xy 26.922476 -23.34768) (xy 26.922476 -22.05228)
			(xy 26.922982 -22.01236) (xy 26.931059 -21.932931) (xy 26.94713 -21.854726) (xy 26.971031 -21.778548)
			(xy 27.002516 -21.705179) (xy 27.041263 -21.635372) (xy 27.086872 -21.569843) (xy 27.138877 -21.509264)
			(xy 27.196744 -21.454257) (xy 27.259879 -21.405387) (xy 27.327634 -21.363155) (xy 27.399314 -21.327994)
			(xy 27.474184 -21.300266) (xy 27.551475 -21.280254) (xy 27.630393 -21.268164) (xy 27.71013 -21.26412)
			(xy 27.789867 -21.268164) (xy 27.868785 -21.280254) (xy 27.946076 -21.300266) (xy 28.020946 -21.327994)
			(xy 28.092626 -21.363155) (xy 28.160381 -21.405387) (xy 28.223516 -21.454257) (xy 28.281383 -21.509264)
			(xy 28.333388 -21.569843) (xy 28.378997 -21.635372) (xy 28.417744 -21.705179) (xy 28.449229 -21.778548)
			(xy 28.47313 -21.854726) (xy 28.489201 -21.932931) (xy 28.497278 -22.01236) (xy 28.497784 -22.05228)
			(xy 28.497784 -23.34768) (xy 28.497278 -23.3876) (xy 28.489201 -23.467029) (xy 28.47313 -23.545234)
			(xy 28.449229 -23.621412) (xy 28.417744 -23.694781) (xy 28.378997 -23.764588) (xy 28.333388 -23.830117)
			(xy 28.281383 -23.890696) (xy 28.223516 -23.945703) (xy 28.160381 -23.994573) (xy 28.092626 -24.036805)
			(xy 28.020946 -24.071966) (xy 27.946076 -24.099694) (xy 27.868785 -24.119706) (xy 27.789867 -24.131796)
			(xy 27.71013 -24.13584) (xy 27.630393 -24.131796) (xy 27.551475 -24.119706) (xy 27.474184 -24.099694)
			(xy 27.399314 -24.071966) (xy 27.327634 -24.036805) (xy 27.259879 -23.994573) (xy 27.196744 -23.945703)
			(xy 27.138877 -23.890696) (xy 27.086872 -23.830117) (xy 27.041263 -23.764588) (xy 27.002516 -23.694781)
			(xy 26.971031 -23.621412) (xy 26.94713 -23.545234) (xy 26.931059 -23.467029) (xy 26.922982 -23.3876)
			(xy 26.922476 -23.34768) (xy 23.241 -23.34768) (xy 23.241 -28.045918) (xy 23.241427 -28.055987) (xy 23.249146 -28.074586)
			(xy 23.255986 -28.081986) (xy 23.472902 -28.298902) (xy 23.480301 -28.305748) (xy 23.498899 -28.313481)
			(xy 23.50897 -28.313888) (xy 25.244806 -28.313888) (xy 25.254876 -28.314312) (xy 25.27348 -28.322026)
			(xy 25.280874 -28.328874) (xy 26.543 -29.591) (xy 29.589982 -29.591) (xy 29.594053 -29.535378) (xy 29.606179 -29.480941)
			(xy 29.626102 -29.42885) (xy 29.653398 -29.380215) (xy 29.687484 -29.336072) (xy 29.727633 -29.297363)
			(xy 29.772991 -29.264912) (xy 29.822591 -29.239411) (xy 29.875375 -29.221404) (xy 29.930218 -29.211274)
			(xy 29.985952 -29.209237) (xy 30.041389 -29.215337) (xy 30.095346 -29.229443) (xy 30.146675 -29.251255)
			(xy 30.194281 -29.280309) (xy 30.237149 -29.315984) (xy 30.274366 -29.357521) (xy 30.305139 -29.404034)
			(xy 30.328811 -29.454531) (xy 30.344879 -29.507938) (xy 30.352999 -29.563114) (xy 30.353508 -29.591)
			(xy 30.352999 -29.618886) (xy 30.344879 -29.674062) (xy 30.328811 -29.727469) (xy 30.305139 -29.777966)
			(xy 30.274366 -29.824479) (xy 30.237149 -29.866016) (xy 30.194281 -29.901691) (xy 30.146675 -29.930745)
			(xy 30.095346 -29.952557) (xy 30.041389 -29.966663) (xy 29.985952 -29.972763) (xy 29.930218 -29.970726)
			(xy 29.875375 -29.960596) (xy 29.822591 -29.942589) (xy 29.772991 -29.917088) (xy 29.727633 -29.884637)
			(xy 29.687484 -29.845928) (xy 29.653398 -29.801785) (xy 29.626102 -29.75315) (xy 29.606179 -29.701059)
			(xy 29.594053 -29.646622) (xy 29.589982 -29.591) (xy 26.543 -29.591) (xy 28.956 -32.004) (xy 30.224982 -32.004)
			(xy 30.229053 -31.948378) (xy 30.241179 -31.893941) (xy 30.261102 -31.84185) (xy 30.288398 -31.793215)
			(xy 30.322484 -31.749072) (xy 30.362633 -31.710363) (xy 30.407991 -31.677912) (xy 30.457591 -31.652411)
			(xy 30.510375 -31.634404) (xy 30.565218 -31.624274) (xy 30.620952 -31.622237) (xy 30.676389 -31.628337)
			(xy 30.730346 -31.642443) (xy 30.781675 -31.664255) (xy 30.829281 -31.693309) (xy 30.872149 -31.728984)
			(xy 30.909366 -31.770521) (xy 30.940139 -31.817034) (xy 30.963811 -31.867531) (xy 30.979879 -31.920938)
			(xy 30.987999 -31.976114) (xy 30.988508 -32.004) (xy 30.987999 -32.031886) (xy 30.979879 -32.087062)
			(xy 30.963811 -32.140469) (xy 30.940139 -32.190966) (xy 30.909366 -32.237479) (xy 30.872149 -32.279016)
			(xy 30.829281 -32.314691) (xy 30.781675 -32.343745) (xy 30.730346 -32.365557) (xy 30.676389 -32.379663)
			(xy 30.620952 -32.385763) (xy 30.565218 -32.383726) (xy 30.510375 -32.373596) (xy 30.457591 -32.355589)
			(xy 30.407991 -32.330088) (xy 30.362633 -32.297637) (xy 30.322484 -32.258928) (xy 30.288398 -32.214785)
			(xy 30.261102 -32.16615) (xy 30.241179 -32.114059) (xy 30.229053 -32.059622) (xy 30.224982 -32.004)
			(xy 28.956 -32.004) (xy 29.845 -32.893) (xy 30.224982 -32.893) (xy 30.229053 -32.837378) (xy 30.241179 -32.782941)
			(xy 30.261102 -32.73085) (xy 30.288398 -32.682215) (xy 30.322484 -32.638072) (xy 30.362633 -32.599363)
			(xy 30.407991 -32.566912) (xy 30.457591 -32.541411) (xy 30.510375 -32.523404) (xy 30.565218 -32.513274)
			(xy 30.620952 -32.511237) (xy 30.676389 -32.517337) (xy 30.730346 -32.531443) (xy 30.781675 -32.553255)
			(xy 30.829281 -32.582309) (xy 30.872149 -32.617984) (xy 30.909366 -32.659521) (xy 30.940139 -32.706034)
			(xy 30.963811 -32.756531) (xy 30.979879 -32.809938) (xy 30.987999 -32.865114) (xy 30.988508 -32.893)
			(xy 30.987999 -32.920886) (xy 30.979879 -32.976062) (xy 30.963811 -33.029469) (xy 30.940139 -33.079966)
			(xy 30.909366 -33.126479) (xy 30.872149 -33.168016) (xy 30.829281 -33.203691) (xy 30.781675 -33.232745)
			(xy 30.730346 -33.254557) (xy 30.676389 -33.268663) (xy 30.620952 -33.274763) (xy 30.565218 -33.272726)
			(xy 30.510375 -33.262596) (xy 30.457591 -33.244589) (xy 30.407991 -33.219088) (xy 30.362633 -33.186637)
			(xy 30.322484 -33.147928) (xy 30.288398 -33.103785) (xy 30.261102 -33.05515) (xy 30.241179 -33.003059)
			(xy 30.229053 -32.948622) (xy 30.224982 -32.893) (xy 29.845 -32.893) (xy 30.393132 -33.441132) (xy 30.424882 -33.446466)
			(xy 30.439614 -33.4391) (xy 30.465821 -33.426929) (xy 30.520986 -33.40974) (xy 30.578109 -33.401046)
			(xy 30.607 -33.400492) (xy 30.634251 -33.400978) (xy 30.688199 -33.408734) (xy 30.740494 -33.424089)
			(xy 30.790071 -33.446731) (xy 30.835921 -33.476197) (xy 30.877112 -33.511888) (xy 30.912803 -33.553079)
			(xy 30.942269 -33.598929) (xy 30.964911 -33.648506) (xy 30.980266 -33.700801) (xy 30.988022 -33.754749)
			(xy 30.988508 -33.782) (xy 30.987941 -33.812087) (xy 30.97849 -33.871515) (xy 30.959821 -33.928721)
			(xy 30.9324 -33.982285) (xy 30.896905 -34.030877) (xy 30.875986 -34.05251) (xy 30.869132 -34.059905)
			(xy 30.861387 -34.078504) (xy 30.861 -34.088578) (xy 30.861 -34.364422) (xy 30.861427 -34.37449)
			(xy 30.869147 -34.393089) (xy 30.875986 -34.40049) (xy 30.896923 -34.422106) (xy 30.932406 -34.470708)
			(xy 30.959822 -34.524276) (xy 30.978492 -34.581484) (xy 30.987951 -34.640912) (xy 30.988508 -34.671)
			(xy 30.988103 -34.696479) (xy 30.981352 -34.746986) (xy 30.967931 -34.796144) (xy 30.948079 -34.843074)
			(xy 30.92215 -34.886941) (xy 30.90672 -34.90722) (xy 30.894528 -34.92246) (xy 30.896814 -34.960814)
			(xy 30.97276 -35.03676) (xy 30.980166 -35.043455) (xy 30.998602 -35.051058) (xy 31.008574 -35.051492)
		)
		(stroke
			(width 0)
			(type solid)
		)
		(fill yes)
		(layer "B.Cu")
		(net "P5V_STBY_DEBUG")
	)
	(gr_poly
		(pts
			(xy 24.568912 -74.041) (xy 24.578981 -74.040575) (xy 24.597582 -74.032857) (xy 24.60498 -74.026014)
			(xy 24.877014 -73.75398) (xy 24.883867 -73.746585) (xy 24.891607 -73.727986) (xy 24.892 -73.717912)
			(xy 24.892 -71.395082) (xy 24.891573 -71.385013) (xy 24.883854 -71.366414) (xy 24.877014 -71.359014)
			(xy 23.128986 -69.610986) (xy 23.122132 -69.603591) (xy 23.11439 -69.584992) (xy 23.114 -69.574918)
			(xy 23.114 -67.585082) (xy 23.114427 -67.575013) (xy 23.122146 -67.556414) (xy 23.128986 -67.549014)
			(xy 24.877014 -65.800986) (xy 24.883868 -65.793591) (xy 24.89161 -65.774992) (xy 24.892 -65.764918)
			(xy 24.892 -44.344082) (xy 24.892427 -44.334013) (xy 24.900146 -44.315414) (xy 24.906986 -44.308014)
			(xy 29.576014 -39.638986) (xy 29.582868 -39.631591) (xy 29.59061 -39.612992) (xy 29.591 -39.602918)
			(xy 29.591 -36.978082) (xy 29.590573 -36.968013) (xy 29.582854 -36.949414) (xy 29.576014 -36.942014)
			(xy 29.351986 -36.717986) (xy 29.344591 -36.711132) (xy 29.325992 -36.70339) (xy 29.315918 -36.703)
			(xy 21.103082 -36.703) (xy 21.093013 -36.702573) (xy 21.074414 -36.694854) (xy 21.067014 -36.688014)
			(xy 20.276566 -35.897566) (xy 20.269169 -35.890718) (xy 20.25057 -35.882985) (xy 20.240498 -35.88258)
			(xy 14.440662 -35.88258) (xy 14.430595 -35.882149) (xy 14.412003 -35.874423) (xy 14.404594 -35.867594)
			(xy 12.943078 -34.406078) (xy 12.936227 -34.398682) (xy 12.928488 -34.380083) (xy 12.928092 -34.37001)
			(xy 12.928092 -32.645858) (xy 12.928522 -32.635791) (xy 12.936247 -32.617197) (xy 12.943078 -32.60979)
			(xy 14.360144 -31.192724) (xy 14.366985 -31.185324) (xy 14.3747 -31.166725) (xy 14.37513 -31.156656)
			(xy 14.37513 -23.697946) (xy 14.375564 -23.687881) (xy 14.383295 -23.669293) (xy 14.390116 -23.661878)
			(xy 15.295626 -22.756368) (xy 15.302475 -22.748971) (xy 15.31021 -22.730372) (xy 15.310612 -22.7203)
			(xy 15.310612 -14.520926) (xy 15.310044 -14.50982) (xy 15.300688 -14.489673) (xy 15.292578 -14.482064)
			(xy 15.224252 -14.42466) (xy 15.202916 -14.418818) (xy 15.191486 -14.42085) (xy 15.172022 -14.42405)
			(xy 15.132724 -14.427481) (xy 15.113 -14.427708) (xy 15.083032 -14.427218) (xy 15.02361 -14.419395)
			(xy 14.965717 -14.403882) (xy 14.910344 -14.380946) (xy 14.858438 -14.350979) (xy 14.810888 -14.314492)
			(xy 14.768508 -14.272112) (xy 14.732021 -14.224562) (xy 14.702054 -14.172656) (xy 14.679118 -14.117283)
			(xy 14.663605 -14.05939) (xy 14.655782 -13.999968) (xy 14.655782 -13.940032) (xy 14.663605 -13.88061)
			(xy 14.679118 -13.822717) (xy 14.702054 -13.767344) (xy 14.732021 -13.715438) (xy 14.768508 -13.667888)
			(xy 14.810888 -13.625508) (xy 14.858438 -13.589021) (xy 14.910344 -13.559054) (xy 14.965717 -13.536118)
			(xy 15.02361 -13.520605) (xy 15.083032 -13.512782) (xy 15.113 -13.512292) (xy 15.141962 -13.512738)
			(xy 15.199423 -13.520053) (xy 15.2555 -13.534565) (xy 15.309296 -13.556043) (xy 15.359949 -13.584142)
			(xy 15.406648 -13.618413) (xy 15.448645 -13.658306) (xy 15.46733 -13.68044) (xy 15.474188 -13.688568)
			(xy 15.49273 -13.69822) (xy 15.587726 -13.704824) (xy 15.607538 -13.697712) (xy 15.615158 -13.6906)
			(xy 15.636455 -13.671509) (xy 15.683691 -13.639265) (xy 15.735208 -13.614426) (xy 15.789853 -13.597546)
			(xy 15.846404 -13.589003) (xy 15.875 -13.588492) (xy 15.903895 -13.588998) (xy 15.961029 -13.597674)
			(xy 16.016194 -13.614888) (xy 16.042386 -13.6271) (xy 16.057118 -13.634466) (xy 16.088868 -13.629132)
			(xy 17.007078 -12.710922) (xy 17.01448 -12.704085) (xy 17.033078 -12.696376) (xy 17.043146 -12.695936)
			(xy 18.8214 -12.695936) (xy 18.831469 -12.695511) (xy 18.850067 -12.68779) (xy 18.857468 -12.68095)
			(xy 19.3167 -12.221718) (xy 19.323387 -12.214309) (xy 19.330976 -12.195873) (xy 19.331432 -12.185904)
			(xy 19.331432 -7.922514) (xy 19.330943 -7.912553) (xy 19.323354 -7.89413) (xy 19.3167 -7.8867) (xy 18.778728 -7.348728)
			(xy 18.77189 -7.341327) (xy 18.764177 -7.322728) (xy 18.763742 -7.31266) (xy 18.763742 -1.900174)
			(xy 18.763313 -1.890107) (xy 18.755585 -1.871515) (xy 18.748756 -1.864106) (xy 18.265902 -1.381252)
			(xy 18.258506 -1.3744) (xy 18.239908 -1.366656) (xy 18.229834 -1.366266) (xy 3.397504 -1.366266)
			(xy 3.392932 -1.370584) (xy 1.950466 -1.370584) (xy 1.940398 -1.371013) (xy 1.921801 -1.378734) (xy 1.914398 -1.38557)
			(xy 1.615186 -1.684782) (xy 1.608343 -1.692181) (xy 1.600625 -1.71078) (xy 1.6002 -1.72085) (xy 1.6002 -5.65277)
			(xy 1.600636 -5.662835) (xy 1.608368 -5.68142) (xy 1.615186 -5.688838) (xy 1.679194 -5.752846) (xy 1.68659 -5.759699)
			(xy 1.705188 -5.767444) (xy 1.715262 -5.767832) (xy 3.982974 -5.767832) (xy 3.993025 -5.767328) (xy 4.011588 -5.759608)
			(xy 4.019042 -5.752846) (xy 4.37134 -5.400548) (xy 4.378185 -5.39315) (xy 4.38591 -5.374551) (xy 4.386326 -5.36448)
			(xy 4.386326 -4.14147) (xy 4.386755 -4.131403) (xy 4.39448 -4.112809) (xy 4.401312 -4.105402) (xy 4.595368 -3.911346)
			(xy 4.602768 -3.904505) (xy 4.621367 -3.896788) (xy 4.631436 -3.89636) (xy 5.643372 -3.89636) (xy 5.653435 -3.896798)
			(xy 5.672015 -3.904537) (xy 5.67944 -3.911346) (xy 6.005322 -4.237228) (xy 6.012173 -4.244624) (xy 6.019909 -4.263223)
			(xy 6.020308 -4.273296) (xy 6.020308 -5.045456) (xy 6.020797 -5.055456) (xy 6.028424 -5.073946) (xy 6.04251 -5.088145)
			(xy 6.05155 -5.092446) (xy 6.163119 -5.13867) (xy 10.423395 -5.13867) (xy 10.423395 -5.061462) (xy 10.431465 -4.984678)
			(xy 10.447518 -4.909157) (xy 10.471376 -4.835729) (xy 10.502779 -4.765196) (xy 10.541383 -4.698333)
			(xy 10.586764 -4.63587) (xy 10.638426 -4.578494) (xy 10.695802 -4.526832) (xy 10.758265 -4.481451)
			(xy 10.825128 -4.442847) (xy 10.895661 -4.411444) (xy 10.969089 -4.387586) (xy 11.04461 -4.371533)
			(xy 11.121394 -4.363463) (xy 11.198602 -4.363463) (xy 11.275386 -4.371533) (xy 11.350907 -4.387586)
			(xy 11.424335 -4.411444) (xy 11.494868 -4.442847) (xy 11.561731 -4.481451) (xy 11.624194 -4.526832)
			(xy 11.68157 -4.578494) (xy 11.733232 -4.63587) (xy 11.778613 -4.698333) (xy 11.817217 -4.765196)
			(xy 11.84862 -4.835729) (xy 11.872478 -4.909157) (xy 11.888531 -4.984678) (xy 11.896601 -5.061462)
			(xy 11.897106 -5.100066) (xy 11.896601 -5.13867) (xy 11.888531 -5.215454) (xy 11.872478 -5.290975)
			(xy 11.84862 -5.364403) (xy 11.817217 -5.434936) (xy 11.778613 -5.501799) (xy 11.733232 -5.564262)
			(xy 11.68157 -5.621638) (xy 11.624194 -5.6733) (xy 11.561731 -5.718681) (xy 11.494868 -5.757285)
			(xy 11.424335 -5.788688) (xy 11.350907 -5.812546) (xy 11.275386 -5.828599) (xy 11.198602 -5.836669)
			(xy 11.121394 -5.836669) (xy 11.04461 -5.828599) (xy 10.969089 -5.812546) (xy 10.895661 -5.788688)
			(xy 10.825128 -5.757285) (xy 10.758265 -5.718681) (xy 10.695802 -5.6733) (xy 10.638426 -5.621638)
			(xy 10.586764 -5.564262) (xy 10.541383 -5.501799) (xy 10.502779 -5.434936) (xy 10.471376 -5.364403)
			(xy 10.447518 -5.290975) (xy 10.431465 -5.215454) (xy 10.423395 -5.13867) (xy 6.163119 -5.13867)
			(xy 7.290562 -5.60578) (xy 7.295189 -5.607556) (xy 7.304911 -5.609482) (xy 7.309866 -5.60959) (xy 9.213342 -5.60959)
			(xy 9.223409 -5.61002) (xy 9.242003 -5.617744) (xy 9.24941 -5.624576) (xy 10.30478 -6.679946) (xy 13.786106 -6.679946)
			(xy 13.79015 -6.598916) (xy 13.802242 -6.518692) (xy 13.822261 -6.44007) (xy 13.85001 -6.363832)
			(xy 13.885211 -6.290736) (xy 13.927515 -6.221508) (xy 13.976502 -6.156836) (xy 14.031685 -6.097364)
			(xy 14.092515 -6.043681) (xy 14.158388 -5.996321) (xy 14.228649 -5.955756) (xy 14.3026 -5.922388)
			(xy 14.379506 -5.896549) (xy 14.458603 -5.878496) (xy 14.539104 -5.868408) (xy 14.620209 -5.866385)
			(xy 14.701113 -5.872448) (xy 14.781011 -5.886536) (xy 14.859109 -5.908509) (xy 14.934631 -5.93815)
			(xy 15.006827 -5.975162) (xy 15.074979 -6.019179) (xy 15.138409 -6.069764) (xy 15.196488 -6.126412)
			(xy 15.248638 -6.188562) (xy 15.29434 -6.255595) (xy 15.333141 -6.326845) (xy 15.364655 -6.401605)
			(xy 15.388569 -6.479131) (xy 15.404644 -6.558653) (xy 15.412722 -6.639381) (xy 15.413228 -6.679946)
			(xy 16.326106 -6.679946) (xy 16.33015 -6.598916) (xy 16.342242 -6.518692) (xy 16.362261 -6.44007)
			(xy 16.39001 -6.363832) (xy 16.425211 -6.290736) (xy 16.467515 -6.221508) (xy 16.516502 -6.156836)
			(xy 16.571685 -6.097364) (xy 16.632515 -6.043681) (xy 16.698388 -5.996321) (xy 16.768649 -5.955756)
			(xy 16.8426 -5.922388) (xy 16.919506 -5.896549) (xy 16.998603 -5.878496) (xy 17.079104 -5.868408)
			(xy 17.160209 -5.866385) (xy 17.241113 -5.872448) (xy 17.321011 -5.886536) (xy 17.399109 -5.908509)
			(xy 17.474631 -5.93815) (xy 17.546827 -5.975162) (xy 17.614979 -6.019179) (xy 17.678409 -6.069764)
			(xy 17.736488 -6.126412) (xy 17.788638 -6.188562) (xy 17.83434 -6.255595) (xy 17.873141 -6.326845)
			(xy 17.904655 -6.401605) (xy 17.928569 -6.479131) (xy 17.944644 -6.558653) (xy 17.952722 -6.639381)
			(xy 17.953228 -6.679946) (xy 17.952722 -6.720511) (xy 17.944644 -6.801239) (xy 17.928569 -6.880761)
			(xy 17.904655 -6.958287) (xy 17.873141 -7.033047) (xy 17.83434 -7.104297) (xy 17.788638 -7.17133)
			(xy 17.736488 -7.23348) (xy 17.678409 -7.290128) (xy 17.614979 -7.340713) (xy 17.546827 -7.38473)
			(xy 17.474631 -7.421742) (xy 17.399109 -7.451383) (xy 17.321011 -7.473356) (xy 17.241113 -7.487444)
			(xy 17.160209 -7.493507) (xy 17.079104 -7.491484) (xy 16.998603 -7.481396) (xy 16.919506 -7.463343)
			(xy 16.8426 -7.437504) (xy 16.768649 -7.404136) (xy 16.698388 -7.363571) (xy 16.632515 -7.316211)
			(xy 16.571685 -7.262528) (xy 16.516502 -7.203056) (xy 16.467515 -7.138384) (xy 16.425211 -7.069156)
			(xy 16.39001 -6.99606) (xy 16.362261 -6.919822) (xy 16.342242 -6.8412) (xy 16.33015 -6.760976) (xy 16.326106 -6.679946)
			(xy 15.413228 -6.679946) (xy 15.412722 -6.720511) (xy 15.404644 -6.801239) (xy 15.388569 -6.880761)
			(xy 15.364655 -6.958287) (xy 15.333141 -7.033047) (xy 15.29434 -7.104297) (xy 15.248638 -7.17133)
			(xy 15.196488 -7.23348) (xy 15.138409 -7.290128) (xy 15.074979 -7.340713) (xy 15.006827 -7.38473)
			(xy 14.934631 -7.421742) (xy 14.859109 -7.451383) (xy 14.781011 -7.473356) (xy 14.701113 -7.487444)
			(xy 14.620209 -7.493507) (xy 14.539104 -7.491484) (xy 14.458603 -7.481396) (xy 14.379506 -7.463343)
			(xy 14.3026 -7.437504) (xy 14.228649 -7.404136) (xy 14.158388 -7.363571) (xy 14.092515 -7.316211)
			(xy 14.031685 -7.262528) (xy 13.976502 -7.203056) (xy 13.927515 -7.138384) (xy 13.885211 -7.069156)
			(xy 13.85001 -6.99606) (xy 13.822261 -6.919822) (xy 13.802242 -6.8412) (xy 13.79015 -6.760976) (xy 13.786106 -6.679946)
			(xy 10.30478 -6.679946) (xy 10.602976 -6.978142) (xy 10.612374 -6.981952) (xy 10.633258 -6.991025)
			(xy 10.672674 -7.013821) (xy 10.708781 -7.041562) (xy 10.72515 -7.05739) (xy 12.05738 -8.38962) (xy 12.073214 -8.405982)
			(xy 12.10094 -8.4421) (xy 12.12373 -8.481519) (xy 12.132818 -8.502396) (xy 12.136628 -8.511794) (xy 12.314174 -8.68934)
			(xy 12.321017 -8.696739) (xy 12.328741 -8.715338) (xy 12.32916 -8.725408) (xy 12.32916 -10.189968)
			(xy 14.677626 -10.189968) (xy 14.677626 -10.130032) (xy 14.685449 -10.07061) (xy 14.700962 -10.012717)
			(xy 14.723898 -9.957344) (xy 14.753865 -9.905438) (xy 14.790352 -9.857888) (xy 14.832732 -9.815508)
			(xy 14.880282 -9.779021) (xy 14.932188 -9.749054) (xy 14.987561 -9.726118) (xy 15.045454 -9.710605)
			(xy 15.104876 -9.702782) (xy 15.164812 -9.702782) (xy 15.224234 -9.710605) (xy 15.282127 -9.726118)
			(xy 15.3375 -9.749054) (xy 15.389406 -9.779021) (xy 15.436956 -9.815508) (xy 15.479336 -9.857888)
			(xy 15.515823 -9.905438) (xy 15.54579 -9.957344) (xy 15.568726 -10.012717) (xy 15.584239 -10.07061)
			(xy 15.592062 -10.130032) (xy 15.592552 -10.16) (xy 15.592062 -10.189968) (xy 15.584239 -10.24939)
			(xy 15.568726 -10.307283) (xy 15.54579 -10.362656) (xy 15.515823 -10.414562) (xy 15.479336 -10.462112)
			(xy 15.436956 -10.504492) (xy 15.389406 -10.540979) (xy 15.3375 -10.570946) (xy 15.282127 -10.593882)
			(xy 15.224234 -10.609395) (xy 15.164812 -10.617218) (xy 15.104876 -10.617218) (xy 15.045454 -10.609395)
			(xy 14.987561 -10.593882) (xy 14.932188 -10.570946) (xy 14.880282 -10.540979) (xy 14.832732 -10.504492)
			(xy 14.790352 -10.462112) (xy 14.753865 -10.414562) (xy 14.723898 -10.362656) (xy 14.700962 -10.307283)
			(xy 14.685449 -10.24939) (xy 14.677626 -10.189968) (xy 12.32916 -10.189968) (xy 12.32916 -21.050758)
			(xy 12.328725 -21.060823) (xy 12.320991 -21.079408) (xy 12.314174 -21.086826) (xy 10.638032 -22.762968)
			(xy 11.973796 -22.762968) (xy 11.973796 -22.703032) (xy 11.981619 -22.64361) (xy 11.997132 -22.585717)
			(xy 12.020068 -22.530344) (xy 12.050035 -22.478438) (xy 12.086522 -22.430888) (xy 12.128902 -22.388508)
			(xy 12.176452 -22.352021) (xy 12.228358 -22.322054) (xy 12.283731 -22.299118) (xy 12.341624 -22.283605)
			(xy 12.401046 -22.275782) (xy 12.460982 -22.275782) (xy 12.520404 -22.283605) (xy 12.578297 -22.299118)
			(xy 12.63367 -22.322054) (xy 12.685576 -22.352021) (xy 12.733126 -22.388508) (xy 12.775506 -22.430888)
			(xy 12.811993 -22.478438) (xy 12.84196 -22.530344) (xy 12.864896 -22.585717) (xy 12.880409 -22.64361)
			(xy 12.888232 -22.703032) (xy 12.888722 -22.733) (xy 12.888232 -22.762968) (xy 12.880409 -22.82239)
			(xy 12.864896 -22.880283) (xy 12.84196 -22.935656) (xy 12.811993 -22.987562) (xy 12.775506 -23.035112)
			(xy 12.733126 -23.077492) (xy 12.685576 -23.113979) (xy 12.63367 -23.143946) (xy 12.578297 -23.166882)
			(xy 12.520404 -23.182395) (xy 12.460982 -23.190218) (xy 12.401046 -23.190218) (xy 12.341624 -23.182395)
			(xy 12.283731 -23.166882) (xy 12.228358 -23.143946) (xy 12.176452 -23.113979) (xy 12.128902 -23.077492)
			(xy 12.086522 -23.035112) (xy 12.050035 -22.987562) (xy 12.020068 -22.935656) (xy 11.997132 -22.880283)
			(xy 11.981619 -22.82239) (xy 11.973796 -22.762968) (xy 10.638032 -22.762968) (xy 9.539986 -23.861014)
			(xy 9.532591 -23.867868) (xy 9.513992 -23.87561) (xy 9.503918 -23.876) (xy 6.698742 -23.876) (xy 6.696202 -23.876254)
			(xy 6.60422 -23.885891) (xy 6.419771 -23.899749) (xy 6.234961 -23.907405) (xy 6.142482 -23.908512)
			(xy 6.142228 -23.908512) (xy 6.084062 -23.908766) (xy 6.073648 -23.90902) (xy 6.055614 -23.916386)
			(xy 5.39496 -24.57704) (xy 5.388113 -24.584438) (xy 5.380384 -24.603037) (xy 5.379974 -24.613108)
			(xy 5.379974 -26.064968) (xy 13.273768 -26.064968) (xy 13.273768 -26.005032) (xy 13.281591 -25.94561)
			(xy 13.297104 -25.887717) (xy 13.32004 -25.832344) (xy 13.350007 -25.780438) (xy 13.386494 -25.732888)
			(xy 13.428874 -25.690508) (xy 13.476424 -25.654021) (xy 13.52833 -25.624054) (xy 13.583703 -25.601118)
			(xy 13.641596 -25.585605) (xy 13.701018 -25.577782) (xy 13.760954 -25.577782) (xy 13.820376 -25.585605)
			(xy 13.878269 -25.601118) (xy 13.933642 -25.624054) (xy 13.985548 -25.654021) (xy 14.033098 -25.690508)
			(xy 14.075478 -25.732888) (xy 14.111965 -25.780438) (xy 14.141932 -25.832344) (xy 14.164868 -25.887717)
			(xy 14.180381 -25.94561) (xy 14.188204 -26.005032) (xy 14.188694 -26.035) (xy 14.188204 -26.064968)
			(xy 14.180381 -26.12439) (xy 14.164868 -26.182283) (xy 14.141932 -26.237656) (xy 14.111965 -26.289562)
			(xy 14.075478 -26.337112) (xy 14.033098 -26.379492) (xy 13.985548 -26.415979) (xy 13.933642 -26.445946)
			(xy 13.878269 -26.468882) (xy 13.820376 -26.484395) (xy 13.760954 -26.492218) (xy 13.701018 -26.492218)
			(xy 13.641596 -26.484395) (xy 13.583703 -26.468882) (xy 13.52833 -26.445946) (xy 13.476424 -26.415979)
			(xy 13.428874 -26.379492) (xy 13.386494 -26.337112) (xy 13.350007 -26.289562) (xy 13.32004 -26.237656)
			(xy 13.297104 -26.182283) (xy 13.281591 -26.12439) (xy 13.273768 -26.064968) (xy 5.379974 -26.064968)
			(xy 5.379974 -40.410892) (xy 5.380395 -40.420963) (xy 5.388104 -40.439572) (xy 5.39496 -40.44696)
			(xy 9.383014 -44.435014) (xy 9.390409 -44.441868) (xy 9.409008 -44.44961) (xy 9.419082 -44.45) (xy 18.362422 -44.45)
			(xy 18.37249 -44.450427) (xy 18.391089 -44.458147) (xy 18.39849 -44.464986) (xy 21.448014 -47.51451)
			(xy 21.454868 -47.521905) (xy 21.462613 -47.540504) (xy 21.463 -47.550578) (xy 21.463 -60.049918)
			(xy 21.462573 -60.059987) (xy 21.454854 -60.078586) (xy 21.448014 -60.085986) (xy 20.017486 -61.516514)
			(xy 20.010632 -61.523909) (xy 20.00289 -61.542508) (xy 20.0025 -61.552582) (xy 20.0025 -65.447418)
			(xy 20.002073 -65.457487) (xy 19.994354 -65.476086) (xy 19.987514 -65.483486) (xy 19.71294 -65.75806)
			(xy 19.710654 -65.760854) (xy 19.694048 -65.782203) (xy 19.655803 -65.820448) (xy 19.634454 -65.837054)
			(xy 19.63166 -65.83934) (xy 19.318986 -66.152014) (xy 19.311591 -66.158868) (xy 19.292992 -66.16661)
			(xy 19.282918 -66.167) (xy 17.547082 -66.167) (xy 17.537013 -66.166573) (xy 17.518414 -66.158854)
			(xy 17.511014 -66.152014) (xy 17.286986 -65.927986) (xy 17.280132 -65.920591) (xy 17.27239 -65.901992)
			(xy 17.272 -65.891918) (xy 17.272 -65.426082) (xy 17.271573 -65.416013) (xy 17.263854 -65.397414)
			(xy 17.257014 -65.390014) (xy 17.032986 -65.165986) (xy 17.025591 -65.159132) (xy 17.006992 -65.15139)
			(xy 16.996918 -65.151) (xy 15.642082 -65.151) (xy 15.632013 -65.151427) (xy 15.613414 -65.159146)
			(xy 15.606014 -65.165986) (xy 15.381986 -65.390014) (xy 15.375132 -65.397409) (xy 15.36739 -65.416008)
			(xy 15.367 -65.426082) (xy 15.367 -67.0306) (xy 18.845782 -67.0306) (xy 18.849853 -66.974978) (xy 18.861979 -66.920541)
			(xy 18.881902 -66.86845) (xy 18.909198 -66.819815) (xy 18.943284 -66.775672) (xy 18.983433 -66.736963)
			(xy 19.028791 -66.704512) (xy 19.078391 -66.679011) (xy 19.131175 -66.661004) (xy 19.186018 -66.650874)
			(xy 19.241752 -66.648837) (xy 19.297189 -66.654937) (xy 19.351146 -66.669043) (xy 19.402475 -66.690855)
			(xy 19.450081 -66.719909) (xy 19.492949 -66.755584) (xy 19.530166 -66.797121) (xy 19.560939 -66.843634)
			(xy 19.584611 -66.894131) (xy 19.600679 -66.947538) (xy 19.608799 -67.002714) (xy 19.609308 -67.0306)
			(xy 19.608799 -67.058486) (xy 19.600679 -67.113662) (xy 19.584611 -67.167069) (xy 19.560939 -67.217566)
			(xy 19.530166 -67.264079) (xy 19.492949 -67.305616) (xy 19.450081 -67.341291) (xy 19.402475 -67.370345)
			(xy 19.351146 -67.392157) (xy 19.297189 -67.406263) (xy 19.241752 -67.412363) (xy 19.186018 -67.410326)
			(xy 19.131175 -67.400196) (xy 19.078391 -67.382189) (xy 19.028791 -67.356688) (xy 18.983433 -67.324237)
			(xy 18.943284 -67.285528) (xy 18.909198 -67.241385) (xy 18.881902 -67.19275) (xy 18.861979 -67.140659)
			(xy 18.849853 -67.086222) (xy 18.845782 -67.0306) (xy 15.367 -67.0306) (xy 15.367 -68.77583) (xy 19.59278 -68.77583)
			(xy 19.59278 -68.715894) (xy 19.600603 -68.656472) (xy 19.616116 -68.598579) (xy 19.639052 -68.543206)
			(xy 19.669019 -68.4913) (xy 19.705506 -68.44375) (xy 19.747886 -68.40137) (xy 19.795436 -68.364883)
			(xy 19.847342 -68.334916) (xy 19.902715 -68.31198) (xy 19.960608 -68.296467) (xy 20.02003 -68.288644)
			(xy 20.079966 -68.288644) (xy 20.139388 -68.296467) (xy 20.197281 -68.31198) (xy 20.252654 -68.334916)
			(xy 20.30456 -68.364883) (xy 20.35211 -68.40137) (xy 20.39449 -68.44375) (xy 20.430977 -68.4913)
			(xy 20.460944 -68.543206) (xy 20.48388 -68.598579) (xy 20.499393 -68.656472) (xy 20.507216 -68.715894)
			(xy 20.507706 -68.745862) (xy 20.507216 -68.77583) (xy 21.392878 -68.77583) (xy 21.392878 -68.715894)
			(xy 21.400701 -68.656472) (xy 21.416214 -68.598579) (xy 21.43915 -68.543206) (xy 21.469117 -68.4913)
			(xy 21.505604 -68.44375) (xy 21.547984 -68.40137) (xy 21.595534 -68.364883) (xy 21.64744 -68.334916)
			(xy 21.702813 -68.31198) (xy 21.760706 -68.296467) (xy 21.820128 -68.288644) (xy 21.880064 -68.288644)
			(xy 21.939486 -68.296467) (xy 21.997379 -68.31198) (xy 22.052752 -68.334916) (xy 22.104658 -68.364883)
			(xy 22.152208 -68.40137) (xy 22.194588 -68.44375) (xy 22.231075 -68.4913) (xy 22.261042 -68.543206)
			(xy 22.283978 -68.598579) (xy 22.299491 -68.656472) (xy 22.307314 -68.715894) (xy 22.307804 -68.745862)
			(xy 22.307314 -68.77583) (xy 22.299491 -68.835252) (xy 22.283978 -68.893145) (xy 22.261042 -68.948518)
			(xy 22.231075 -69.000424) (xy 22.194588 -69.047974) (xy 22.152208 -69.090354) (xy 22.104658 -69.126841)
			(xy 22.052752 -69.156808) (xy 21.997379 -69.179744) (xy 21.939486 -69.195257) (xy 21.880064 -69.20308)
			(xy 21.820128 -69.20308) (xy 21.760706 -69.195257) (xy 21.702813 -69.179744) (xy 21.64744 -69.156808)
			(xy 21.595534 -69.126841) (xy 21.547984 -69.090354) (xy 21.505604 -69.047974) (xy 21.469117 -69.000424)
			(xy 21.43915 -68.948518) (xy 21.416214 -68.893145) (xy 21.400701 -68.835252) (xy 21.392878 -68.77583)
			(xy 20.507216 -68.77583) (xy 20.499393 -68.835252) (xy 20.48388 -68.893145) (xy 20.460944 -68.948518)
			(xy 20.430977 -69.000424) (xy 20.39449 -69.047974) (xy 20.35211 -69.090354) (xy 20.30456 -69.126841)
			(xy 20.252654 -69.156808) (xy 20.197281 -69.179744) (xy 20.139388 -69.195257) (xy 20.079966 -69.20308)
			(xy 20.02003 -69.20308) (xy 19.960608 -69.195257) (xy 19.902715 -69.179744) (xy 19.847342 -69.156808)
			(xy 19.795436 -69.126841) (xy 19.747886 -69.090354) (xy 19.705506 -69.047974) (xy 19.669019 -69.000424)
			(xy 19.639052 -68.948518) (xy 19.616116 -68.893145) (xy 19.600603 -68.835252) (xy 19.59278 -68.77583)
			(xy 15.367 -68.77583) (xy 15.367 -72.368918) (xy 15.367427 -72.378987) (xy 15.375146 -72.397586)
			(xy 15.381986 -72.404986) (xy 15.979648 -73.002648) (xy 15.987964 -73.010206) (xy 16.009061 -73.017858)
			(xy 16.020288 -73.01738) (xy 16.109442 -73.009252) (xy 16.129 -72.997822) (xy 16.13535 -72.988424)
			(xy 16.15067 -72.966863) (xy 16.186307 -72.92778) (xy 16.227001 -72.893993) (xy 16.271971 -72.866151)
			(xy 16.320355 -72.844787) (xy 16.371227 -72.830311) (xy 16.42361 -72.822999) (xy 16.450056 -72.822562)
			(xy 16.477312 -72.823022) (xy 16.531269 -72.830774) (xy 16.583574 -72.846125) (xy 16.633162 -72.868765)
			(xy 16.679022 -72.898231) (xy 16.720223 -72.933925) (xy 16.755924 -72.975118) (xy 16.785399 -73.020973)
			(xy 16.808049 -73.070557) (xy 16.823411 -73.122859) (xy 16.831173 -73.176814) (xy 16.831564 -73.20407)
			(xy 17.868136 -73.20407) (xy 17.872207 -73.148448) (xy 17.884333 -73.094011) (xy 17.904256 -73.04192)
			(xy 17.931552 -72.993285) (xy 17.965638 -72.949142) (xy 18.005787 -72.910433) (xy 18.051145 -72.877982)
			(xy 18.100745 -72.852481) (xy 18.153529 -72.834474) (xy 18.208372 -72.824344) (xy 18.264106 -72.822307)
			(xy 18.319543 -72.828407) (xy 18.3735 -72.842513) (xy 18.424829 -72.864325) (xy 18.472435 -72.893379)
			(xy 18.515303 -72.929054) (xy 18.55252 -72.970591) (xy 18.583293 -73.017104) (xy 18.606965 -73.067601)
			(xy 18.623033 -73.121008) (xy 18.631153 -73.176184) (xy 18.631662 -73.20407) (xy 19.968208 -73.20407)
			(xy 19.972279 -73.148448) (xy 19.984405 -73.094011) (xy 20.004328 -73.04192) (xy 20.031624 -72.993285)
			(xy 20.06571 -72.949142) (xy 20.105859 -72.910433) (xy 20.151217 -72.877982) (xy 20.200817 -72.852481)
			(xy 20.253601 -72.834474) (xy 20.308444 -72.824344) (xy 20.364178 -72.822307) (xy 20.419615 -72.828407)
			(xy 20.473572 -72.842513) (xy 20.524901 -72.864325) (xy 20.572507 -72.893379) (xy 20.615375 -72.929054)
			(xy 20.652592 -72.970591) (xy 20.683365 -73.017104) (xy 20.707037 -73.067601) (xy 20.723105 -73.121008)
			(xy 20.731225 -73.176184) (xy 20.731734 -73.20407) (xy 20.731225 -73.231956) (xy 20.730919 -73.234038)
			(xy 21.092904 -73.234038) (xy 21.092904 -73.174102) (xy 21.100727 -73.11468) (xy 21.11624 -73.056787)
			(xy 21.139176 -73.001414) (xy 21.169143 -72.949508) (xy 21.20563 -72.901958) (xy 21.24801 -72.859578)
			(xy 21.29556 -72.823091) (xy 21.347466 -72.793124) (xy 21.402839 -72.770188) (xy 21.460732 -72.754675)
			(xy 21.520154 -72.746852) (xy 21.58009 -72.746852) (xy 21.639512 -72.754675) (xy 21.697405 -72.770188)
			(xy 21.752778 -72.793124) (xy 21.804684 -72.823091) (xy 21.852234 -72.859578) (xy 21.894614 -72.901958)
			(xy 21.931101 -72.949508) (xy 21.961068 -73.001414) (xy 21.984004 -73.056787) (xy 21.999517 -73.11468)
			(xy 22.00734 -73.174102) (xy 22.00783 -73.20407) (xy 22.00734 -73.234038) (xy 23.192976 -73.234038)
			(xy 23.192976 -73.174102) (xy 23.200799 -73.11468) (xy 23.216312 -73.056787) (xy 23.239248 -73.001414)
			(xy 23.269215 -72.949508) (xy 23.305702 -72.901958) (xy 23.348082 -72.859578) (xy 23.395632 -72.823091)
			(xy 23.447538 -72.793124) (xy 23.502911 -72.770188) (xy 23.560804 -72.754675) (xy 23.620226 -72.746852)
			(xy 23.680162 -72.746852) (xy 23.739584 -72.754675) (xy 23.797477 -72.770188) (xy 23.85285 -72.793124)
			(xy 23.904756 -72.823091) (xy 23.952306 -72.859578) (xy 23.994686 -72.901958) (xy 24.031173 -72.949508)
			(xy 24.06114 -73.001414) (xy 24.084076 -73.056787) (xy 24.099589 -73.11468) (xy 24.107412 -73.174102)
			(xy 24.107902 -73.20407) (xy 24.107412 -73.234038) (xy 24.099589 -73.29346) (xy 24.084076 -73.351353)
			(xy 24.06114 -73.406726) (xy 24.031173 -73.458632) (xy 23.994686 -73.506182) (xy 23.952306 -73.548562)
			(xy 23.904756 -73.585049) (xy 23.85285 -73.615016) (xy 23.797477 -73.637952) (xy 23.739584 -73.653465)
			(xy 23.680162 -73.661288) (xy 23.620226 -73.661288) (xy 23.560804 -73.653465) (xy 23.502911 -73.637952)
			(xy 23.447538 -73.615016) (xy 23.395632 -73.585049) (xy 23.348082 -73.548562) (xy 23.305702 -73.506182)
			(xy 23.269215 -73.458632) (xy 23.239248 -73.406726) (xy 23.216312 -73.351353) (xy 23.200799 -73.29346)
			(xy 23.192976 -73.234038) (xy 22.00734 -73.234038) (xy 21.999517 -73.29346) (xy 21.984004 -73.351353)
			(xy 21.961068 -73.406726) (xy 21.931101 -73.458632) (xy 21.894614 -73.506182) (xy 21.852234 -73.548562)
			(xy 21.804684 -73.585049) (xy 21.752778 -73.615016) (xy 21.697405 -73.637952) (xy 21.639512 -73.653465)
			(xy 21.58009 -73.661288) (xy 21.520154 -73.661288) (xy 21.460732 -73.653465) (xy 21.402839 -73.637952)
			(xy 21.347466 -73.615016) (xy 21.29556 -73.585049) (xy 21.24801 -73.548562) (xy 21.20563 -73.506182)
			(xy 21.169143 -73.458632) (xy 21.139176 -73.406726) (xy 21.11624 -73.351353) (xy 21.100727 -73.29346)
			(xy 21.092904 -73.234038) (xy 20.730919 -73.234038) (xy 20.723105 -73.287132) (xy 20.707037 -73.340539)
			(xy 20.683365 -73.391036) (xy 20.652592 -73.437549) (xy 20.615375 -73.479086) (xy 20.572507 -73.514761)
			(xy 20.524901 -73.543815) (xy 20.473572 -73.565627) (xy 20.419615 -73.579733) (xy 20.364178 -73.585833)
			(xy 20.308444 -73.583796) (xy 20.253601 -73.573666) (xy 20.200817 -73.555659) (xy 20.151217 -73.530158)
			(xy 20.105859 -73.497707) (xy 20.06571 -73.458998) (xy 20.031624 -73.414855) (xy 20.004328 -73.36622)
			(xy 19.984405 -73.314129) (xy 19.972279 -73.259692) (xy 19.968208 -73.20407) (xy 18.631662 -73.20407)
			(xy 18.631153 -73.231956) (xy 18.623033 -73.287132) (xy 18.606965 -73.340539) (xy 18.583293 -73.391036)
			(xy 18.55252 -73.437549) (xy 18.515303 -73.479086) (xy 18.472435 -73.514761) (xy 18.424829 -73.543815)
			(xy 18.3735 -73.565627) (xy 18.319543 -73.579733) (xy 18.264106 -73.585833) (xy 18.208372 -73.583796)
			(xy 18.153529 -73.573666) (xy 18.100745 -73.555659) (xy 18.051145 -73.530158) (xy 18.005787 -73.497707)
			(xy 17.965638 -73.458998) (xy 17.931552 -73.414855) (xy 17.904256 -73.36622) (xy 17.884333 -73.314129)
			(xy 17.872207 -73.259692) (xy 17.868136 -73.20407) (xy 16.831564 -73.20407) (xy 16.831115 -73.230516)
			(xy 16.823812 -73.282901) (xy 16.809341 -73.333776) (xy 16.787981 -73.382163) (xy 16.760141 -73.427135)
			(xy 16.726355 -73.46783) (xy 16.687271 -73.503466) (xy 16.665702 -73.518776) (xy 16.656304 -73.525126)
			(xy 16.644874 -73.544684) (xy 16.636746 -73.633838) (xy 16.636314 -73.64506) (xy 16.643943 -73.666153)
			(xy 16.651478 -73.674478) (xy 16.944848 -73.967848) (xy 16.947896 -73.970134) (xy 16.966597 -73.983988)
			(xy 17.002932 -74.013081) (xy 17.02054 -74.0283) (xy 17.02764 -74.034048) (xy 17.04469 -74.04057)
			(xy 17.053814 -74.041)
		)
		(stroke
			(width 0)
			(type solid)
		)
		(fill yes)
		(layer "B.Cu")
		(net "P5V_STBY")
	)
	(gr_poly
		(pts
			(xy 30.712918 -79.248) (xy 30.722987 -79.247573) (xy 30.741586 -79.239854) (xy 30.748986 -79.233014)
			(xy 31.354014 -78.627986) (xy 31.360868 -78.620591) (xy 31.36861 -78.601992) (xy 31.369 -78.591918)
			(xy 31.369 -72.792082) (xy 31.368573 -72.782013) (xy 31.360854 -72.763414) (xy 31.354014 -72.756014)
			(xy 27.63774 -69.03974) (xy 27.630726 -69.033236) (xy 27.613237 -69.025524) (xy 27.603704 -69.024754)
			(xy 27.52471 -69.02196) (xy 27.50693 -69.02831) (xy 27.499564 -69.03466) (xy 27.478672 -69.052077)
			(xy 27.432881 -69.081428) (xy 27.38338 -69.103967) (xy 27.331176 -69.119235) (xy 27.277332 -69.126921)
			(xy 27.250136 -69.12737) (xy 27.222882 -69.126909) (xy 27.16893 -69.119156) (xy 27.11663 -69.103803)
			(xy 27.067047 -69.081162) (xy 27.021193 -69.051694) (xy 26.979999 -69.016) (xy 26.944305 -68.974806)
			(xy 26.914837 -68.928951) (xy 26.892197 -68.879368) (xy 26.876843 -68.827068) (xy 26.869091 -68.773116)
			(xy 26.868628 -68.745862) (xy 26.869113 -68.718669) (xy 26.876842 -68.664836) (xy 26.892139 -68.612647)
			(xy 26.914692 -68.563159) (xy 26.944046 -68.517375) (xy 26.979604 -68.476225) (xy 27.020646 -68.440542)
			(xy 27.06634 -68.411049) (xy 27.115759 -68.388345) (xy 27.141678 -68.380102) (xy 27.157934 -68.375276)
			(xy 27.178 -68.348606) (xy 27.178 -60.600082) (xy 27.178427 -60.590013) (xy 27.186146 -60.571414)
			(xy 27.192986 -60.564014) (xy 32.116014 -55.640986) (xy 32.122868 -55.633591) (xy 32.13061 -55.614992)
			(xy 32.131 -55.604918) (xy 32.131 -47.646082) (xy 32.131427 -47.636013) (xy 32.139146 -47.617414)
			(xy 32.145986 -47.610014) (xy 37.96792 -41.78808) (xy 37.974772 -41.780684) (xy 37.982512 -41.762085)
			(xy 37.982906 -41.752012) (xy 37.982906 -35.125914) (xy 37.982128 -35.113737) (xy 37.97084 -35.092144)
			(xy 37.961316 -35.084512) (xy 37.883084 -35.029394) (xy 37.858954 -35.026092) (xy 37.84727 -35.03041)
			(xy 37.816218 -35.040756) (xy 37.751723 -35.05187) (xy 37.719 -35.052508) (xy 37.691749 -35.052022)
			(xy 37.637801 -35.044266) (xy 37.585506 -35.028911) (xy 37.535929 -35.006269) (xy 37.490079 -34.976803)
			(xy 37.448888 -34.941112) (xy 37.413197 -34.899921) (xy 37.383731 -34.854071) (xy 37.361089 -34.804494)
			(xy 37.345734 -34.752199) (xy 37.337978 -34.698251) (xy 37.337978 -34.643749) (xy 37.345734 -34.589801)
			(xy 37.361089 -34.537506) (xy 37.383731 -34.487929) (xy 37.413197 -34.442079) (xy 37.448888 -34.400888)
			(xy 37.490079 -34.365197) (xy 37.535929 -34.335731) (xy 37.585506 -34.313089) (xy 37.637801 -34.297734)
			(xy 37.691749 -34.289978) (xy 37.719 -34.289492) (xy 37.751722 -34.290145) (xy 37.816216 -34.301255)
			(xy 37.84727 -34.31159) (xy 37.858954 -34.315908) (xy 37.883084 -34.312606) (xy 37.961316 -34.257488)
			(xy 37.970903 -34.249915) (xy 37.982175 -34.228283) (xy 37.982906 -34.216086) (xy 37.982906 -34.187384)
			(xy 37.982514 -34.178536) (xy 37.976485 -34.161897) (xy 37.965179 -34.148281) (xy 37.95776 -34.143442)
			(xy 37.931344 -34.127948) (xy 37.920242 -34.122257) (xy 37.895339 -34.121319) (xy 37.883846 -34.12617)
			(xy 37.857982 -34.137959) (xy 37.803635 -34.154606) (xy 37.74742 -34.163007) (xy 37.719 -34.163508)
			(xy 37.691749 -34.163022) (xy 37.637801 -34.155266) (xy 37.585506 -34.139911) (xy 37.535929 -34.117269)
			(xy 37.490079 -34.087803) (xy 37.448888 -34.052112) (xy 37.413197 -34.010921) (xy 37.383731 -33.965071)
			(xy 37.361089 -33.915494) (xy 37.345734 -33.863199) (xy 37.337978 -33.809251) (xy 37.337978 -33.754749)
			(xy 37.345734 -33.700801) (xy 37.361089 -33.648506) (xy 37.383731 -33.598929) (xy 37.413197 -33.553079)
			(xy 37.448888 -33.511888) (xy 37.490079 -33.476197) (xy 37.535929 -33.446731) (xy 37.585506 -33.424089)
			(xy 37.637801 -33.408734) (xy 37.691749 -33.400978) (xy 37.719 -33.400492) (xy 37.751722 -33.401145)
			(xy 37.816216 -33.412255) (xy 37.84727 -33.42259) (xy 37.858954 -33.426908) (xy 37.883084 -33.423606)
			(xy 37.961316 -33.368488) (xy 37.970903 -33.360915) (xy 37.982175 -33.339283) (xy 37.982906 -33.327086)
			(xy 37.982906 -33.298384) (xy 37.982514 -33.289536) (xy 37.976485 -33.272897) (xy 37.965179 -33.259281)
			(xy 37.95776 -33.254442) (xy 37.931344 -33.238948) (xy 37.920242 -33.233257) (xy 37.895339 -33.232319)
			(xy 37.883846 -33.23717) (xy 37.857982 -33.248959) (xy 37.803635 -33.265606) (xy 37.74742 -33.274007)
			(xy 37.719 -33.274508) (xy 37.691749 -33.274022) (xy 37.637801 -33.266266) (xy 37.585506 -33.250911)
			(xy 37.535929 -33.228269) (xy 37.490079 -33.198803) (xy 37.448888 -33.163112) (xy 37.413197 -33.121921)
			(xy 37.383731 -33.076071) (xy 37.361089 -33.026494) (xy 37.345734 -32.974199) (xy 37.337978 -32.920251)
			(xy 37.337978 -32.865749) (xy 37.345734 -32.811801) (xy 37.361089 -32.759506) (xy 37.383731 -32.709929)
			(xy 37.413197 -32.664079) (xy 37.448888 -32.622888) (xy 37.490079 -32.587197) (xy 37.535929 -32.557731)
			(xy 37.585506 -32.535089) (xy 37.637801 -32.519734) (xy 37.691749 -32.511978) (xy 37.719 -32.511492)
			(xy 37.751722 -32.512145) (xy 37.816216 -32.523255) (xy 37.84727 -32.53359) (xy 37.858954 -32.537908)
			(xy 37.883084 -32.534606) (xy 37.961316 -32.479488) (xy 37.970903 -32.471915) (xy 37.982175 -32.450283)
			(xy 37.982906 -32.438086) (xy 37.982906 -32.409384) (xy 37.982514 -32.400536) (xy 37.976485 -32.383897)
			(xy 37.965179 -32.370281) (xy 37.95776 -32.365442) (xy 37.931344 -32.349948) (xy 37.920242 -32.344257)
			(xy 37.895339 -32.343319) (xy 37.883846 -32.34817) (xy 37.857982 -32.359959) (xy 37.803635 -32.376606)
			(xy 37.74742 -32.385007) (xy 37.719 -32.385508) (xy 37.691749 -32.385022) (xy 37.637801 -32.377266)
			(xy 37.585506 -32.361911) (xy 37.535929 -32.339269) (xy 37.490079 -32.309803) (xy 37.448888 -32.274112)
			(xy 37.413197 -32.232921) (xy 37.383731 -32.187071) (xy 37.361089 -32.137494) (xy 37.345734 -32.085199)
			(xy 37.337978 -32.031251) (xy 37.337978 -31.976749) (xy 37.345734 -31.922801) (xy 37.361089 -31.870506)
			(xy 37.383731 -31.820929) (xy 37.413197 -31.775079) (xy 37.448888 -31.733888) (xy 37.490079 -31.698197)
			(xy 37.535929 -31.668731) (xy 37.585506 -31.646089) (xy 37.637801 -31.630734) (xy 37.691749 -31.622978)
			(xy 37.719 -31.622492) (xy 37.751722 -31.623145) (xy 37.816216 -31.634255) (xy 37.84727 -31.64459)
			(xy 37.858954 -31.648908) (xy 37.883084 -31.645606) (xy 37.961316 -31.590488) (xy 37.970903 -31.582915)
			(xy 37.982175 -31.561283) (xy 37.982906 -31.549086) (xy 37.982906 -31.520384) (xy 37.982514 -31.511536)
			(xy 37.976485 -31.494897) (xy 37.965179 -31.481281) (xy 37.95776 -31.476442) (xy 37.931344 -31.460948)
			(xy 37.920242 -31.455257) (xy 37.895339 -31.454319) (xy 37.883846 -31.45917) (xy 37.857982 -31.470959)
			(xy 37.803635 -31.487606) (xy 37.74742 -31.496007) (xy 37.719 -31.496508) (xy 37.691749 -31.496022)
			(xy 37.637801 -31.488266) (xy 37.585506 -31.472911) (xy 37.535929 -31.450269) (xy 37.490079 -31.420803)
			(xy 37.448888 -31.385112) (xy 37.413197 -31.343921) (xy 37.383731 -31.298071) (xy 37.361089 -31.248494)
			(xy 37.345734 -31.196199) (xy 37.337978 -31.142251) (xy 37.337978 -31.087749) (xy 37.345734 -31.033801)
			(xy 37.361089 -30.981506) (xy 37.383731 -30.931929) (xy 37.413197 -30.886079) (xy 37.448888 -30.844888)
			(xy 37.490079 -30.809197) (xy 37.535929 -30.779731) (xy 37.585506 -30.757089) (xy 37.637801 -30.741734)
			(xy 37.691749 -30.733978) (xy 37.719 -30.733492) (xy 37.751722 -30.734145) (xy 37.816216 -30.745255)
			(xy 37.84727 -30.75559) (xy 37.858954 -30.759908) (xy 37.883084 -30.756606) (xy 37.961316 -30.701488)
			(xy 37.970903 -30.693915) (xy 37.982175 -30.672283) (xy 37.982906 -30.660086) (xy 37.982906 -30.631384)
			(xy 37.982514 -30.622536) (xy 37.976485 -30.605897) (xy 37.965179 -30.592281) (xy 37.95776 -30.587442)
			(xy 37.931344 -30.571948) (xy 37.920242 -30.566257) (xy 37.895339 -30.565319) (xy 37.883846 -30.57017)
			(xy 37.857982 -30.581959) (xy 37.803635 -30.598606) (xy 37.74742 -30.607007) (xy 37.719 -30.607508)
			(xy 37.691749 -30.607022) (xy 37.637801 -30.599266) (xy 37.585506 -30.583911) (xy 37.535929 -30.561269)
			(xy 37.490079 -30.531803) (xy 37.448888 -30.496112) (xy 37.413197 -30.454921) (xy 37.383731 -30.409071)
			(xy 37.361089 -30.359494) (xy 37.345734 -30.307199) (xy 37.337978 -30.253251) (xy 37.337978 -30.198749)
			(xy 37.345734 -30.144801) (xy 37.361089 -30.092506) (xy 37.383731 -30.042929) (xy 37.413197 -29.997079)
			(xy 37.448888 -29.955888) (xy 37.490079 -29.920197) (xy 37.535929 -29.890731) (xy 37.585506 -29.868089)
			(xy 37.637801 -29.852734) (xy 37.691749 -29.844978) (xy 37.719 -29.844492) (xy 37.751722 -29.845145)
			(xy 37.816216 -29.856255) (xy 37.84727 -29.86659) (xy 37.858954 -29.870908) (xy 37.883084 -29.867606)
			(xy 37.961316 -29.812488) (xy 37.970903 -29.804915) (xy 37.982175 -29.783283) (xy 37.982906 -29.771086)
			(xy 37.982906 -29.742384) (xy 37.982514 -29.733536) (xy 37.976485 -29.716897) (xy 37.965179 -29.703281)
			(xy 37.95776 -29.698442) (xy 37.931344 -29.682948) (xy 37.920242 -29.677257) (xy 37.895339 -29.676319)
			(xy 37.883846 -29.68117) (xy 37.857982 -29.692959) (xy 37.803635 -29.709606) (xy 37.74742 -29.718007)
			(xy 37.719 -29.718508) (xy 37.691749 -29.718022) (xy 37.637801 -29.710266) (xy 37.585506 -29.694911)
			(xy 37.535929 -29.672269) (xy 37.490079 -29.642803) (xy 37.448888 -29.607112) (xy 37.413197 -29.565921)
			(xy 37.383731 -29.520071) (xy 37.361089 -29.470494) (xy 37.345734 -29.418199) (xy 37.337978 -29.364251)
			(xy 37.337978 -29.309749) (xy 37.345734 -29.255801) (xy 37.361089 -29.203506) (xy 37.383731 -29.153929)
			(xy 37.413197 -29.108079) (xy 37.448888 -29.066888) (xy 37.490079 -29.031197) (xy 37.535929 -29.001731)
			(xy 37.585506 -28.979089) (xy 37.637801 -28.963734) (xy 37.691749 -28.955978) (xy 37.719 -28.955492)
			(xy 37.751722 -28.956145) (xy 37.816216 -28.967255) (xy 37.84727 -28.97759) (xy 37.858954 -28.981908)
			(xy 37.883084 -28.978606) (xy 37.961316 -28.923488) (xy 37.970903 -28.915915) (xy 37.982175 -28.894283)
			(xy 37.982906 -28.882086) (xy 37.982906 -28.853384) (xy 37.982514 -28.844536) (xy 37.976485 -28.827897)
			(xy 37.965179 -28.814281) (xy 37.95776 -28.809442) (xy 37.931344 -28.793948) (xy 37.920242 -28.788257)
			(xy 37.895339 -28.787319) (xy 37.883846 -28.79217) (xy 37.857982 -28.803959) (xy 37.803635 -28.820606)
			(xy 37.74742 -28.829007) (xy 37.719 -28.829508) (xy 37.691749 -28.829022) (xy 37.637801 -28.821266)
			(xy 37.585506 -28.805911) (xy 37.535929 -28.783269) (xy 37.490079 -28.753803) (xy 37.448888 -28.718112)
			(xy 37.413197 -28.676921) (xy 37.383731 -28.631071) (xy 37.361089 -28.581494) (xy 37.345734 -28.529199)
			(xy 37.337978 -28.475251) (xy 37.337978 -28.420749) (xy 37.345734 -28.366801) (xy 37.361089 -28.314506)
			(xy 37.383731 -28.264929) (xy 37.413197 -28.219079) (xy 37.448888 -28.177888) (xy 37.490079 -28.142197)
			(xy 37.535929 -28.112731) (xy 37.585506 -28.090089) (xy 37.637801 -28.074734) (xy 37.691749 -28.066978)
			(xy 37.719 -28.066492) (xy 37.751722 -28.067145) (xy 37.816216 -28.078255) (xy 37.84727 -28.08859)
			(xy 37.858954 -28.092908) (xy 37.883084 -28.089606) (xy 37.961316 -28.034488) (xy 37.970903 -28.026915)
			(xy 37.982175 -28.005283) (xy 37.982906 -27.993086) (xy 37.982906 -26.870914) (xy 37.982128 -26.858737)
			(xy 37.97084 -26.837144) (xy 37.961316 -26.829512) (xy 37.883084 -26.774394) (xy 37.858954 -26.771092)
			(xy 37.84727 -26.77541) (xy 37.816218 -26.785756) (xy 37.751723 -26.79687) (xy 37.719 -26.797508)
			(xy 37.691749 -26.797022) (xy 37.637801 -26.789266) (xy 37.585506 -26.773911) (xy 37.535929 -26.751269)
			(xy 37.490079 -26.721803) (xy 37.448888 -26.686112) (xy 37.413197 -26.644921) (xy 37.383731 -26.599071)
			(xy 37.361089 -26.549494) (xy 37.345734 -26.497199) (xy 37.337978 -26.443251) (xy 37.337978 -26.388749)
			(xy 37.345734 -26.334801) (xy 37.361089 -26.282506) (xy 37.383731 -26.232929) (xy 37.413197 -26.187079)
			(xy 37.448888 -26.145888) (xy 37.490079 -26.110197) (xy 37.535929 -26.080731) (xy 37.585506 -26.058089)
			(xy 37.637801 -26.042734) (xy 37.691749 -26.034978) (xy 37.719 -26.034492) (xy 37.751722 -26.035145)
			(xy 37.816216 -26.046255) (xy 37.84727 -26.05659) (xy 37.858954 -26.060908) (xy 37.883084 -26.057606)
			(xy 37.961316 -26.002488) (xy 37.970903 -25.994915) (xy 37.982175 -25.973283) (xy 37.982906 -25.961086)
			(xy 37.982906 -24.838914) (xy 37.982128 -24.826737) (xy 37.97084 -24.805144) (xy 37.961316 -24.797512)
			(xy 37.883084 -24.742394) (xy 37.858954 -24.739092) (xy 37.84727 -24.74341) (xy 37.816218 -24.753756)
			(xy 37.751723 -24.76487) (xy 37.719 -24.765508) (xy 37.691749 -24.765022) (xy 37.637801 -24.757266)
			(xy 37.585506 -24.741911) (xy 37.535929 -24.719269) (xy 37.490079 -24.689803) (xy 37.448888 -24.654112)
			(xy 37.413197 -24.612921) (xy 37.383731 -24.567071) (xy 37.361089 -24.517494) (xy 37.345734 -24.465199)
			(xy 37.337978 -24.411251) (xy 37.337978 -24.356749) (xy 37.345734 -24.302801) (xy 37.361089 -24.250506)
			(xy 37.383731 -24.200929) (xy 37.413197 -24.155079) (xy 37.448888 -24.113888) (xy 37.490079 -24.078197)
			(xy 37.535929 -24.048731) (xy 37.585506 -24.026089) (xy 37.637801 -24.010734) (xy 37.691749 -24.002978)
			(xy 37.719 -24.002492) (xy 37.751722 -24.003145) (xy 37.816216 -24.014255) (xy 37.84727 -24.02459)
			(xy 37.858954 -24.028908) (xy 37.883084 -24.025606) (xy 37.961316 -23.970488) (xy 37.970903 -23.962915)
			(xy 37.982175 -23.941283) (xy 37.982906 -23.929086) (xy 37.982906 -22.806914) (xy 37.982128 -22.794737)
			(xy 37.97084 -22.773144) (xy 37.961316 -22.765512) (xy 37.883084 -22.710394) (xy 37.858954 -22.707092)
			(xy 37.84727 -22.71141) (xy 37.816218 -22.721756) (xy 37.751723 -22.73287) (xy 37.719 -22.733508)
			(xy 37.691749 -22.733022) (xy 37.637801 -22.725266) (xy 37.585506 -22.709911) (xy 37.535929 -22.687269)
			(xy 37.490079 -22.657803) (xy 37.448888 -22.622112) (xy 37.413197 -22.580921) (xy 37.383731 -22.535071)
			(xy 37.361089 -22.485494) (xy 37.345734 -22.433199) (xy 37.337978 -22.379251) (xy 37.337978 -22.324749)
			(xy 37.345734 -22.270801) (xy 37.361089 -22.218506) (xy 37.383731 -22.168929) (xy 37.413197 -22.123079)
			(xy 37.448888 -22.081888) (xy 37.490079 -22.046197) (xy 37.535929 -22.016731) (xy 37.585506 -21.994089)
			(xy 37.637801 -21.978734) (xy 37.691749 -21.970978) (xy 37.719 -21.970492) (xy 37.751722 -21.971145)
			(xy 37.816216 -21.982255) (xy 37.84727 -21.99259) (xy 37.858954 -21.996908) (xy 37.883084 -21.993606)
			(xy 37.961316 -21.938488) (xy 37.970903 -21.930915) (xy 37.982175 -21.909283) (xy 37.982906 -21.897086)
			(xy 37.982906 -20.774914) (xy 37.982128 -20.762737) (xy 37.97084 -20.741144) (xy 37.961316 -20.733512)
			(xy 37.883084 -20.678394) (xy 37.858954 -20.675092) (xy 37.84727 -20.67941) (xy 37.816218 -20.689756)
			(xy 37.751723 -20.70087) (xy 37.719 -20.701508) (xy 37.691749 -20.701022) (xy 37.637801 -20.693266)
			(xy 37.585506 -20.677911) (xy 37.535929 -20.655269) (xy 37.490079 -20.625803) (xy 37.448888 -20.590112)
			(xy 37.413197 -20.548921) (xy 37.383731 -20.503071) (xy 37.361089 -20.453494) (xy 37.345734 -20.401199)
			(xy 37.337978 -20.347251) (xy 37.337978 -20.292749) (xy 37.345734 -20.238801) (xy 37.361089 -20.186506)
			(xy 37.383731 -20.136929) (xy 37.413197 -20.091079) (xy 37.448888 -20.049888) (xy 37.490079 -20.014197)
			(xy 37.535929 -19.984731) (xy 37.585506 -19.962089) (xy 37.637801 -19.946734) (xy 37.691749 -19.938978)
			(xy 37.719 -19.938492) (xy 37.751722 -19.939145) (xy 37.816216 -19.950255) (xy 37.84727 -19.96059)
			(xy 37.858954 -19.964908) (xy 37.883084 -19.961606) (xy 37.961316 -19.906488) (xy 37.970903 -19.898915)
			(xy 37.982175 -19.877283) (xy 37.982906 -19.865086) (xy 37.982906 -19.213068) (xy 37.982477 -19.203)
			(xy 37.974756 -19.184404) (xy 37.96792 -19.177) (xy 37.615114 -18.824194) (xy 37.60771 -18.817362)
			(xy 37.589112 -18.80966) (xy 37.579046 -18.809208) (xy 33.56229 -18.809208) (xy 33.55222 -18.808784)
			(xy 33.533618 -18.801067) (xy 33.526222 -18.794222) (xy 33.323022 -18.591022) (xy 33.313116 -18.584926)
			(xy 33.30702 -18.583148) (xy 33.219365 -18.55466) (xy 33.046344 -18.491081) (xy 32.87624 -18.420068)
			(xy 32.709371 -18.341752) (xy 32.546051 -18.256282) (xy 32.386587 -18.163818) (xy 32.231277 -18.064533)
			(xy 32.080414 -17.958614) (xy 31.934281 -17.846259) (xy 31.793151 -17.72768) (xy 31.657291 -17.603099)
			(xy 31.526954 -17.47275) (xy 31.402386 -17.336878) (xy 31.28382 -17.195737) (xy 31.171479 -17.049593)
			(xy 31.065574 -16.89872) (xy 30.966304 -16.743401) (xy 30.873855 -16.583928) (xy 30.7884 -16.4206)
			(xy 30.7101 -16.253724) (xy 30.639102 -16.083613) (xy 30.57554 -15.910586) (xy 30.547056 -15.82293)
			(xy 30.545024 -15.817088) (xy 30.538928 -15.806928) (xy 30.52699 -15.79499) (xy 30.520135 -15.787595)
			(xy 30.51239 -15.768996) (xy 30.512004 -15.758922) (xy 30.512004 -15.707614) (xy 30.509972 -15.700756)
			(xy 30.483335 -15.605576) (xy 30.437847 -15.413211) (xy 30.401344 -15.21894) (xy 30.373904 -15.023184)
			(xy 30.355589 -14.826364) (xy 30.346435 -14.628905) (xy 30.345888 -14.53007) (xy 30.345888 -11.02995)
			(xy 30.346443 -10.931094) (xy 30.355591 -10.733593) (xy 30.373902 -10.536731) (xy 30.401337 -10.340931)
			(xy 30.437837 -10.146617) (xy 30.483322 -9.954208) (xy 30.509972 -9.85901) (xy 30.512004 -9.852152)
			(xy 30.512004 -9.300718) (xy 30.512442 -9.290655) (xy 30.520178 -9.272072) (xy 30.52699 -9.26465)
			(xy 30.954218 -8.837422) (xy 30.95752 -8.832088) (xy 31.003771 -8.756312) (xy 31.101749 -8.608243)
			(xy 31.205819 -8.46439) (xy 31.315799 -8.325004) (xy 31.431498 -8.190327) (xy 31.552715 -8.060595)
			(xy 31.679238 -7.936031) (xy 31.810847 -7.816855) (xy 31.878778 -7.7597) (xy 31.886983 -7.752142)
			(xy 31.896463 -7.731978) (xy 31.897066 -7.720838) (xy 31.897066 -6.640322) (xy 31.896628 -6.630259)
			(xy 31.88889 -6.611678) (xy 31.88208 -6.604254) (xy 31.56585 -6.288024) (xy 31.55845 -6.281183) (xy 31.539851 -6.273463)
			(xy 31.529782 -6.273038) (xy 30.296358 -6.273038) (xy 30.286292 -6.27347) (xy 30.267702 -6.281199)
			(xy 30.26029 -6.288024) (xy 29.142436 -7.405878) (xy 29.135598 -7.413279) (xy 29.127886 -7.431878)
			(xy 29.12745 -7.441946) (xy 29.12745 -7.781036) (xy 29.1277 -7.788216) (xy 29.131705 -7.802007) (xy 29.135324 -7.808214)
			(xy 29.151999 -7.83572) (xy 29.178314 -7.894413) (xy 29.196153 -7.956212) (xy 29.205164 -8.0199)
			(xy 29.205169 -8.084222) (xy 29.196169 -8.147912) (xy 29.178341 -8.209714) (xy 29.152036 -8.268411)
			(xy 29.135324 -8.295894) (xy 29.131696 -8.302095) (xy 29.127711 -8.315891) (xy 29.12745 -8.323072)
			(xy 29.12745 -17.71015) (xy 29.12798 -17.72014) (xy 29.135686 -17.738581) (xy 29.142436 -17.745964)
			(xy 31.716472 -20.32) (xy 32.227772 -20.32) (xy 32.231843 -20.264378) (xy 32.243969 -20.209941) (xy 32.263892 -20.15785)
			(xy 32.291188 -20.109215) (xy 32.325274 -20.065072) (xy 32.365423 -20.026363) (xy 32.410781 -19.993912)
			(xy 32.460381 -19.968411) (xy 32.513165 -19.950404) (xy 32.568008 -19.940274) (xy 32.623742 -19.938237)
			(xy 32.679179 -19.944337) (xy 32.733136 -19.958443) (xy 32.784465 -19.980255) (xy 32.832071 -20.009309)
			(xy 32.874939 -20.044984) (xy 32.912156 -20.086521) (xy 32.942929 -20.133034) (xy 32.966601 -20.183531)
			(xy 32.982669 -20.236938) (xy 32.990789 -20.292114) (xy 32.991298 -20.32) (xy 32.990789 -20.347886)
			(xy 32.982669 -20.403062) (xy 32.966601 -20.456469) (xy 32.942929 -20.506966) (xy 32.912156 -20.553479)
			(xy 32.874939 -20.595016) (xy 32.832071 -20.630691) (xy 32.784465 -20.659745) (xy 32.733136 -20.681557)
			(xy 32.679179 -20.695663) (xy 32.623742 -20.701763) (xy 32.568008 -20.699726) (xy 32.513165 -20.689596)
			(xy 32.460381 -20.671589) (xy 32.410781 -20.646088) (xy 32.365423 -20.613637) (xy 32.325274 -20.574928)
			(xy 32.291188 -20.530785) (xy 32.263892 -20.48215) (xy 32.243969 -20.430059) (xy 32.231843 -20.375622)
			(xy 32.227772 -20.32) (xy 31.716472 -20.32) (xy 32.195008 -20.798536) (xy 32.20235 -20.805352) (xy 32.220814 -20.813092)
			(xy 32.230822 -20.813522) (xy 32.23387 -20.813522) (xy 32.320992 -20.900644) (xy 32.328387 -20.907498)
			(xy 32.346986 -20.915244) (xy 32.35706 -20.91563) (xy 34.688526 -20.91563) (xy 34.698593 -20.916059)
			(xy 34.717188 -20.923783) (xy 34.724594 -20.930616) (xy 34.88055 -21.086572) (xy 34.89198 -21.093176)
			(xy 34.89833 -21.094954) (xy 34.925509 -21.102898) (xy 34.977338 -21.125701) (xy 35.025226 -21.155916)
			(xy 35.068123 -21.192877) (xy 35.105084 -21.235774) (xy 35.135299 -21.283662) (xy 35.158102 -21.335491)
			(xy 35.166046 -21.36267) (xy 35.167824 -21.36902) (xy 35.174428 -21.38045) (xy 35.291014 -21.497036)
			(xy 35.297864 -21.504432) (xy 35.305599 -21.523031) (xy 35.306 -21.533104) (xy 35.306 -34.903918)
			(xy 35.305573 -34.913987) (xy 35.297854 -34.932586) (xy 35.291014 -34.939986) (xy 34.939986 -35.291014)
			(xy 34.932591 -35.297868) (xy 34.913992 -35.30561) (xy 34.903918 -35.306) (xy 30.628082 -35.306)
			(xy 30.618013 -35.305573) (xy 30.599414 -35.297854) (xy 30.592014 -35.291014) (xy 30.113986 -34.812986)
			(xy 30.107132 -34.805591) (xy 30.09939 -34.786992) (xy 30.099 -34.776918) (xy 30.099 -34.057082)
			(xy 30.098573 -34.047013) (xy 30.090854 -34.028414) (xy 30.084014 -34.021014) (xy 24.906986 -28.843986)
			(xy 24.899591 -28.837132) (xy 24.880992 -28.82939) (xy 24.870918 -28.829) (xy 22.881082 -28.829)
			(xy 22.871013 -28.828573) (xy 22.852414 -28.820854) (xy 22.845014 -28.814014) (xy 22.493986 -28.462986)
			(xy 22.487132 -28.455591) (xy 22.47939 -28.436992) (xy 22.479 -28.426918) (xy 22.479 -25.802082)
			(xy 22.478573 -25.792013) (xy 22.470854 -25.773414) (xy 22.464014 -25.766014) (xy 21.604986 -24.906986)
			(xy 21.597591 -24.900132) (xy 21.578992 -24.89239) (xy 21.568918 -24.892) (xy 20.341082 -24.892)
			(xy 20.331013 -24.891573) (xy 20.312414 -24.883854) (xy 20.305014 -24.877014) (xy 19.953986 -24.525986)
			(xy 19.947132 -24.518591) (xy 19.93939 -24.499992) (xy 19.939 -24.489918) (xy 19.939 -21.738082)
			(xy 19.938573 -21.728013) (xy 19.930854 -21.709414) (xy 19.924014 -21.702014) (xy 19.699986 -21.477986)
			(xy 19.692591 -21.471132) (xy 19.673992 -21.46339) (xy 19.663918 -21.463) (xy 18.690082 -21.463)
			(xy 18.680013 -21.463427) (xy 18.661414 -21.471146) (xy 18.654014 -21.477986) (xy 18.175986 -21.956014)
			(xy 18.169132 -21.963409) (xy 18.16139 -21.982008) (xy 18.161 -21.992082) (xy 18.161 -22.467824)
			(xy 18.161679 -22.480465) (xy 18.173679 -22.502718) (xy 18.18386 -22.510242) (xy 18.265648 -22.56409)
			(xy 18.291048 -22.566376) (xy 18.302986 -22.561042) (xy 18.331342 -22.54919) (xy 18.389943 -22.530655)
			(xy 18.450127 -22.518186) (xy 18.511269 -22.511914) (xy 18.542 -22.511512) (xy 18.575808 -22.511986)
			(xy 18.643 -22.519557) (xy 18.708921 -22.534603) (xy 18.772744 -22.556935) (xy 18.833664 -22.586273)
			(xy 18.890917 -22.622247) (xy 18.943782 -22.664406) (xy 18.991594 -22.712218) (xy 19.033753 -22.765083)
			(xy 19.069727 -22.822336) (xy 19.099065 -22.883256) (xy 19.121397 -22.947079) (xy 19.136443 -23.013)
			(xy 19.144014 -23.080192) (xy 19.144488 -23.114) (xy 19.144031 -23.147807) (xy 19.136456 -23.214996)
			(xy 19.121402 -23.280913) (xy 19.099057 -23.344728) (xy 19.069704 -23.405639) (xy 19.033712 -23.462877)
			(xy 18.991534 -23.515723) (xy 18.967958 -23.539958) (xy 18.957544 -23.550372) (xy 18.950733 -23.557851)
			(xy 18.943137 -23.576583) (xy 18.942812 -23.586694) (xy 18.943574 -23.669752) (xy 18.951448 -23.688294)
			(xy 18.959068 -23.695406) (xy 18.983768 -23.71977) (xy 19.027995 -23.77323) (xy 19.065785 -23.831417)
			(xy 19.096639 -23.893562) (xy 19.120147 -23.95884) (xy 19.135999 -24.026388) (xy 19.143983 -24.095309)
			(xy 19.144488 -24.13) (xy 19.144031 -24.163807) (xy 19.136456 -24.230996) (xy 19.121402 -24.296913)
			(xy 19.099057 -24.360728) (xy 19.069704 -24.421639) (xy 19.033712 -24.478877) (xy 18.991534 -24.531723)
			(xy 18.967958 -24.555958) (xy 18.61058 -24.913336) (xy 18.603903 -24.920748) (xy 18.596337 -24.939184)
			(xy 18.595848 -24.94915) (xy 18.595848 -29.623766) (xy 18.596335 -29.633727) (xy 18.603928 -29.652147)
			(xy 18.61058 -29.65958) (xy 19.797014 -30.846014) (xy 19.804409 -30.852868) (xy 19.823008 -30.86061)
			(xy 19.833082 -30.861) (xy 22.965918 -30.861) (xy 22.975987 -30.861427) (xy 22.994586 -30.869146)
			(xy 23.001986 -30.875986) (xy 28.55976 -36.43376) (xy 28.567166 -36.440455) (xy 28.585602 -36.448058)
			(xy 28.595574 -36.448492) (xy 29.44241 -36.448492) (xy 29.442664 -36.449) (xy 29.442918 -36.449)
			(xy 29.452987 -36.449427) (xy 29.471586 -36.457146) (xy 29.478986 -36.463986) (xy 29.830014 -36.815014)
			(xy 29.836868 -36.822409) (xy 29.84461 -36.841008) (xy 29.845 -36.851082) (xy 29.845 -36.851336)
			(xy 29.845508 -36.85159) (xy 29.845508 -37.638282) (xy 31.944299 -37.638282) (xy 31.944299 -37.509142)
			(xy 31.952249 -37.380247) (xy 31.968119 -37.252087) (xy 31.991848 -37.125146) (xy 32.023347 -36.999907)
			(xy 32.062496 -36.876844) (xy 32.109147 -36.756425) (xy 32.163122 -36.639106) (xy 32.224217 -36.525332)
			(xy 32.2922 -36.415535) (xy 32.366814 -36.310132) (xy 32.447775 -36.209522) (xy 32.534775 -36.114087)
			(xy 32.627486 -36.024188) (xy 32.725556 -35.940167) (xy 32.828611 -35.862343) (xy 32.936262 -35.791011)
			(xy 33.048101 -35.726441) (xy 33.163702 -35.668879) (xy 33.282627 -35.618542) (xy 33.404426 -35.575622)
			(xy 33.528636 -35.540281) (xy 33.654785 -35.512654) (xy 33.782397 -35.492845) (xy 33.910986 -35.480929)
			(xy 34.040064 -35.476953) (xy 34.169142 -35.480929) (xy 34.297731 -35.492845) (xy 34.425343 -35.512654)
			(xy 34.551492 -35.540281) (xy 34.675702 -35.575622) (xy 34.797501 -35.618542) (xy 34.916426 -35.668879)
			(xy 35.032027 -35.726441) (xy 35.143866 -35.791011) (xy 35.251517 -35.862343) (xy 35.354572 -35.940167)
			(xy 35.452642 -36.024188) (xy 35.545353 -36.114087) (xy 35.632353 -36.209522) (xy 35.713314 -36.310132)
			(xy 35.787928 -36.415535) (xy 35.855911 -36.525332) (xy 35.917006 -36.639106) (xy 35.970981 -36.756425)
			(xy 36.017632 -36.876844) (xy 36.056781 -36.999907) (xy 36.08828 -37.125146) (xy 36.112009 -37.252087)
			(xy 36.127879 -37.380247) (xy 36.135829 -37.509142) (xy 36.136326 -37.573712) (xy 36.135829 -37.638282)
			(xy 36.127879 -37.767177) (xy 36.112009 -37.895337) (xy 36.08828 -38.022278) (xy 36.056781 -38.147517)
			(xy 36.017632 -38.27058) (xy 35.970981 -38.390999) (xy 35.917006 -38.508318) (xy 35.855911 -38.622092)
			(xy 35.787928 -38.731889) (xy 35.713314 -38.837292) (xy 35.632353 -38.937902) (xy 35.545353 -39.033337)
			(xy 35.452642 -39.123236) (xy 35.354572 -39.207257) (xy 35.251517 -39.285081) (xy 35.143866 -39.356413)
			(xy 35.032027 -39.420983) (xy 34.916426 -39.478545) (xy 34.797501 -39.528882) (xy 34.675702 -39.571802)
			(xy 34.551492 -39.607143) (xy 34.425343 -39.63477) (xy 34.297731 -39.654579) (xy 34.169142 -39.666495)
			(xy 34.040064 -39.670472) (xy 33.910986 -39.666495) (xy 33.782397 -39.654579) (xy 33.654785 -39.63477)
			(xy 33.528636 -39.607143) (xy 33.404426 -39.571802) (xy 33.282627 -39.528882) (xy 33.163702 -39.478545)
			(xy 33.048101 -39.420983) (xy 32.936262 -39.356413) (xy 32.828611 -39.285081) (xy 32.725556 -39.207257)
			(xy 32.627486 -39.123236) (xy 32.534775 -39.033337) (xy 32.447775 -38.937902) (xy 32.366814 -38.837292)
			(xy 32.2922 -38.731889) (xy 32.224217 -38.622092) (xy 32.163122 -38.508318) (xy 32.109147 -38.390999)
			(xy 32.062496 -38.27058) (xy 32.023347 -38.147517) (xy 31.991848 -38.022278) (xy 31.968119 -37.895337)
			(xy 31.952249 -37.767177) (xy 31.944299 -37.638282) (xy 29.845508 -37.638282) (xy 29.845508 -39.72941)
			(xy 29.845 -39.729664) (xy 29.845 -39.983918) (xy 29.844573 -39.993987) (xy 29.836854 -40.012586)
			(xy 29.830014 -40.019986) (xy 29.21 -40.64) (xy 33.526982 -40.64) (xy 33.531053 -40.584378) (xy 33.543179 -40.529941)
			(xy 33.563102 -40.47785) (xy 33.590398 -40.429215) (xy 33.624484 -40.385072) (xy 33.664633 -40.346363)
			(xy 33.709991 -40.313912) (xy 33.759591 -40.288411) (xy 33.812375 -40.270404) (xy 33.867218 -40.260274)
			(xy 33.922952 -40.258237) (xy 33.978389 -40.264337) (xy 34.032346 -40.278443) (xy 34.083675 -40.300255)
			(xy 34.131281 -40.329309) (xy 34.174149 -40.364984) (xy 34.211366 -40.406521) (xy 34.242139 -40.453034)
			(xy 34.265811 -40.503531) (xy 34.281879 -40.556938) (xy 34.289999 -40.612114) (xy 34.290508 -40.64)
			(xy 34.289999 -40.667886) (xy 34.281879 -40.723062) (xy 34.265811 -40.776469) (xy 34.242139 -40.826966)
			(xy 34.211366 -40.873479) (xy 34.174149 -40.915016) (xy 34.131281 -40.950691) (xy 34.083675 -40.979745)
			(xy 34.032346 -41.001557) (xy 33.978389 -41.015663) (xy 33.922952 -41.021763) (xy 33.867218 -41.019726)
			(xy 33.812375 -41.009596) (xy 33.759591 -40.991589) (xy 33.709991 -40.966088) (xy 33.664633 -40.933637)
			(xy 33.624484 -40.894928) (xy 33.590398 -40.850785) (xy 33.563102 -40.80215) (xy 33.543179 -40.750059)
			(xy 33.531053 -40.695622) (xy 33.526982 -40.64) (xy 29.21 -40.64) (xy 25.287986 -44.562014) (xy 25.281132 -44.569409)
			(xy 25.27339 -44.588008) (xy 25.273 -44.598082) (xy 25.273 -65.891918) (xy 25.272573 -65.901987)
			(xy 25.264854 -65.920586) (xy 25.258014 -65.927986) (xy 24.144986 -67.041014) (xy 24.138132 -67.048409)
			(xy 24.13039 -67.067008) (xy 24.13 -67.077082) (xy 24.13 -68.745862) (xy 25.06802 -68.745862) (xy 25.072091 -68.69024)
			(xy 25.084217 -68.635803) (xy 25.10414 -68.583712) (xy 25.131436 -68.535077) (xy 25.165522 -68.490934)
			(xy 25.205671 -68.452225) (xy 25.251029 -68.419774) (xy 25.300629 -68.394273) (xy 25.353413 -68.376266)
			(xy 25.408256 -68.366136) (xy 25.46399 -68.364099) (xy 25.519427 -68.370199) (xy 25.573384 -68.384305)
			(xy 25.624713 -68.406117) (xy 25.672319 -68.435171) (xy 25.715187 -68.470846) (xy 25.752404 -68.512383)
			(xy 25.783177 -68.558896) (xy 25.806849 -68.609393) (xy 25.822917 -68.6628) (xy 25.831037 -68.717976)
			(xy 25.831546 -68.745862) (xy 25.831037 -68.773748) (xy 25.822917 -68.828924) (xy 25.806849 -68.882331)
			(xy 25.783177 -68.932828) (xy 25.752404 -68.979341) (xy 25.715187 -69.020878) (xy 25.672319 -69.056553)
			(xy 25.624713 -69.085607) (xy 25.573384 -69.107419) (xy 25.519427 -69.121525) (xy 25.46399 -69.127625)
			(xy 25.408256 -69.125588) (xy 25.353413 -69.115458) (xy 25.300629 -69.097451) (xy 25.251029 -69.07195)
			(xy 25.205671 -69.039499) (xy 25.165522 -69.00079) (xy 25.131436 -68.956647) (xy 25.10414 -68.908012)
			(xy 25.084217 -68.855921) (xy 25.072091 -68.801484) (xy 25.06802 -68.745862) (xy 24.13 -68.745862)
			(xy 24.13 -70.082918) (xy 24.130427 -70.092987) (xy 24.138146 -70.111586) (xy 24.144986 -70.118986)
			(xy 25.258014 -71.232014) (xy 25.264868 -71.239409) (xy 25.27261 -71.258008) (xy 25.273 -71.268082)
			(xy 25.273 -72.900032) (xy 25.2735 -72.910469) (xy 25.281825 -72.929609) (xy 25.297113 -72.943818)
			(xy 25.306782 -72.947784) (xy 25.412446 -72.985376) (xy 25.44318 -72.97674) (xy 25.453594 -72.96404)
			(xy 25.4718 -72.942354) (xy 25.513529 -72.904083) (xy 25.560459 -72.872404) (xy 25.611558 -72.848015)
			(xy 25.665703 -72.831452) (xy 25.721701 -72.823079) (xy 25.750012 -72.822562) (xy 25.777265 -72.823049)
			(xy 25.831216 -72.830807) (xy 25.883513 -72.846165) (xy 25.933093 -72.868808) (xy 25.978945 -72.898277)
			(xy 26.020137 -72.933971) (xy 26.05583 -72.975165) (xy 26.085298 -73.021018) (xy 26.10794 -73.070598)
			(xy 26.123295 -73.122896) (xy 26.131052 -73.176847) (xy 26.131052 -73.20407) (xy 26.568144 -73.20407)
			(xy 26.572215 -73.148448) (xy 26.584341 -73.094011) (xy 26.604264 -73.04192) (xy 26.63156 -72.993285)
			(xy 26.665646 -72.949142) (xy 26.705795 -72.910433) (xy 26.751153 -72.877982) (xy 26.800753 -72.852481)
			(xy 26.853537 -72.834474) (xy 26.90838 -72.824344) (xy 26.964114 -72.822307) (xy 27.019551 -72.828407)
			(xy 27.073508 -72.842513) (xy 27.124837 -72.864325) (xy 27.172443 -72.893379) (xy 27.215311 -72.929054)
			(xy 27.252528 -72.970591) (xy 27.283301 -73.017104) (xy 27.306973 -73.067601) (xy 27.323041 -73.121008)
			(xy 27.331161 -73.176184) (xy 27.33167 -73.20407) (xy 27.331161 -73.231956) (xy 27.323041 -73.287132)
			(xy 27.306973 -73.340539) (xy 27.283301 -73.391036) (xy 27.252528 -73.437549) (xy 27.215311 -73.479086)
			(xy 27.172443 -73.514761) (xy 27.124837 -73.543815) (xy 27.073508 -73.565627) (xy 27.019551 -73.579733)
			(xy 26.964114 -73.585833) (xy 26.90838 -73.583796) (xy 26.853537 -73.573666) (xy 26.800753 -73.555659)
			(xy 26.751153 -73.530158) (xy 26.705795 -73.497707) (xy 26.665646 -73.458998) (xy 26.63156 -73.414855)
			(xy 26.604264 -73.36622) (xy 26.584341 -73.314129) (xy 26.572215 -73.259692) (xy 26.568144 -73.20407)
			(xy 26.131052 -73.20407) (xy 26.131052 -73.231353) (xy 26.123295 -73.285304) (xy 26.10794 -73.337602)
			(xy 26.085298 -73.387182) (xy 26.05583 -73.433035) (xy 26.020137 -73.474229) (xy 25.978945 -73.509923)
			(xy 25.933093 -73.539392) (xy 25.883513 -73.562035) (xy 25.831216 -73.577393) (xy 25.777265 -73.585151)
			(xy 25.750012 -73.585578) (xy 25.721701 -73.585062) (xy 25.665701 -73.57669) (xy 25.611555 -73.560128)
			(xy 25.560454 -73.535741) (xy 25.513521 -73.504064) (xy 25.47179 -73.465795) (xy 25.453594 -73.4441)
			(xy 25.44318 -73.4314) (xy 25.412446 -73.422764) (xy 25.306782 -73.460356) (xy 25.297131 -73.46434)
			(xy 25.281885 -73.478575) (xy 25.273519 -73.497682) (xy 25.273 -73.508108) (xy 25.273 -73.765918)
			(xy 25.272573 -73.775987) (xy 25.264854 -73.794586) (xy 25.258014 -73.801986) (xy 24.779986 -74.280014)
			(xy 24.772591 -74.286868) (xy 24.753992 -74.29461) (xy 24.743918 -74.295) (xy 24.695658 -74.295)
			(xy 24.695404 -74.295508) (xy 18.435574 -74.295508) (xy 18.425609 -74.295987) (xy 18.407175 -74.303565)
			(xy 18.39976 -74.31024) (xy 17.86001 -74.84999) (xy 26.306274 -74.84999) (xy 26.310322 -74.755968)
			(xy 26.322439 -74.662643) (xy 26.342533 -74.570704) (xy 26.370456 -74.480834) (xy 26.406002 -74.393696)
			(xy 26.448907 -74.309937) (xy 26.498853 -74.230176) (xy 26.555471 -74.155003) (xy 26.618342 -74.084977)
			(xy 26.686999 -74.020614) (xy 26.760936 -73.962391) (xy 26.839604 -73.910741) (xy 26.922421 -73.866043)
			(xy 27.008773 -73.828631) (xy 27.098023 -73.798781) (xy 27.189507 -73.776713) (xy 27.282551 -73.762592)
			(xy 27.376463 -73.756521) (xy 27.47055 -73.758546) (xy 27.564115 -73.768651) (xy 27.656465 -73.786762)
			(xy 27.746915 -73.812746) (xy 27.834798 -73.846408) (xy 27.919461 -73.887501) (xy 28.000278 -73.935719)
			(xy 28.076651 -73.990707) (xy 28.148014 -74.052056) (xy 28.213839 -74.119314) (xy 28.273639 -74.19198)
			(xy 28.326971 -74.269519) (xy 28.373439 -74.351355) (xy 28.412701 -74.436882) (xy 28.444465 -74.525469)
			(xy 28.468496 -74.616457) (xy 28.484616 -74.709175) (xy 28.492706 -74.802936) (xy 28.493212 -74.84999)
			(xy 28.492706 -74.897044) (xy 28.484616 -74.990805) (xy 28.468496 -75.083523) (xy 28.444465 -75.174511)
			(xy 28.412701 -75.263098) (xy 28.373439 -75.348625) (xy 28.326971 -75.430461) (xy 28.273639 -75.508)
			(xy 28.213839 -75.580666) (xy 28.148014 -75.647924) (xy 28.076651 -75.709273) (xy 28.000278 -75.764261)
			(xy 27.919461 -75.812479) (xy 27.834798 -75.853572) (xy 27.746915 -75.887234) (xy 27.656465 -75.913218)
			(xy 27.564115 -75.931329) (xy 27.47055 -75.941434) (xy 27.376463 -75.943459) (xy 27.282551 -75.937388)
			(xy 27.189507 -75.923267) (xy 27.098023 -75.901199) (xy 27.008773 -75.871349) (xy 26.922421 -75.833937)
			(xy 26.839604 -75.789239) (xy 26.760936 -75.737589) (xy 26.686999 -75.679366) (xy 26.618342 -75.615003)
			(xy 26.555471 -75.544977) (xy 26.498853 -75.469804) (xy 26.448907 -75.390043) (xy 26.406002 -75.306284)
			(xy 26.370456 -75.219146) (xy 26.342533 -75.129276) (xy 26.322439 -75.037337) (xy 26.310322 -74.944012)
			(xy 26.306274 -74.84999) (xy 17.86001 -74.84999) (xy 16.778986 -75.931014) (xy 16.771591 -75.937868)
			(xy 16.752992 -75.94561) (xy 16.742918 -75.946) (xy 15.769082 -75.946) (xy 15.759013 -75.945573)
			(xy 15.740414 -75.937854) (xy 15.733014 -75.931014) (xy 15.07998 -75.27798) (xy 15.073128 -75.270584)
			(xy 15.065388 -75.251985) (xy 15.064994 -75.241912) (xy 15.064994 -67.422776) (xy 15.064572 -67.413456)
			(xy 15.057882 -67.396057) (xy 15.0454 -67.382212) (xy 15.037308 -67.377564) (xy 14.943836 -67.329558)
			(xy 14.915896 -67.331844) (xy 14.903958 -67.340226) (xy 14.879471 -67.357136) (xy 14.826359 -67.383971)
			(xy 14.76973 -67.402251) (xy 14.710953 -67.411534) (xy 14.6812 -67.412108) (xy 14.653949 -67.411622)
			(xy 14.600001 -67.403866) (xy 14.547706 -67.388511) (xy 14.498129 -67.365869) (xy 14.452279 -67.336403)
			(xy 14.411088 -67.300712) (xy 14.375397 -67.259521) (xy 14.345931 -67.213671) (xy 14.323289 -67.164094)
			(xy 14.307934 -67.111799) (xy 14.300178 -67.057851) (xy 14.299692 -67.0306) (xy 14.300105 -67.005012)
			(xy 14.306954 -66.954296) (xy 14.320528 -66.904953) (xy 14.330172 -66.881248) (xy 14.334744 -66.87058)
			(xy 14.333728 -66.848228) (xy 14.286738 -66.758058) (xy 14.268704 -66.744342) (xy 14.257528 -66.742056)
			(xy 14.227042 -66.735153) (xy 14.168159 -66.714179) (xy 14.112678 -66.685387) (xy 14.061632 -66.649313)
			(xy 14.01597 -66.606627) (xy 13.976541 -66.558125) (xy 13.94408 -66.504708) (xy 13.919191 -66.44737)
			(xy 13.902336 -66.387179) (xy 13.89383 -66.325253) (xy 13.893292 -66.294) (xy 13.893782 -66.264032)
			(xy 13.901605 -66.20461) (xy 13.917118 -66.146717) (xy 13.940054 -66.091344) (xy 13.970021 -66.039438)
			(xy 14.006508 -65.991888) (xy 14.048888 -65.949508) (xy 14.096438 -65.913021) (xy 14.148344 -65.883054)
			(xy 14.203717 -65.860118) (xy 14.26161 -65.844605) (xy 14.321032 -65.836782) (xy 14.380968 -65.836782)
			(xy 14.44039 -65.844605) (xy 14.498283 -65.860118) (xy 14.553656 -65.883054) (xy 14.605562 -65.913021)
			(xy 14.653112 -65.949508) (xy 14.695492 -65.991888) (xy 14.731979 -66.039438) (xy 14.761946 -66.091344)
			(xy 14.784882 -66.146717) (xy 14.800395 -66.20461) (xy 14.808218 -66.264032) (xy 14.808708 -66.294)
			(xy 14.808219 -66.323891) (xy 14.800438 -66.383165) (xy 14.785021 -66.440925) (xy 14.762229 -66.496193)
			(xy 14.747748 -66.522346) (xy 14.741906 -66.532252) (xy 14.740128 -66.554604) (xy 14.776196 -66.649854)
			(xy 14.792198 -66.665348) (xy 14.803374 -66.669158) (xy 14.830107 -66.678773) (xy 14.880608 -66.704792)
			(xy 14.903958 -66.720974) (xy 14.915896 -66.729356) (xy 14.943836 -66.731642) (xy 15.037308 -66.683636)
			(xy 15.04541 -66.679015) (xy 15.057857 -66.665144) (xy 15.064524 -66.647742) (xy 15.064994 -66.638424)
			(xy 15.064994 -64.965326) (xy 15.06543 -64.955262) (xy 15.073163 -64.936676) (xy 15.07998 -64.929258)
			(xy 15.732252 -64.276986) (xy 15.739649 -64.270139) (xy 15.758248 -64.26241) (xy 15.76832 -64.262)
			(xy 16.869918 -64.262) (xy 16.879987 -64.262427) (xy 16.898586 -64.270146) (xy 16.905986 -64.276986)
			(xy 17.511014 -64.882014) (xy 17.517868 -64.889409) (xy 17.52561 -64.908008) (xy 17.526 -64.918082)
			(xy 17.526 -65.299336) (xy 17.526508 -65.29959) (xy 17.526508 -65.765426) (xy 17.526987 -65.775391)
			(xy 17.534565 -65.793825) (xy 17.54124 -65.80124) (xy 17.63776 -65.89776) (xy 17.645166 -65.904455)
			(xy 17.663602 -65.912058) (xy 17.673574 -65.912492) (xy 18.902426 -65.912492) (xy 18.912391 -65.912013)
			(xy 18.930825 -65.904435) (xy 18.93824 -65.89776) (xy 19.061684 -65.774316) (xy 19.069 -65.766202)
			(xy 19.076587 -65.745737) (xy 19.075054 -65.723964) (xy 19.07032 -65.714118) (xy 19.055766 -65.685994)
			(xy 19.035162 -65.626117) (xy 19.024726 -65.563661) (xy 19.024092 -65.532) (xy 19.024578 -65.504749)
			(xy 19.032334 -65.450801) (xy 19.047689 -65.398506) (xy 19.070331 -65.348929) (xy 19.099797 -65.303079)
			(xy 19.135488 -65.261888) (xy 19.176679 -65.226197) (xy 19.222529 -65.196731) (xy 19.272106 -65.174089)
			(xy 19.324401 -65.158734) (xy 19.378349 -65.150978) (xy 19.4056 -65.150492) (xy 19.437262 -65.151114)
			(xy 19.499718 -65.161558) (xy 19.559595 -65.182161) (xy 19.587718 -65.19672) (xy 19.602704 -65.204848)
			(xy 19.635724 -65.200276) (xy 19.670014 -65.165986) (xy 19.676868 -65.158591) (xy 19.68461 -65.139992)
			(xy 19.685 -65.129918) (xy 19.685 -61.486288) (xy 19.68451 -61.476282) (xy 19.676848 -61.457794)
			(xy 19.662696 -61.443645) (xy 19.644206 -61.435988) (xy 19.6342 -61.435488) (xy 19.431 -61.435488)
			(xy 19.397192 -61.435014) (xy 19.33 -61.427443) (xy 19.264079 -61.412397) (xy 19.200256 -61.390065)
			(xy 19.139336 -61.360727) (xy 19.082083 -61.324753) (xy 19.029218 -61.282594) (xy 18.981406 -61.234782)
			(xy 18.939247 -61.181917) (xy 18.903273 -61.124664) (xy 18.873935 -61.063744) (xy 18.851603 -60.999921)
			(xy 18.836557 -60.934) (xy 18.828986 -60.866808) (xy 18.828512 -60.833) (xy 18.829017 -60.79831)
			(xy 18.837018 -60.729394) (xy 18.85288 -60.661852) (xy 18.876393 -60.596578) (xy 18.907245 -60.534435)
			(xy 18.945029 -60.476247) (xy 18.989245 -60.422782) (xy 19.013932 -60.398406) (xy 19.021552 -60.39104)
			(xy 19.02968 -60.372244) (xy 19.02968 -60.277756) (xy 19.021552 -60.25896) (xy 19.013932 -60.251594)
			(xy 18.989232 -60.22723) (xy 18.945005 -60.17377) (xy 18.907215 -60.115583) (xy 18.876361 -60.053438)
			(xy 18.852853 -59.98816) (xy 18.837001 -59.920612) (xy 18.829017 -59.851691) (xy 18.828512 -59.817)
			(xy 18.828986 -59.783192) (xy 18.836557 -59.716) (xy 18.851603 -59.650079) (xy 18.873935 -59.586256)
			(xy 18.903273 -59.525336) (xy 18.939247 -59.468083) (xy 18.981406 -59.415218) (xy 19.029218 -59.367406)
			(xy 19.082083 -59.325247) (xy 19.139336 -59.289273) (xy 19.200256 -59.259935) (xy 19.264079 -59.237603)
			(xy 19.33 -59.222557) (xy 19.397192 -59.214986) (xy 19.431 -59.214512) (xy 19.54149 -59.214512) (xy 19.551459 -59.21404)
			(xy 19.569904 -59.206473) (xy 19.577304 -59.19978) (xy 19.620484 -59.1566) (xy 19.62717 -59.149191)
			(xy 19.634755 -59.130755) (xy 19.635216 -59.120786) (xy 19.635216 -58.256932) (xy 19.634603 -58.245606)
			(xy 19.624837 -58.225167) (xy 19.61642 -58.217562) (xy 19.545808 -58.160666) (xy 19.523456 -58.155332)
			(xy 19.512026 -58.157872) (xy 19.492017 -58.161936) (xy 19.451416 -58.166265) (xy 19.431 -58.166508)
			(xy 19.403749 -58.166022) (xy 19.349801 -58.158266) (xy 19.297506 -58.142911) (xy 19.247929 -58.120269)
			(xy 19.202079 -58.090803) (xy 19.160888 -58.055112) (xy 19.125197 -58.013921) (xy 19.095731 -57.968071)
			(xy 19.073089 -57.918494) (xy 19.057734 -57.866199) (xy 19.049978 -57.812251) (xy 19.049978 -57.757749)
			(xy 19.057734 -57.703801) (xy 19.073089 -57.651506) (xy 19.095731 -57.601929) (xy 19.125197 -57.556079)
			(xy 19.160888 -57.514888) (xy 19.202079 -57.479197) (xy 19.247929 -57.449731) (xy 19.297506 -57.427089)
			(xy 19.349801 -57.411734) (xy 19.403749 -57.403978) (xy 19.431 -57.403492) (xy 19.451415 -57.403745)
			(xy 19.492016 -57.408072) (xy 19.512026 -57.412128) (xy 19.523456 -57.414668) (xy 19.545808 -57.409334)
			(xy 19.61642 -57.352438) (xy 19.624817 -57.344822) (xy 19.634567 -57.324387) (xy 19.635216 -57.313068)
			(xy 19.635216 -50.734214) (xy 19.634726 -50.724253) (xy 19.627135 -50.705833) (xy 19.620484 -50.6984)
			(xy 16.465042 -47.542958) (xy 16.44145 -47.518737) (xy 16.399275 -47.465886) (xy 16.363284 -47.408645)
			(xy 16.33393 -47.347732) (xy 16.311582 -47.283916) (xy 16.296521 -47.217998) (xy 16.288938 -47.150808)
			(xy 16.288512 -47.117) (xy 16.289017 -47.08231) (xy 16.297018 -47.013394) (xy 16.31288 -46.945852)
			(xy 16.336393 -46.880578) (xy 16.367245 -46.818435) (xy 16.405029 -46.760247) (xy 16.449245 -46.706782)
			(xy 16.473932 -46.682406) (xy 16.481552 -46.675294) (xy 16.489426 -46.656752) (xy 16.490188 -46.573694)
			(xy 16.489855 -46.563584) (xy 16.482266 -46.54485) (xy 16.475456 -46.537372) (xy 16.465042 -46.526958)
			(xy 16.44145 -46.502737) (xy 16.399275 -46.449886) (xy 16.363284 -46.392645) (xy 16.33393 -46.331732)
			(xy 16.311582 -46.267916) (xy 16.296521 -46.201998) (xy 16.288938 -46.134808) (xy 16.288512 -46.101)
			(xy 16.288986 -46.067192) (xy 16.296557 -46) (xy 16.311603 -45.934079) (xy 16.333935 -45.870256)
			(xy 16.363273 -45.809336) (xy 16.399247 -45.752083) (xy 16.441406 -45.699218) (xy 16.489218 -45.651406)
			(xy 16.542083 -45.609247) (xy 16.599336 -45.573273) (xy 16.660256 -45.543935) (xy 16.724079 -45.521603)
			(xy 16.79 -45.506557) (xy 16.857192 -45.498986) (xy 16.891 -45.498512) (xy 16.928091 -45.499066)
			(xy 17.001709 -45.508198) (xy 17.073646 -45.526311) (xy 17.14281 -45.55313) (xy 17.208153 -45.588248)
			(xy 17.238726 -45.609256) (xy 17.25041 -45.617384) (xy 17.278604 -45.619416) (xy 17.371568 -45.57141)
			(xy 17.37965 -45.566782) (xy 17.392045 -45.552903) (xy 17.398643 -45.535504) (xy 17.399 -45.526198)
			(xy 17.399 -44.852082) (xy 17.398573 -44.842013) (xy 17.390854 -44.823414) (xy 17.384014 -44.816014)
			(xy 17.28724 -44.71924) (xy 17.279834 -44.712545) (xy 17.261398 -44.704942) (xy 17.251426 -44.704508)
			(xy 9.29259 -44.704508) (xy 9.292336 -44.704) (xy 9.292082 -44.704) (xy 9.282013 -44.703573) (xy 9.263414 -44.695854)
			(xy 9.256014 -44.689014) (xy 5.1308 -40.5638) (xy 5.123953 -40.556401) (xy 5.116219 -40.537804) (xy 5.115814 -40.527732)
			(xy 5.115814 -26.218896) (xy 5.115391 -26.208826) (xy 5.107677 -26.190221) (xy 5.100828 -26.182828)
			(xy 4.840986 -25.922986) (xy 4.833591 -25.916132) (xy 4.814992 -25.90839) (xy 4.804918 -25.908) (xy 1.600962 -25.908)
			(xy 1.590895 -25.90843) (xy 1.572301 -25.916154) (xy 1.564894 -25.922986) (xy 1.340866 -26.147014)
			(xy 1.334015 -26.15441) (xy 1.326275 -26.173009) (xy 1.32588 -26.183082) (xy 1.32588 -28.096968)
			(xy 1.574782 -28.096968) (xy 1.574782 -28.037032) (xy 1.582605 -27.97761) (xy 1.598118 -27.919717)
			(xy 1.621054 -27.864344) (xy 1.651021 -27.812438) (xy 1.687508 -27.764888) (xy 1.729888 -27.722508)
			(xy 1.777438 -27.686021) (xy 1.829344 -27.656054) (xy 1.884717 -27.633118) (xy 1.94261 -27.617605)
			(xy 2.002032 -27.609782) (xy 2.061968 -27.609782) (xy 2.12139 -27.617605) (xy 2.179283 -27.633118)
			(xy 2.234656 -27.656054) (xy 2.286562 -27.686021) (xy 2.334112 -27.722508) (xy 2.376492 -27.764888)
			(xy 2.412979 -27.812438) (xy 2.421953 -27.827982) (xy 3.606782 -27.827982) (xy 3.606782 -27.768046)
			(xy 3.614605 -27.708624) (xy 3.630118 -27.650731) (xy 3.653054 -27.595358) (xy 3.683021 -27.543452)
			(xy 3.719508 -27.495902) (xy 3.761888 -27.453522) (xy 3.809438 -27.417035) (xy 3.861344 -27.387068)
			(xy 3.916717 -27.364132) (xy 3.97461 -27.348619) (xy 4.034032 -27.340796) (xy 4.093968 -27.340796)
			(xy 4.15339 -27.348619) (xy 4.211283 -27.364132) (xy 4.266656 -27.387068) (xy 4.318562 -27.417035)
			(xy 4.366112 -27.453522) (xy 4.408492 -27.495902) (xy 4.444979 -27.543452) (xy 4.474946 -27.595358)
			(xy 4.497882 -27.650731) (xy 4.513395 -27.708624) (xy 4.521218 -27.768046) (xy 4.521708 -27.798014)
			(xy 4.521218 -27.827982) (xy 4.513395 -27.887404) (xy 4.497882 -27.945297) (xy 4.474946 -28.00067)
			(xy 4.444979 -28.052576) (xy 4.408492 -28.100126) (xy 4.366112 -28.142506) (xy 4.318562 -28.178993)
			(xy 4.266656 -28.20896) (xy 4.211283 -28.231896) (xy 4.15339 -28.247409) (xy 4.093968 -28.255232)
			(xy 4.034032 -28.255232) (xy 3.97461 -28.247409) (xy 3.916717 -28.231896) (xy 3.861344 -28.20896)
			(xy 3.809438 -28.178993) (xy 3.761888 -28.142506) (xy 3.719508 -28.100126) (xy 3.683021 -28.052576)
			(xy 3.653054 -28.00067) (xy 3.630118 -27.945297) (xy 3.614605 -27.887404) (xy 3.606782 -27.827982)
			(xy 2.421953 -27.827982) (xy 2.442946 -27.864344) (xy 2.465882 -27.919717) (xy 2.481395 -27.97761)
			(xy 2.489218 -28.037032) (xy 2.489708 -28.067) (xy 2.489218 -28.096968) (xy 2.481395 -28.15639) (xy 2.465882 -28.214283)
			(xy 2.442946 -28.269656) (xy 2.412979 -28.321562) (xy 2.376492 -28.369112) (xy 2.334112 -28.411492)
			(xy 2.286562 -28.447979) (xy 2.234656 -28.477946) (xy 2.179283 -28.500882) (xy 2.12139 -28.516395)
			(xy 2.061968 -28.524218) (xy 2.002032 -28.524218) (xy 1.94261 -28.516395) (xy 1.884717 -28.500882)
			(xy 1.829344 -28.477946) (xy 1.777438 -28.447979) (xy 1.729888 -28.411492) (xy 1.687508 -28.369112)
			(xy 1.651021 -28.321562) (xy 1.621054 -28.269656) (xy 1.598118 -28.214283) (xy 1.582605 -28.15639)
			(xy 1.574782 -28.096968) (xy 1.32588 -28.096968) (xy 1.32588 -46.765968) (xy 2.463782 -46.765968)
			(xy 2.463782 -46.706032) (xy 2.471605 -46.64661) (xy 2.487118 -46.588717) (xy 2.510054 -46.533344)
			(xy 2.540021 -46.481438) (xy 2.576508 -46.433888) (xy 2.618888 -46.391508) (xy 2.666438 -46.355021)
			(xy 2.718344 -46.325054) (xy 2.773717 -46.302118) (xy 2.83161 -46.286605) (xy 2.891032 -46.278782)
			(xy 2.950968 -46.278782) (xy 3.01039 -46.286605) (xy 3.068283 -46.302118) (xy 3.123656 -46.325054)
			(xy 3.175562 -46.355021) (xy 3.223112 -46.391508) (xy 3.265492 -46.433888) (xy 3.301979 -46.481438)
			(xy 3.331946 -46.533344) (xy 3.354882 -46.588717) (xy 3.370395 -46.64661) (xy 3.378218 -46.706032)
			(xy 3.378708 -46.736) (xy 3.378218 -46.765968) (xy 3.370395 -46.82539) (xy 3.354882 -46.883283) (xy 3.331946 -46.938656)
			(xy 3.301979 -46.990562) (xy 3.265492 -47.038112) (xy 3.223112 -47.080492) (xy 3.175562 -47.116979)
			(xy 3.123656 -47.146946) (xy 3.068283 -47.169882) (xy 3.01039 -47.185395) (xy 2.950968 -47.193218)
			(xy 2.891032 -47.193218) (xy 2.83161 -47.185395) (xy 2.773717 -47.169882) (xy 2.718344 -47.146946)
			(xy 2.666438 -47.116979) (xy 2.618888 -47.080492) (xy 2.576508 -47.038112) (xy 2.540021 -46.990562)
			(xy 2.510054 -46.938656) (xy 2.487118 -46.883283) (xy 2.471605 -46.82539) (xy 2.463782 -46.765968)
			(xy 1.32588 -46.765968) (xy 1.32588 -47.273968) (xy 7.924782 -47.273968) (xy 7.924782 -47.214032)
			(xy 7.932605 -47.15461) (xy 7.948118 -47.096717) (xy 7.971054 -47.041344) (xy 8.001021 -46.989438)
			(xy 8.037508 -46.941888) (xy 8.079888 -46.899508) (xy 8.127438 -46.863021) (xy 8.179344 -46.833054)
			(xy 8.234717 -46.810118) (xy 8.29261 -46.794605) (xy 8.352032 -46.786782) (xy 8.411968 -46.786782)
			(xy 8.47139 -46.794605) (xy 8.529283 -46.810118) (xy 8.584656 -46.833054) (xy 8.636562 -46.863021)
			(xy 8.684112 -46.899508) (xy 8.726492 -46.941888) (xy 8.762979 -46.989438) (xy 8.792946 -47.041344)
			(xy 8.815882 -47.096717) (xy 8.831395 -47.15461) (xy 8.839218 -47.214032) (xy 8.839708 -47.244) (xy 8.839218 -47.273968)
			(xy 8.831395 -47.33339) (xy 8.815882 -47.391283) (xy 8.792946 -47.446656) (xy 8.762979 -47.498562)
			(xy 8.726492 -47.546112) (xy 8.684112 -47.588492) (xy 8.636562 -47.624979) (xy 8.584656 -47.654946)
			(xy 8.529283 -47.677882) (xy 8.47139 -47.693395) (xy 8.411968 -47.701218) (xy 8.352032 -47.701218)
			(xy 8.29261 -47.693395) (xy 8.234717 -47.677882) (xy 8.179344 -47.654946) (xy 8.127438 -47.624979)
			(xy 8.079888 -47.588492) (xy 8.037508 -47.546112) (xy 8.001021 -47.498562) (xy 7.971054 -47.446656)
			(xy 7.948118 -47.391283) (xy 7.932605 -47.33339) (xy 7.924782 -47.273968) (xy 1.32588 -47.273968)
			(xy 1.32588 -48.797968) (xy 2.463782 -48.797968) (xy 2.463782 -48.738032) (xy 2.471605 -48.67861)
			(xy 2.487118 -48.620717) (xy 2.510054 -48.565344) (xy 2.540021 -48.513438) (xy 2.576508 -48.465888)
			(xy 2.618888 -48.423508) (xy 2.666438 -48.387021) (xy 2.718344 -48.357054) (xy 2.773717 -48.334118)
			(xy 2.83161 -48.318605) (xy 2.891032 -48.310782) (xy 2.950968 -48.310782) (xy 3.01039 -48.318605)
			(xy 3.068283 -48.334118) (xy 3.123656 -48.357054) (xy 3.175562 -48.387021) (xy 3.223112 -48.423508)
			(xy 3.265492 -48.465888) (xy 3.301979 -48.513438) (xy 3.331946 -48.565344) (xy 3.354882 -48.620717)
			(xy 3.370395 -48.67861) (xy 3.378218 -48.738032) (xy 3.378708 -48.768) (xy 3.378218 -48.797968) (xy 3.370395 -48.85739)
			(xy 3.354882 -48.915283) (xy 3.331946 -48.970656) (xy 3.301979 -49.022562) (xy 3.265492 -49.070112)
			(xy 3.223112 -49.112492) (xy 3.175562 -49.148979) (xy 3.123656 -49.178946) (xy 3.068283 -49.201882)
			(xy 3.01039 -49.217395) (xy 2.950968 -49.225218) (xy 2.891032 -49.225218) (xy 2.83161 -49.217395)
			(xy 2.773717 -49.201882) (xy 2.718344 -49.178946) (xy 2.666438 -49.148979) (xy 2.618888 -49.112492)
			(xy 2.576508 -49.070112) (xy 2.540021 -49.022562) (xy 2.510054 -48.970656) (xy 2.487118 -48.915283)
			(xy 2.471605 -48.85739) (xy 2.463782 -48.797968) (xy 1.32588 -48.797968) (xy 1.32588 -50.829968)
			(xy 2.463782 -50.829968) (xy 2.463782 -50.770032) (xy 2.471605 -50.71061) (xy 2.487118 -50.652717)
			(xy 2.510054 -50.597344) (xy 2.540021 -50.545438) (xy 2.576508 -50.497888) (xy 2.618888 -50.455508)
			(xy 2.666438 -50.419021) (xy 2.718344 -50.389054) (xy 2.773717 -50.366118) (xy 2.83161 -50.350605)
			(xy 2.891032 -50.342782) (xy 2.950968 -50.342782) (xy 3.01039 -50.350605) (xy 3.068283 -50.366118)
			(xy 3.123656 -50.389054) (xy 3.175562 -50.419021) (xy 3.223112 -50.455508) (xy 3.265492 -50.497888)
			(xy 3.301979 -50.545438) (xy 3.331946 -50.597344) (xy 3.354882 -50.652717) (xy 3.370395 -50.71061)
			(xy 3.378218 -50.770032) (xy 3.378708 -50.8) (xy 3.378218 -50.829968) (xy 15.817832 -50.829968) (xy 15.817832 -50.770032)
			(xy 15.825655 -50.71061) (xy 15.841168 -50.652717) (xy 15.864104 -50.597344) (xy 15.894071 -50.545438)
			(xy 15.930558 -50.497888) (xy 15.972938 -50.455508) (xy 16.020488 -50.419021) (xy 16.072394 -50.389054)
			(xy 16.127767 -50.366118) (xy 16.18566 -50.350605) (xy 16.245082 -50.342782) (xy 16.305018 -50.342782)
			(xy 16.36444 -50.350605) (xy 16.422333 -50.366118) (xy 16.477706 -50.389054) (xy 16.529612 -50.419021)
			(xy 16.577162 -50.455508) (xy 16.619542 -50.497888) (xy 16.656029 -50.545438) (xy 16.685996 -50.597344)
			(xy 16.708932 -50.652717) (xy 16.724445 -50.71061) (xy 16.732268 -50.770032) (xy 16.732758 -50.8)
			(xy 16.732268 -50.829968) (xy 16.724445 -50.88939) (xy 16.708932 -50.947283) (xy 16.685996 -51.002656)
			(xy 16.656029 -51.054562) (xy 16.619542 -51.102112) (xy 16.577162 -51.144492) (xy 16.529612 -51.180979)
			(xy 16.477706 -51.210946) (xy 16.422333 -51.233882) (xy 16.36444 -51.249395) (xy 16.305018 -51.257218)
			(xy 16.245082 -51.257218) (xy 16.18566 -51.249395) (xy 16.127767 -51.233882) (xy 16.072394 -51.210946)
			(xy 16.020488 -51.180979) (xy 15.972938 -51.144492) (xy 15.930558 -51.102112) (xy 15.894071 -51.054562)
			(xy 15.864104 -51.002656) (xy 15.841168 -50.947283) (xy 15.825655 -50.88939) (xy 15.817832 -50.829968)
			(xy 3.378218 -50.829968) (xy 3.370395 -50.88939) (xy 3.354882 -50.947283) (xy 3.331946 -51.002656)
			(xy 3.301979 -51.054562) (xy 3.265492 -51.102112) (xy 3.223112 -51.144492) (xy 3.175562 -51.180979)
			(xy 3.123656 -51.210946) (xy 3.068283 -51.233882) (xy 3.01039 -51.249395) (xy 2.950968 -51.257218)
			(xy 2.891032 -51.257218) (xy 2.83161 -51.249395) (xy 2.773717 -51.233882) (xy 2.718344 -51.210946)
			(xy 2.666438 -51.180979) (xy 2.618888 -51.144492) (xy 2.576508 -51.102112) (xy 2.540021 -51.054562)
			(xy 2.510054 -51.002656) (xy 2.487118 -50.947283) (xy 2.471605 -50.88939) (xy 2.463782 -50.829968)
			(xy 1.32588 -50.829968) (xy 1.32588 -51.845968) (xy 14.547832 -51.845968) (xy 14.547832 -51.786032)
			(xy 14.555655 -51.72661) (xy 14.571168 -51.668717) (xy 14.594104 -51.613344) (xy 14.624071 -51.561438)
			(xy 14.660558 -51.513888) (xy 14.702938 -51.471508) (xy 14.750488 -51.435021) (xy 14.802394 -51.405054)
			(xy 14.857767 -51.382118) (xy 14.91566 -51.366605) (xy 14.975082 -51.358782) (xy 15.035018 -51.358782)
			(xy 15.09444 -51.366605) (xy 15.152333 -51.382118) (xy 15.207706 -51.405054) (xy 15.259612 -51.435021)
			(xy 15.307162 -51.471508) (xy 15.349542 -51.513888) (xy 15.386029 -51.561438) (xy 15.415996 -51.613344)
			(xy 15.438932 -51.668717) (xy 15.454445 -51.72661) (xy 15.462268 -51.786032) (xy 15.462758 -51.816)
			(xy 15.462268 -51.845968) (xy 15.454445 -51.90539) (xy 15.438932 -51.963283) (xy 15.415996 -52.018656)
			(xy 15.386029 -52.070562) (xy 15.349542 -52.118112) (xy 15.307162 -52.160492) (xy 15.259612 -52.196979)
			(xy 15.207706 -52.226946) (xy 15.152333 -52.249882) (xy 15.09444 -52.265395) (xy 15.035018 -52.273218)
			(xy 14.975082 -52.273218) (xy 14.91566 -52.265395) (xy 14.857767 -52.249882) (xy 14.802394 -52.226946)
			(xy 14.750488 -52.196979) (xy 14.702938 -52.160492) (xy 14.660558 -52.118112) (xy 14.624071 -52.070562)
			(xy 14.594104 -52.018656) (xy 14.571168 -51.963283) (xy 14.555655 -51.90539) (xy 14.547832 -51.845968)
			(xy 1.32588 -51.845968) (xy 1.32588 -54.258968) (xy 4.495782 -54.258968) (xy 4.495782 -54.199032)
			(xy 4.503605 -54.13961) (xy 4.519118 -54.081717) (xy 4.542054 -54.026344) (xy 4.572021 -53.974438)
			(xy 4.608508 -53.926888) (xy 4.650888 -53.884508) (xy 4.698438 -53.848021) (xy 4.750344 -53.818054)
			(xy 4.805717 -53.795118) (xy 4.86361 -53.779605) (xy 4.923032 -53.771782) (xy 4.982968 -53.771782)
			(xy 5.04239 -53.779605) (xy 5.100283 -53.795118) (xy 5.155656 -53.818054) (xy 5.207562 -53.848021)
			(xy 5.255112 -53.884508) (xy 5.297492 -53.926888) (xy 5.333979 -53.974438) (xy 5.363946 -54.026344)
			(xy 5.386882 -54.081717) (xy 5.402395 -54.13961) (xy 5.410218 -54.199032) (xy 5.410708 -54.229) (xy 5.410218 -54.258968)
			(xy 5.409148 -54.267096) (xy 9.956782 -54.267096) (xy 9.956782 -54.20716) (xy 9.964605 -54.147738)
			(xy 9.980118 -54.089845) (xy 10.003054 -54.034472) (xy 10.033021 -53.982566) (xy 10.069508 -53.935016)
			(xy 10.111888 -53.892636) (xy 10.159438 -53.856149) (xy 10.211344 -53.826182) (xy 10.266717 -53.803246)
			(xy 10.32461 -53.787733) (xy 10.384032 -53.77991) (xy 10.443968 -53.77991) (xy 10.50339 -53.787733)
			(xy 10.561283 -53.803246) (xy 10.616656 -53.826182) (xy 10.668562 -53.856149) (xy 10.716112 -53.892636)
			(xy 10.758492 -53.935016) (xy 10.794979 -53.982566) (xy 10.824946 -54.034472) (xy 10.847882 -54.089845)
			(xy 10.863395 -54.147738) (xy 10.871218 -54.20716) (xy 10.871708 -54.237128) (xy 10.871218 -54.267096)
			(xy 10.863395 -54.326518) (xy 10.847882 -54.384411) (xy 10.824946 -54.439784) (xy 10.794979 -54.49169)
			(xy 10.758492 -54.53924) (xy 10.716112 -54.58162) (xy 10.668562 -54.618107) (xy 10.616656 -54.648074)
			(xy 10.561283 -54.67101) (xy 10.50339 -54.686523) (xy 10.443968 -54.694346) (xy 10.384032 -54.694346)
			(xy 10.32461 -54.686523) (xy 10.266717 -54.67101) (xy 10.211344 -54.648074) (xy 10.159438 -54.618107)
			(xy 10.111888 -54.58162) (xy 10.069508 -54.53924) (xy 10.033021 -54.49169) (xy 10.003054 -54.439784)
			(xy 9.980118 -54.384411) (xy 9.964605 -54.326518) (xy 9.956782 -54.267096) (xy 5.409148 -54.267096)
			(xy 5.402395 -54.31839) (xy 5.386882 -54.376283) (xy 5.363946 -54.431656) (xy 5.333979 -54.483562)
			(xy 5.297492 -54.531112) (xy 5.255112 -54.573492) (xy 5.207562 -54.609979) (xy 5.155656 -54.639946)
			(xy 5.100283 -54.662882) (xy 5.04239 -54.678395) (xy 4.982968 -54.686218) (xy 4.923032 -54.686218)
			(xy 4.86361 -54.678395) (xy 4.805717 -54.662882) (xy 4.750344 -54.639946) (xy 4.698438 -54.609979)
			(xy 4.650888 -54.573492) (xy 4.608508 -54.531112) (xy 4.572021 -54.483562) (xy 4.542054 -54.431656)
			(xy 4.519118 -54.376283) (xy 4.503605 -54.31839) (xy 4.495782 -54.258968) (xy 1.32588 -54.258968)
			(xy 1.32588 -56.290968) (xy 4.495782 -56.290968) (xy 4.495782 -56.231032) (xy 4.503605 -56.17161)
			(xy 4.519118 -56.113717) (xy 4.542054 -56.058344) (xy 4.572021 -56.006438) (xy 4.608508 -55.958888)
			(xy 4.650888 -55.916508) (xy 4.698438 -55.880021) (xy 4.750344 -55.850054) (xy 4.805717 -55.827118)
			(xy 4.86361 -55.811605) (xy 4.923032 -55.803782) (xy 4.982968 -55.803782) (xy 5.04239 -55.811605)
			(xy 5.100283 -55.827118) (xy 5.155656 -55.850054) (xy 5.207562 -55.880021) (xy 5.255112 -55.916508)
			(xy 5.297492 -55.958888) (xy 5.333979 -56.006438) (xy 5.363946 -56.058344) (xy 5.386882 -56.113717)
			(xy 5.402395 -56.17161) (xy 5.410218 -56.231032) (xy 5.410708 -56.261) (xy 5.410218 -56.290968) (xy 5.402395 -56.35039)
			(xy 5.386882 -56.408283) (xy 5.363946 -56.463656) (xy 5.333979 -56.515562) (xy 5.297492 -56.563112)
			(xy 5.255112 -56.605492) (xy 5.207562 -56.641979) (xy 5.155656 -56.671946) (xy 5.100283 -56.694882)
			(xy 5.04239 -56.710395) (xy 4.982968 -56.718218) (xy 4.923032 -56.718218) (xy 4.86361 -56.710395)
			(xy 4.805717 -56.694882) (xy 4.750344 -56.671946) (xy 4.698438 -56.641979) (xy 4.650888 -56.605492)
			(xy 4.608508 -56.563112) (xy 4.572021 -56.515562) (xy 4.542054 -56.463656) (xy 4.519118 -56.408283)
			(xy 4.503605 -56.35039) (xy 4.495782 -56.290968) (xy 1.32588 -56.290968) (xy 1.32588 -58.293) (xy 4.570982 -58.293)
			(xy 4.575053 -58.237378) (xy 4.587179 -58.182941) (xy 4.607102 -58.13085) (xy 4.634398 -58.082215)
			(xy 4.668484 -58.038072) (xy 4.708633 -57.999363) (xy 4.753991 -57.966912) (xy 4.803591 -57.941411)
			(xy 4.856375 -57.923404) (xy 4.911218 -57.913274) (xy 4.966952 -57.911237) (xy 5.022389 -57.917337)
			(xy 5.076346 -57.931443) (xy 5.127675 -57.953255) (xy 5.175281 -57.982309) (xy 5.218149 -58.017984)
			(xy 5.255366 -58.059521) (xy 5.286139 -58.106034) (xy 5.309811 -58.156531) (xy 5.325879 -58.209938)
			(xy 5.333999 -58.265114) (xy 5.334508 -58.293) (xy 5.333999 -58.320886) (xy 5.325879 -58.376062)
			(xy 5.309811 -58.429469) (xy 5.286139 -58.479966) (xy 5.255366 -58.526479) (xy 5.218149 -58.568016)
			(xy 5.175281 -58.603691) (xy 5.127675 -58.632745) (xy 5.076346 -58.654557) (xy 5.022389 -58.668663)
			(xy 4.966952 -58.674763) (xy 4.911218 -58.672726) (xy 4.856375 -58.662596) (xy 4.803591 -58.644589)
			(xy 4.753991 -58.619088) (xy 4.708633 -58.586637) (xy 4.668484 -58.547928) (xy 4.634398 -58.503785)
			(xy 4.607102 -58.45515) (xy 4.587179 -58.403059) (xy 4.575053 -58.348622) (xy 4.570982 -58.293) (xy 1.32588 -58.293)
			(xy 1.32588 -58.581798) (xy 1.326302 -58.591869) (xy 1.334014 -58.610476) (xy 1.340866 -58.617866)
			(xy 1.553968 -58.830968) (xy 16.941782 -58.830968) (xy 16.941782 -58.771032) (xy 16.949605 -58.71161)
			(xy 16.965118 -58.653717) (xy 16.988054 -58.598344) (xy 17.018021 -58.546438) (xy 17.054508 -58.498888)
			(xy 17.096888 -58.456508) (xy 17.144438 -58.420021) (xy 17.196344 -58.390054) (xy 17.251717 -58.367118)
			(xy 17.30961 -58.351605) (xy 17.369032 -58.343782) (xy 17.428968 -58.343782) (xy 17.48839 -58.351605)
			(xy 17.546283 -58.367118) (xy 17.601656 -58.390054) (xy 17.653562 -58.420021) (xy 17.701112 -58.456508)
			(xy 17.743492 -58.498888) (xy 17.779979 -58.546438) (xy 17.809946 -58.598344) (xy 17.832882 -58.653717)
			(xy 17.848395 -58.71161) (xy 17.856218 -58.771032) (xy 17.856708 -58.801) (xy 17.856218 -58.830968)
			(xy 17.848395 -58.89039) (xy 17.832882 -58.948283) (xy 17.809946 -59.003656) (xy 17.779979 -59.055562)
			(xy 17.743492 -59.103112) (xy 17.701112 -59.145492) (xy 17.653562 -59.181979) (xy 17.601656 -59.211946)
			(xy 17.546283 -59.234882) (xy 17.48839 -59.250395) (xy 17.428968 -59.258218) (xy 17.369032 -59.258218)
			(xy 17.30961 -59.250395) (xy 17.251717 -59.234882) (xy 17.196344 -59.211946) (xy 17.144438 -59.181979)
			(xy 17.096888 -59.145492) (xy 17.054508 -59.103112) (xy 17.018021 -59.055562) (xy 16.988054 -59.003656)
			(xy 16.965118 -58.948283) (xy 16.949605 -58.89039) (xy 16.941782 -58.830968) (xy 1.553968 -58.830968)
			(xy 3.048 -60.325) (xy 4.570982 -60.325) (xy 4.575053 -60.269378) (xy 4.587179 -60.214941) (xy 4.607102 -60.16285)
			(xy 4.634398 -60.114215) (xy 4.668484 -60.070072) (xy 4.708633 -60.031363) (xy 4.753991 -59.998912)
			(xy 4.803591 -59.973411) (xy 4.856375 -59.955404) (xy 4.911218 -59.945274) (xy 4.966952 -59.943237)
			(xy 5.022389 -59.949337) (xy 5.076346 -59.963443) (xy 5.127675 -59.985255) (xy 5.175281 -60.014309)
			(xy 5.218149 -60.049984) (xy 5.255366 -60.091521) (xy 5.286139 -60.138034) (xy 5.309811 -60.188531)
			(xy 5.325879 -60.241938) (xy 5.333999 -60.297114) (xy 5.334508 -60.325) (xy 5.333999 -60.352886)
			(xy 5.325879 -60.408062) (xy 5.309811 -60.461469) (xy 5.286139 -60.511966) (xy 5.255366 -60.558479)
			(xy 5.218149 -60.600016) (xy 5.175281 -60.635691) (xy 5.127675 -60.664745) (xy 5.076346 -60.686557)
			(xy 5.022389 -60.700663) (xy 4.966952 -60.706763) (xy 4.911218 -60.704726) (xy 4.856375 -60.694596)
			(xy 4.803591 -60.676589) (xy 4.753991 -60.651088) (xy 4.708633 -60.618637) (xy 4.668484 -60.579928)
			(xy 4.634398 -60.535785) (xy 4.607102 -60.48715) (xy 4.587179 -60.435059) (xy 4.575053 -60.380622)
			(xy 4.570982 -60.325) (xy 3.048 -60.325) (xy 4.739132 -62.016132) (xy 4.770882 -62.021466) (xy 4.785614 -62.0141)
			(xy 4.811821 -62.001929) (xy 4.866986 -61.98474) (xy 4.924109 -61.976046) (xy 4.953 -61.975492) (xy 4.980251 -61.975978)
			(xy 5.034199 -61.983734) (xy 5.086494 -61.999089) (xy 5.136071 -62.021731) (xy 5.181921 -62.051197)
			(xy 5.223112 -62.086888) (xy 5.258803 -62.128079) (xy 5.288269 -62.173929) (xy 5.310911 -62.223506)
			(xy 5.326266 -62.275801) (xy 5.334022 -62.329749) (xy 5.334508 -62.357) (xy 5.334002 -62.385895)
			(xy 5.325326 -62.443029) (xy 5.308112 -62.498194) (xy 5.2959 -62.524386) (xy 5.288534 -62.539118)
			(xy 5.293868 -62.570868) (xy 5.490968 -62.767968) (xy 17.087832 -62.767968) (xy 17.087832 -62.708032)
			(xy 17.095655 -62.64861) (xy 17.111168 -62.590717) (xy 17.134104 -62.535344) (xy 17.164071 -62.483438)
			(xy 17.200558 -62.435888) (xy 17.242938 -62.393508) (xy 17.290488 -62.357021) (xy 17.342394 -62.327054)
			(xy 17.397767 -62.304118) (xy 17.45566 -62.288605) (xy 17.515082 -62.280782) (xy 17.575018 -62.280782)
			(xy 17.63444 -62.288605) (xy 17.692333 -62.304118) (xy 17.747706 -62.327054) (xy 17.799612 -62.357021)
			(xy 17.847162 -62.393508) (xy 17.889542 -62.435888) (xy 17.926029 -62.483438) (xy 17.955996 -62.535344)
			(xy 17.978932 -62.590717) (xy 17.994445 -62.64861) (xy 18.002268 -62.708032) (xy 18.002758 -62.738)
			(xy 18.002268 -62.767968) (xy 17.994445 -62.82739) (xy 17.978932 -62.885283) (xy 17.955996 -62.940656)
			(xy 17.926029 -62.992562) (xy 17.889542 -63.040112) (xy 17.847162 -63.082492) (xy 17.799612 -63.118979)
			(xy 17.747706 -63.148946) (xy 17.692333 -63.171882) (xy 17.63444 -63.187395) (xy 17.575018 -63.195218)
			(xy 17.515082 -63.195218) (xy 17.45566 -63.187395) (xy 17.397767 -63.171882) (xy 17.342394 -63.148946)
			(xy 17.290488 -63.118979) (xy 17.242938 -63.082492) (xy 17.200558 -63.040112) (xy 17.164071 -62.992562)
			(xy 17.134104 -62.940656) (xy 17.111168 -62.885283) (xy 17.095655 -62.82739) (xy 17.087832 -62.767968)
			(xy 5.490968 -62.767968) (xy 11.669014 -68.946014) (xy 11.675868 -68.953409) (xy 11.68361 -68.972008)
			(xy 11.684 -68.982082) (xy 11.684 -78.083918) (xy 11.684427 -78.093987) (xy 11.692146 -78.112586)
			(xy 11.698986 -78.119986) (xy 12.812014 -79.233014) (xy 12.819409 -79.239868) (xy 12.838008 -79.24761)
			(xy 12.848082 -79.248)
		)
		(stroke
			(width 0)
			(type solid)
		)
		(fill yes)
		(layer "B.Cu")
		(net "P3V3_STBY")
	)
	(gr_line
		(start 0 -69.193918)
		(end 0 -1.999996)
		(stroke
			(width 0.2)
			(type default)
		)
		(layer "In1.Cu")
	)
	(gr_arc
		(start 0 -69.193918)
		(mid 0.14254 -69.93562)
		(end 0.54991 -70.571614)
		(stroke
			(width 0.2)
			(type default)
		)
		(layer "In1.Cu")
	)
	(gr_poly
		(pts
			(xy 99.039934 -69.308726) (xy 99.049939 -69.308233) (xy 99.068424 -69.300568) (xy 99.082572 -69.286417)
			(xy 99.090234 -69.267931) (xy 99.090734 -69.257926) (xy 99.090734 -2.008378) (xy 99.090209 -1.952315)
			(xy 99.081828 -1.840503) (xy 99.065115 -1.72963) (xy 99.040163 -1.620317) (xy 99.007112 -1.513173)
			(xy 98.966147 -1.408799) (xy 98.917496 -1.307778) (xy 98.861432 -1.210675) (xy 98.798268 -1.118034)
			(xy 98.728358 -1.030371) (xy 98.652092 -0.948179) (xy 98.569897 -0.871915) (xy 98.482233 -0.802007)
			(xy 98.389589 -0.738846) (xy 98.292485 -0.682784) (xy 98.191463 -0.634136) (xy 98.087087 -0.593174)
			(xy 97.979943 -0.560126) (xy 97.870628 -0.535177) (xy 97.759755 -0.518467) (xy 97.647943 -0.510089)
			(xy 97.59188 -0.509524) (xy 84.637118 -0.509524) (xy 84.620862 -0.509524) (xy 84.620354 -0.509524)
			(xy 84.566389 -0.510014) (xy 84.458734 -0.51773) (xy 84.351904 -0.533104) (xy 84.246442 -0.556059)
			(xy 84.142887 -0.586478) (xy 84.041765 -0.624205) (xy 83.943591 -0.669049) (xy 83.848866 -0.720781)
			(xy 83.758071 -0.779137) (xy 83.671671 -0.843821) (xy 83.590104 -0.914502) (xy 83.513786 -0.990821)
			(xy 83.443106 -1.072389) (xy 83.378423 -1.158791) (xy 83.320068 -1.249586) (xy 83.268338 -1.344312)
			(xy 83.223496 -1.442487) (xy 83.18577 -1.54361) (xy 83.155353 -1.647166) (xy 83.1324 -1.752628) (xy 83.117027 -1.859458)
			(xy 83.109313 -1.967113) (xy 83.1088 -2.021078) (xy 83.1088 -2.021586) (xy 83.1088 -2.037842) (xy 83.1088 -5.06456)
			(xy 92.503995 -5.06456) (xy 92.503995 -4.93542) (xy 92.511945 -4.806525) (xy 92.527815 -4.678365)
			(xy 92.551544 -4.551424) (xy 92.583043 -4.426185) (xy 92.622192 -4.303122) (xy 92.668843 -4.182703)
			(xy 92.722818 -4.065384) (xy 92.783913 -3.95161) (xy 92.851896 -3.841813) (xy 92.92651 -3.73641)
			(xy 93.007471 -3.6358) (xy 93.094471 -3.540365) (xy 93.187182 -3.450466) (xy 93.285252 -3.366445)
			(xy 93.388307 -3.288621) (xy 93.495958 -3.217289) (xy 93.607797 -3.152719) (xy 93.723398 -3.095157)
			(xy 93.842323 -3.04482) (xy 93.964122 -3.0019) (xy 94.088332 -2.966559) (xy 94.214481 -2.938932)
			(xy 94.342093 -2.919123) (xy 94.470682 -2.907207) (xy 94.59976 -2.903231) (xy 94.728838 -2.907207)
			(xy 94.857427 -2.919123) (xy 94.985039 -2.938932) (xy 95.111188 -2.966559) (xy 95.235398 -3.0019)
			(xy 95.357197 -3.04482) (xy 95.476122 -3.095157) (xy 95.591723 -3.152719) (xy 95.703562 -3.217289)
			(xy 95.811213 -3.288621) (xy 95.914268 -3.366445) (xy 96.012338 -3.450466) (xy 96.105049 -3.540365)
			(xy 96.192049 -3.6358) (xy 96.27301 -3.73641) (xy 96.347624 -3.841813) (xy 96.415607 -3.95161) (xy 96.476702 -4.065384)
			(xy 96.530677 -4.182703) (xy 96.577328 -4.303122) (xy 96.616477 -4.426185) (xy 96.647976 -4.551424)
			(xy 96.671705 -4.678365) (xy 96.687575 -4.806525) (xy 96.695525 -4.93542) (xy 96.696022 -4.99999)
			(xy 96.695525 -5.06456) (xy 96.687575 -5.193455) (xy 96.671705 -5.321615) (xy 96.647976 -5.448556)
			(xy 96.616477 -5.573795) (xy 96.577328 -5.696858) (xy 96.530677 -5.817277) (xy 96.476702 -5.934596)
			(xy 96.415607 -6.04837) (xy 96.347624 -6.158167) (xy 96.27301 -6.26357) (xy 96.192049 -6.36418) (xy 96.105049 -6.459615)
			(xy 96.012338 -6.549514) (xy 95.914268 -6.633535) (xy 95.811213 -6.711359) (xy 95.703562 -6.782691)
			(xy 95.591723 -6.847261) (xy 95.476122 -6.904823) (xy 95.357197 -6.95516) (xy 95.235398 -6.99808)
			(xy 95.111188 -7.033421) (xy 94.985039 -7.061048) (xy 94.857427 -7.080857) (xy 94.728838 -7.092773)
			(xy 94.59976 -7.09675) (xy 94.470682 -7.092773) (xy 94.342093 -7.080857) (xy 94.214481 -7.061048)
			(xy 94.088332 -7.033421) (xy 93.964122 -6.99808) (xy 93.842323 -6.95516) (xy 93.723398 -6.904823)
			(xy 93.607797 -6.847261) (xy 93.495958 -6.782691) (xy 93.388307 -6.711359) (xy 93.285252 -6.633535)
			(xy 93.187182 -6.549514) (xy 93.094471 -6.459615) (xy 93.007471 -6.36418) (xy 92.92651 -6.26357)
			(xy 92.851896 -6.158167) (xy 92.783913 -6.04837) (xy 92.722818 -5.934596) (xy 92.668843 -5.817277)
			(xy 92.622192 -5.696858) (xy 92.583043 -5.573795) (xy 92.551544 -5.448556) (xy 92.527815 -5.321615)
			(xy 92.511945 -5.193455) (xy 92.503995 -5.06456) (xy 83.1088 -5.06456) (xy 83.1088 -47.75962) (xy 83.107784 -47.760636)
			(xy 83.107784 -48.899064) (xy 83.1088 -48.90008) (xy 83.1088 -69.257926) (xy 83.109293 -69.26793)
			(xy 83.116957 -69.286413) (xy 83.131109 -69.300558) (xy 83.149596 -69.308212) (xy 83.1596 -69.308726)
		)
		(stroke
			(width 0)
			(type solid)
		)
		(fill yes)
		(layer "In1.Cu")
		(net "GND_TDR")
	)
	(gr_poly
		(pts
			(xy 97.59188 -173.79188) (xy 97.647944 -173.791357) (xy 97.75976 -173.782979) (xy 97.870636 -173.766268)
			(xy 97.979954 -173.741319) (xy 98.087102 -173.70827) (xy 98.19148 -173.667306) (xy 98.292505 -173.618657)
			(xy 98.389613 -173.562594) (xy 98.482259 -173.499431) (xy 98.569925 -173.429521) (xy 98.652123 -173.353255)
			(xy 98.728391 -173.27106) (xy 98.798304 -173.183396) (xy 98.861469 -173.090751) (xy 98.917535 -172.993646)
			(xy 98.966188 -172.892622) (xy 99.007155 -172.788245) (xy 99.040207 -172.681099) (xy 99.06516 -172.571782)
			(xy 99.081874 -172.460905) (xy 99.090255 -172.34909) (xy 99.090734 -172.293026) (xy 99.090734 -69.867526)
			(xy 99.090251 -69.857512) (xy 99.082597 -69.839006) (xy 99.068445 -69.824836) (xy 99.049947 -69.817161)
			(xy 99.039934 -69.816726) (xy 83.1596 -69.816726) (xy 83.149581 -69.817146) (xy 83.131068 -69.824817)
			(xy 83.116902 -69.83899) (xy 83.109241 -69.857506) (xy 83.1088 -69.867526) (xy 83.1088 -80.392219)
			(xy 93.052633 -80.392219) (xy 93.052633 -80.306469) (xy 93.060545 -80.221086) (xy 93.076301 -80.136796)
			(xy 93.099768 -80.05432) (xy 93.130744 -79.974361) (xy 93.168966 -79.897601) (xy 93.214107 -79.824695)
			(xy 93.265783 -79.756266) (xy 93.323552 -79.692896) (xy 93.386922 -79.635127) (xy 93.455351 -79.583451)
			(xy 93.528257 -79.53831) (xy 93.605017 -79.500088) (xy 93.684976 -79.469112) (xy 93.767452 -79.445645)
			(xy 93.851742 -79.429889) (xy 93.937125 -79.421977) (xy 94.022875 -79.421977) (xy 94.108258 -79.429889)
			(xy 94.192548 -79.445645) (xy 94.275024 -79.469112) (xy 94.354983 -79.500088) (xy 94.431743 -79.53831)
			(xy 94.504649 -79.583451) (xy 94.573078 -79.635127) (xy 94.636448 -79.692896) (xy 94.694217 -79.756266)
			(xy 94.745893 -79.824695) (xy 94.791034 -79.897601) (xy 94.829256 -79.974361) (xy 94.860232 -80.05432)
			(xy 94.883699 -80.136796) (xy 94.899455 -80.221086) (xy 94.907367 -80.306469) (xy 94.907862 -80.349344)
			(xy 94.907367 -80.392219) (xy 95.592633 -80.392219) (xy 95.592633 -80.306469) (xy 95.600545 -80.221086)
			(xy 95.616301 -80.136796) (xy 95.639768 -80.05432) (xy 95.670744 -79.974361) (xy 95.708966 -79.897601)
			(xy 95.754107 -79.824695) (xy 95.805783 -79.756266) (xy 95.863552 -79.692896) (xy 95.926922 -79.635127)
			(xy 95.995351 -79.583451) (xy 96.068257 -79.53831) (xy 96.145017 -79.500088) (xy 96.224976 -79.469112)
			(xy 96.307452 -79.445645) (xy 96.391742 -79.429889) (xy 96.477125 -79.421977) (xy 96.562875 -79.421977)
			(xy 96.648258 -79.429889) (xy 96.732548 -79.445645) (xy 96.815024 -79.469112) (xy 96.894983 -79.500088)
			(xy 96.971743 -79.53831) (xy 97.044649 -79.583451) (xy 97.113078 -79.635127) (xy 97.176448 -79.692896)
			(xy 97.234217 -79.756266) (xy 97.285893 -79.824695) (xy 97.331034 -79.897601) (xy 97.369256 -79.974361)
			(xy 97.400232 -80.05432) (xy 97.423699 -80.136796) (xy 97.439455 -80.221086) (xy 97.447367 -80.306469)
			(xy 97.447862 -80.349344) (xy 97.447367 -80.392219) (xy 97.439455 -80.477602) (xy 97.423699 -80.561892)
			(xy 97.400232 -80.644368) (xy 97.369256 -80.724327) (xy 97.331034 -80.801087) (xy 97.285893 -80.873993)
			(xy 97.234217 -80.942422) (xy 97.176448 -81.005792) (xy 97.113078 -81.063561) (xy 97.044649 -81.115237)
			(xy 96.971743 -81.160378) (xy 96.894983 -81.1986) (xy 96.815024 -81.229576) (xy 96.732548 -81.253043)
			(xy 96.648258 -81.268799) (xy 96.562875 -81.276711) (xy 96.477125 -81.276711) (xy 96.391742 -81.268799)
			(xy 96.307452 -81.253043) (xy 96.224976 -81.229576) (xy 96.145017 -81.1986) (xy 96.068257 -81.160378)
			(xy 95.995351 -81.115237) (xy 95.926922 -81.063561) (xy 95.863552 -81.005792) (xy 95.805783 -80.942422)
			(xy 95.754107 -80.873993) (xy 95.708966 -80.801087) (xy 95.670744 -80.724327) (xy 95.639768 -80.644368)
			(xy 95.616301 -80.561892) (xy 95.600545 -80.477602) (xy 95.592633 -80.392219) (xy 94.907367 -80.392219)
			(xy 94.899455 -80.477602) (xy 94.883699 -80.561892) (xy 94.860232 -80.644368) (xy 94.829256 -80.724327)
			(xy 94.791034 -80.801087) (xy 94.745893 -80.873993) (xy 94.694217 -80.942422) (xy 94.636448 -81.005792)
			(xy 94.573078 -81.063561) (xy 94.504649 -81.115237) (xy 94.431743 -81.160378) (xy 94.354983 -81.1986)
			(xy 94.275024 -81.229576) (xy 94.192548 -81.253043) (xy 94.108258 -81.268799) (xy 94.022875 -81.276711)
			(xy 93.937125 -81.276711) (xy 93.851742 -81.268799) (xy 93.767452 -81.253043) (xy 93.684976 -81.229576)
			(xy 93.605017 -81.1986) (xy 93.528257 -81.160378) (xy 93.455351 -81.115237) (xy 93.386922 -81.063561)
			(xy 93.323552 -81.005792) (xy 93.265783 -80.942422) (xy 93.214107 -80.873993) (xy 93.168966 -80.801087)
			(xy 93.130744 -80.724327) (xy 93.099768 -80.644368) (xy 93.076301 -80.561892) (xy 93.060545 -80.477602)
			(xy 93.052633 -80.392219) (xy 83.1088 -80.392219) (xy 83.1088 -84.26958) (xy 94.627192 -84.26958)
			(xy 94.627192 -83.65744) (xy 94.627647 -83.645359) (xy 94.635103 -83.622378) (xy 94.649299 -83.602827)
			(xy 94.668842 -83.588622) (xy 94.69182 -83.581153) (xy 94.7039 -83.580732) (xy 95.80118 -83.580732)
			(xy 95.813266 -83.58113) (xy 95.836254 -83.588597) (xy 95.855808 -83.602806) (xy 95.870012 -83.622363)
			(xy 95.877473 -83.645354) (xy 95.877888 -83.65744) (xy 95.877888 -84.26958) (xy 95.87747 -84.281664)
			(xy 95.870005 -84.304649) (xy 95.855801 -84.324201) (xy 95.836249 -84.338405) (xy 95.813264 -84.34587)
			(xy 95.80118 -84.346288) (xy 94.7039 -84.346288) (xy 94.691815 -84.345887) (xy 94.668829 -84.338417)
			(xy 94.649277 -84.324209) (xy 94.635074 -84.304653) (xy 94.62761 -84.281665) (xy 94.627192 -84.26958)
			(xy 83.1088 -84.26958) (xy 83.1088 -86.742219) (xy 93.052633 -86.742219) (xy 93.052633 -86.656469)
			(xy 93.060545 -86.571086) (xy 93.076301 -86.486796) (xy 93.099768 -86.40432) (xy 93.130744 -86.324361)
			(xy 93.168966 -86.247601) (xy 93.214107 -86.174695) (xy 93.265783 -86.106266) (xy 93.323552 -86.042896)
			(xy 93.386922 -85.985127) (xy 93.455351 -85.933451) (xy 93.528257 -85.88831) (xy 93.605017 -85.850088)
			(xy 93.684976 -85.819112) (xy 93.767452 -85.795645) (xy 93.851742 -85.779889) (xy 93.937125 -85.771977)
			(xy 94.022875 -85.771977) (xy 94.108258 -85.779889) (xy 94.192548 -85.795645) (xy 94.275024 -85.819112)
			(xy 94.354983 -85.850088) (xy 94.431743 -85.88831) (xy 94.504649 -85.933451) (xy 94.573078 -85.985127)
			(xy 94.636448 -86.042896) (xy 94.694217 -86.106266) (xy 94.745893 -86.174695) (xy 94.791034 -86.247601)
			(xy 94.829256 -86.324361) (xy 94.860232 -86.40432) (xy 94.883699 -86.486796) (xy 94.899455 -86.571086)
			(xy 94.907367 -86.656469) (xy 94.907862 -86.699344) (xy 94.907367 -86.742219) (xy 95.592633 -86.742219)
			(xy 95.592633 -86.656469) (xy 95.600545 -86.571086) (xy 95.616301 -86.486796) (xy 95.639768 -86.40432)
			(xy 95.670744 -86.324361) (xy 95.708966 -86.247601) (xy 95.754107 -86.174695) (xy 95.805783 -86.106266)
			(xy 95.863552 -86.042896) (xy 95.926922 -85.985127) (xy 95.995351 -85.933451) (xy 96.068257 -85.88831)
			(xy 96.145017 -85.850088) (xy 96.224976 -85.819112) (xy 96.307452 -85.795645) (xy 96.391742 -85.779889)
			(xy 96.477125 -85.771977) (xy 96.562875 -85.771977) (xy 96.648258 -85.779889) (xy 96.732548 -85.795645)
			(xy 96.815024 -85.819112) (xy 96.894983 -85.850088) (xy 96.971743 -85.88831) (xy 97.044649 -85.933451)
			(xy 97.113078 -85.985127) (xy 97.176448 -86.042896) (xy 97.234217 -86.106266) (xy 97.285893 -86.174695)
			(xy 97.331034 -86.247601) (xy 97.369256 -86.324361) (xy 97.400232 -86.40432) (xy 97.423699 -86.486796)
			(xy 97.439455 -86.571086) (xy 97.447367 -86.656469) (xy 97.447862 -86.699344) (xy 97.447367 -86.742219)
			(xy 97.439455 -86.827602) (xy 97.423699 -86.911892) (xy 97.400232 -86.994368) (xy 97.369256 -87.074327)
			(xy 97.331034 -87.151087) (xy 97.285893 -87.223993) (xy 97.234217 -87.292422) (xy 97.176448 -87.355792)
			(xy 97.113078 -87.413561) (xy 97.044649 -87.465237) (xy 96.971743 -87.510378) (xy 96.894983 -87.5486)
			(xy 96.815024 -87.579576) (xy 96.732548 -87.603043) (xy 96.648258 -87.618799) (xy 96.562875 -87.626711)
			(xy 96.477125 -87.626711) (xy 96.391742 -87.618799) (xy 96.307452 -87.603043) (xy 96.224976 -87.579576)
			(xy 96.145017 -87.5486) (xy 96.068257 -87.510378) (xy 95.995351 -87.465237) (xy 95.926922 -87.413561)
			(xy 95.863552 -87.355792) (xy 95.805783 -87.292422) (xy 95.754107 -87.223993) (xy 95.708966 -87.151087)
			(xy 95.670744 -87.074327) (xy 95.639768 -86.994368) (xy 95.616301 -86.911892) (xy 95.600545 -86.827602)
			(xy 95.592633 -86.742219) (xy 94.907367 -86.742219) (xy 94.899455 -86.827602) (xy 94.883699 -86.911892)
			(xy 94.860232 -86.994368) (xy 94.829256 -87.074327) (xy 94.791034 -87.151087) (xy 94.745893 -87.223993)
			(xy 94.694217 -87.292422) (xy 94.636448 -87.355792) (xy 94.573078 -87.413561) (xy 94.504649 -87.465237)
			(xy 94.431743 -87.510378) (xy 94.354983 -87.5486) (xy 94.275024 -87.579576) (xy 94.192548 -87.603043)
			(xy 94.108258 -87.618799) (xy 94.022875 -87.626711) (xy 93.937125 -87.626711) (xy 93.851742 -87.618799)
			(xy 93.767452 -87.603043) (xy 93.684976 -87.579576) (xy 93.605017 -87.5486) (xy 93.528257 -87.510378)
			(xy 93.455351 -87.465237) (xy 93.386922 -87.413561) (xy 93.323552 -87.355792) (xy 93.265783 -87.292422)
			(xy 93.214107 -87.223993) (xy 93.168966 -87.151087) (xy 93.130744 -87.074327) (xy 93.099768 -86.994368)
			(xy 93.076301 -86.911892) (xy 93.060545 -86.827602) (xy 93.052633 -86.742219) (xy 83.1088 -86.742219)
			(xy 83.1088 -106.760975) (xy 85.559633 -106.760975) (xy 85.559633 -106.675225) (xy 85.567545 -106.589842)
			(xy 85.583301 -106.505552) (xy 85.606768 -106.423076) (xy 85.637744 -106.343117) (xy 85.675966 -106.266357)
			(xy 85.721107 -106.193451) (xy 85.772783 -106.125022) (xy 85.830552 -106.061652) (xy 85.893922 -106.003883)
			(xy 85.962351 -105.952207) (xy 86.035257 -105.907066) (xy 86.112017 -105.868844) (xy 86.191976 -105.837868)
			(xy 86.274452 -105.814401) (xy 86.358742 -105.798645) (xy 86.444125 -105.790733) (xy 86.529875 -105.790733)
			(xy 86.615258 -105.798645) (xy 86.699548 -105.814401) (xy 86.782024 -105.837868) (xy 86.861983 -105.868844)
			(xy 86.938743 -105.907066) (xy 87.011649 -105.952207) (xy 87.080078 -106.003883) (xy 87.143448 -106.061652)
			(xy 87.201217 -106.125022) (xy 87.252893 -106.193451) (xy 87.298034 -106.266357) (xy 87.336256 -106.343117)
			(xy 87.367232 -106.423076) (xy 87.390699 -106.505552) (xy 87.406455 -106.589842) (xy 87.414367 -106.675225)
			(xy 87.414862 -106.7181) (xy 87.414367 -106.760975) (xy 88.099633 -106.760975) (xy 88.099633 -106.675225)
			(xy 88.107545 -106.589842) (xy 88.123301 -106.505552) (xy 88.146768 -106.423076) (xy 88.177744 -106.343117)
			(xy 88.215966 -106.266357) (xy 88.261107 -106.193451) (xy 88.312783 -106.125022) (xy 88.370552 -106.061652)
			(xy 88.433922 -106.003883) (xy 88.502351 -105.952207) (xy 88.575257 -105.907066) (xy 88.652017 -105.868844)
			(xy 88.731976 -105.837868) (xy 88.814452 -105.814401) (xy 88.898742 -105.798645) (xy 88.984125 -105.790733)
			(xy 89.069875 -105.790733) (xy 89.155258 -105.798645) (xy 89.239548 -105.814401) (xy 89.322024 -105.837868)
			(xy 89.401983 -105.868844) (xy 89.478743 -105.907066) (xy 89.551649 -105.952207) (xy 89.620078 -106.003883)
			(xy 89.683448 -106.061652) (xy 89.741217 -106.125022) (xy 89.792893 -106.193451) (xy 89.838034 -106.266357)
			(xy 89.876256 -106.343117) (xy 89.907232 -106.423076) (xy 89.930699 -106.505552) (xy 89.946455 -106.589842)
			(xy 89.954367 -106.675225) (xy 89.954862 -106.7181) (xy 89.954367 -106.760975) (xy 89.946455 -106.846358)
			(xy 89.930699 -106.930648) (xy 89.907232 -107.013124) (xy 89.876256 -107.093083) (xy 89.838034 -107.169843)
			(xy 89.792893 -107.242749) (xy 89.741217 -107.311178) (xy 89.683448 -107.374548) (xy 89.620078 -107.432317)
			(xy 89.551649 -107.483993) (xy 89.478743 -107.529134) (xy 89.401983 -107.567356) (xy 89.322024 -107.598332)
			(xy 89.239548 -107.621799) (xy 89.155258 -107.637555) (xy 89.069875 -107.645467) (xy 88.984125 -107.645467)
			(xy 88.898742 -107.637555) (xy 88.814452 -107.621799) (xy 88.731976 -107.598332) (xy 88.652017 -107.567356)
			(xy 88.575257 -107.529134) (xy 88.502351 -107.483993) (xy 88.433922 -107.432317) (xy 88.370552 -107.374548)
			(xy 88.312783 -107.311178) (xy 88.261107 -107.242749) (xy 88.215966 -107.169843) (xy 88.177744 -107.093083)
			(xy 88.146768 -107.013124) (xy 88.123301 -106.930648) (xy 88.107545 -106.846358) (xy 88.099633 -106.760975)
			(xy 87.414367 -106.760975) (xy 87.406455 -106.846358) (xy 87.390699 -106.930648) (xy 87.367232 -107.013124)
			(xy 87.336256 -107.093083) (xy 87.298034 -107.169843) (xy 87.252893 -107.242749) (xy 87.201217 -107.311178)
			(xy 87.143448 -107.374548) (xy 87.080078 -107.432317) (xy 87.011649 -107.483993) (xy 86.938743 -107.529134)
			(xy 86.861983 -107.567356) (xy 86.782024 -107.598332) (xy 86.699548 -107.621799) (xy 86.615258 -107.637555)
			(xy 86.529875 -107.645467) (xy 86.444125 -107.645467) (xy 86.358742 -107.637555) (xy 86.274452 -107.621799)
			(xy 86.191976 -107.598332) (xy 86.112017 -107.567356) (xy 86.035257 -107.529134) (xy 85.962351 -107.483993)
			(xy 85.893922 -107.432317) (xy 85.830552 -107.374548) (xy 85.772783 -107.311178) (xy 85.721107 -107.242749)
			(xy 85.675966 -107.169843) (xy 85.637744 -107.093083) (xy 85.606768 -107.013124) (xy 85.583301 -106.930648)
			(xy 85.567545 -106.846358) (xy 85.559633 -106.760975) (xy 83.1088 -106.760975) (xy 83.1088 -110.638336)
			(xy 87.134192 -110.638336) (xy 87.134192 -110.026196) (xy 87.134661 -110.014121) (xy 87.142124 -109.991154)
			(xy 87.15632 -109.971617) (xy 87.175858 -109.957423) (xy 87.198825 -109.94996) (xy 87.2109 -109.949488)
			(xy 88.30818 -109.949488) (xy 88.320261 -109.94993) (xy 88.343243 -109.957391) (xy 88.362793 -109.97159)
			(xy 88.376998 -109.991136) (xy 88.384466 -110.014115) (xy 88.384888 -110.026196) (xy 88.384888 -110.638336)
			(xy 88.384466 -110.650414) (xy 88.376991 -110.673386) (xy 88.362785 -110.692924) (xy 88.343236 -110.707117)
			(xy 88.320259 -110.714575) (xy 88.30818 -110.715044) (xy 87.2109 -110.715044) (xy 87.198829 -110.714536)
			(xy 87.175868 -110.707078) (xy 87.156334 -110.692892) (xy 87.142138 -110.673364) (xy 87.134669 -110.650407)
			(xy 87.134192 -110.638336) (xy 83.1088 -110.638336) (xy 83.1088 -113.110975) (xy 85.559633 -113.110975)
			(xy 85.559633 -113.025225) (xy 85.567545 -112.939842) (xy 85.583301 -112.855552) (xy 85.606768 -112.773076)
			(xy 85.637744 -112.693117) (xy 85.675966 -112.616357) (xy 85.721107 -112.543451) (xy 85.772783 -112.475022)
			(xy 85.830552 -112.411652) (xy 85.893922 -112.353883) (xy 85.962351 -112.302207) (xy 86.035257 -112.257066)
			(xy 86.112017 -112.218844) (xy 86.191976 -112.187868) (xy 86.274452 -112.164401) (xy 86.358742 -112.148645)
			(xy 86.444125 -112.140733) (xy 86.529875 -112.140733) (xy 86.615258 -112.148645) (xy 86.699548 -112.164401)
			(xy 86.782024 -112.187868) (xy 86.861983 -112.218844) (xy 86.938743 -112.257066) (xy 87.011649 -112.302207)
			(xy 87.080078 -112.353883) (xy 87.143448 -112.411652) (xy 87.201217 -112.475022) (xy 87.252893 -112.543451)
			(xy 87.298034 -112.616357) (xy 87.336256 -112.693117) (xy 87.367232 -112.773076) (xy 87.390699 -112.855552)
			(xy 87.406455 -112.939842) (xy 87.414367 -113.025225) (xy 87.414862 -113.0681) (xy 87.414367 -113.110975)
			(xy 88.099633 -113.110975) (xy 88.099633 -113.025225) (xy 88.107545 -112.939842) (xy 88.123301 -112.855552)
			(xy 88.146768 -112.773076) (xy 88.177744 -112.693117) (xy 88.215966 -112.616357) (xy 88.261107 -112.543451)
			(xy 88.312783 -112.475022) (xy 88.370552 -112.411652) (xy 88.433922 -112.353883) (xy 88.502351 -112.302207)
			(xy 88.575257 -112.257066) (xy 88.652017 -112.218844) (xy 88.731976 -112.187868) (xy 88.814452 -112.164401)
			(xy 88.898742 -112.148645) (xy 88.984125 -112.140733) (xy 89.069875 -112.140733) (xy 89.155258 -112.148645)
			(xy 89.239548 -112.164401) (xy 89.322024 -112.187868) (xy 89.401983 -112.218844) (xy 89.478743 -112.257066)
			(xy 89.551649 -112.302207) (xy 89.620078 -112.353883) (xy 89.683448 -112.411652) (xy 89.741217 -112.475022)
			(xy 89.792893 -112.543451) (xy 89.838034 -112.616357) (xy 89.876256 -112.693117) (xy 89.907232 -112.773076)
			(xy 89.930699 -112.855552) (xy 89.946455 -112.939842) (xy 89.954367 -113.025225) (xy 89.954862 -113.0681)
			(xy 89.954367 -113.110975) (xy 89.946455 -113.196358) (xy 89.930699 -113.280648) (xy 89.907232 -113.363124)
			(xy 89.876256 -113.443083) (xy 89.838034 -113.519843) (xy 89.792893 -113.592749) (xy 89.741217 -113.661178)
			(xy 89.683448 -113.724548) (xy 89.620078 -113.782317) (xy 89.551649 -113.833993) (xy 89.478743 -113.879134)
			(xy 89.401983 -113.917356) (xy 89.322024 -113.948332) (xy 89.239548 -113.971799) (xy 89.155258 -113.987555)
			(xy 89.069875 -113.995467) (xy 88.984125 -113.995467) (xy 88.898742 -113.987555) (xy 88.814452 -113.971799)
			(xy 88.731976 -113.948332) (xy 88.652017 -113.917356) (xy 88.575257 -113.879134) (xy 88.502351 -113.833993)
			(xy 88.433922 -113.782317) (xy 88.370552 -113.724548) (xy 88.312783 -113.661178) (xy 88.261107 -113.592749)
			(xy 88.215966 -113.519843) (xy 88.177744 -113.443083) (xy 88.146768 -113.363124) (xy 88.123301 -113.280648)
			(xy 88.107545 -113.196358) (xy 88.099633 -113.110975) (xy 87.414367 -113.110975) (xy 87.406455 -113.196358)
			(xy 87.390699 -113.280648) (xy 87.367232 -113.363124) (xy 87.336256 -113.443083) (xy 87.298034 -113.519843)
			(xy 87.252893 -113.592749) (xy 87.201217 -113.661178) (xy 87.143448 -113.724548) (xy 87.080078 -113.782317)
			(xy 87.011649 -113.833993) (xy 86.938743 -113.879134) (xy 86.861983 -113.917356) (xy 86.782024 -113.948332)
			(xy 86.699548 -113.971799) (xy 86.615258 -113.987555) (xy 86.529875 -113.995467) (xy 86.444125 -113.995467)
			(xy 86.358742 -113.987555) (xy 86.274452 -113.971799) (xy 86.191976 -113.948332) (xy 86.112017 -113.917356)
			(xy 86.035257 -113.879134) (xy 85.962351 -113.833993) (xy 85.893922 -113.782317) (xy 85.830552 -113.724548)
			(xy 85.772783 -113.661178) (xy 85.721107 -113.592749) (xy 85.675966 -113.519843) (xy 85.637744 -113.443083)
			(xy 85.606768 -113.363124) (xy 85.583301 -113.280648) (xy 85.567545 -113.196358) (xy 85.559633 -113.110975)
			(xy 83.1088 -113.110975) (xy 83.1088 -151.769775) (xy 85.559633 -151.769775) (xy 85.559633 -151.684025)
			(xy 85.567545 -151.598642) (xy 85.583301 -151.514352) (xy 85.606768 -151.431876) (xy 85.637744 -151.351917)
			(xy 85.675966 -151.275157) (xy 85.721107 -151.202251) (xy 85.772783 -151.133822) (xy 85.830552 -151.070452)
			(xy 85.893922 -151.012683) (xy 85.962351 -150.961007) (xy 86.035257 -150.915866) (xy 86.112017 -150.877644)
			(xy 86.191976 -150.846668) (xy 86.274452 -150.823201) (xy 86.358742 -150.807445) (xy 86.444125 -150.799533)
			(xy 86.529875 -150.799533) (xy 86.615258 -150.807445) (xy 86.699548 -150.823201) (xy 86.782024 -150.846668)
			(xy 86.861983 -150.877644) (xy 86.938743 -150.915866) (xy 87.011649 -150.961007) (xy 87.080078 -151.012683)
			(xy 87.143448 -151.070452) (xy 87.201217 -151.133822) (xy 87.252893 -151.202251) (xy 87.298034 -151.275157)
			(xy 87.336256 -151.351917) (xy 87.367232 -151.431876) (xy 87.390699 -151.514352) (xy 87.406455 -151.598642)
			(xy 87.414367 -151.684025) (xy 87.414862 -151.7269) (xy 87.414367 -151.769775) (xy 88.099633 -151.769775)
			(xy 88.099633 -151.684025) (xy 88.107545 -151.598642) (xy 88.123301 -151.514352) (xy 88.146768 -151.431876)
			(xy 88.177744 -151.351917) (xy 88.215966 -151.275157) (xy 88.261107 -151.202251) (xy 88.312783 -151.133822)
			(xy 88.370552 -151.070452) (xy 88.433922 -151.012683) (xy 88.502351 -150.961007) (xy 88.575257 -150.915866)
			(xy 88.652017 -150.877644) (xy 88.731976 -150.846668) (xy 88.814452 -150.823201) (xy 88.898742 -150.807445)
			(xy 88.984125 -150.799533) (xy 89.069875 -150.799533) (xy 89.155258 -150.807445) (xy 89.239548 -150.823201)
			(xy 89.322024 -150.846668) (xy 89.401983 -150.877644) (xy 89.478743 -150.915866) (xy 89.551649 -150.961007)
			(xy 89.620078 -151.012683) (xy 89.683448 -151.070452) (xy 89.741217 -151.133822) (xy 89.792893 -151.202251)
			(xy 89.838034 -151.275157) (xy 89.876256 -151.351917) (xy 89.907232 -151.431876) (xy 89.930699 -151.514352)
			(xy 89.946455 -151.598642) (xy 89.954367 -151.684025) (xy 89.954862 -151.7269) (xy 89.954367 -151.769775)
			(xy 93.052633 -151.769775) (xy 93.052633 -151.684025) (xy 93.060545 -151.598642) (xy 93.076301 -151.514352)
			(xy 93.099768 -151.431876) (xy 93.130744 -151.351917) (xy 93.168966 -151.275157) (xy 93.214107 -151.202251)
			(xy 93.265783 -151.133822) (xy 93.323552 -151.070452) (xy 93.386922 -151.012683) (xy 93.455351 -150.961007)
			(xy 93.528257 -150.915866) (xy 93.605017 -150.877644) (xy 93.684976 -150.846668) (xy 93.767452 -150.823201)
			(xy 93.851742 -150.807445) (xy 93.937125 -150.799533) (xy 94.022875 -150.799533) (xy 94.108258 -150.807445)
			(xy 94.192548 -150.823201) (xy 94.275024 -150.846668) (xy 94.354983 -150.877644) (xy 94.431743 -150.915866)
			(xy 94.504649 -150.961007) (xy 94.573078 -151.012683) (xy 94.636448 -151.070452) (xy 94.694217 -151.133822)
			(xy 94.745893 -151.202251) (xy 94.791034 -151.275157) (xy 94.829256 -151.351917) (xy 94.860232 -151.431876)
			(xy 94.883699 -151.514352) (xy 94.899455 -151.598642) (xy 94.907367 -151.684025) (xy 94.907862 -151.7269)
			(xy 94.907367 -151.769775) (xy 95.592633 -151.769775) (xy 95.592633 -151.684025) (xy 95.600545 -151.598642)
			(xy 95.616301 -151.514352) (xy 95.639768 -151.431876) (xy 95.670744 -151.351917) (xy 95.708966 -151.275157)
			(xy 95.754107 -151.202251) (xy 95.805783 -151.133822) (xy 95.863552 -151.070452) (xy 95.926922 -151.012683)
			(xy 95.995351 -150.961007) (xy 96.068257 -150.915866) (xy 96.145017 -150.877644) (xy 96.224976 -150.846668)
			(xy 96.307452 -150.823201) (xy 96.391742 -150.807445) (xy 96.477125 -150.799533) (xy 96.562875 -150.799533)
			(xy 96.648258 -150.807445) (xy 96.732548 -150.823201) (xy 96.815024 -150.846668) (xy 96.894983 -150.877644)
			(xy 96.971743 -150.915866) (xy 97.044649 -150.961007) (xy 97.113078 -151.012683) (xy 97.176448 -151.070452)
			(xy 97.234217 -151.133822) (xy 97.285893 -151.202251) (xy 97.331034 -151.275157) (xy 97.369256 -151.351917)
			(xy 97.400232 -151.431876) (xy 97.423699 -151.514352) (xy 97.439455 -151.598642) (xy 97.447367 -151.684025)
			(xy 97.447862 -151.7269) (xy 97.447367 -151.769775) (xy 97.439455 -151.855158) (xy 97.423699 -151.939448)
			(xy 97.400232 -152.021924) (xy 97.369256 -152.101883) (xy 97.331034 -152.178643) (xy 97.285893 -152.251549)
			(xy 97.234217 -152.319978) (xy 97.176448 -152.383348) (xy 97.113078 -152.441117) (xy 97.044649 -152.492793)
			(xy 96.971743 -152.537934) (xy 96.894983 -152.576156) (xy 96.815024 -152.607132) (xy 96.732548 -152.630599)
			(xy 96.648258 -152.646355) (xy 96.562875 -152.654267) (xy 96.477125 -152.654267) (xy 96.391742 -152.646355)
			(xy 96.307452 -152.630599) (xy 96.224976 -152.607132) (xy 96.145017 -152.576156) (xy 96.068257 -152.537934)
			(xy 95.995351 -152.492793) (xy 95.926922 -152.441117) (xy 95.863552 -152.383348) (xy 95.805783 -152.319978)
			(xy 95.754107 -152.251549) (xy 95.708966 -152.178643) (xy 95.670744 -152.101883) (xy 95.639768 -152.021924)
			(xy 95.616301 -151.939448) (xy 95.600545 -151.855158) (xy 95.592633 -151.769775) (xy 94.907367 -151.769775)
			(xy 94.899455 -151.855158) (xy 94.883699 -151.939448) (xy 94.860232 -152.021924) (xy 94.829256 -152.101883)
			(xy 94.791034 -152.178643) (xy 94.745893 -152.251549) (xy 94.694217 -152.319978) (xy 94.636448 -152.383348)
			(xy 94.573078 -152.441117) (xy 94.504649 -152.492793) (xy 94.431743 -152.537934) (xy 94.354983 -152.576156)
			(xy 94.275024 -152.607132) (xy 94.192548 -152.630599) (xy 94.108258 -152.646355) (xy 94.022875 -152.654267)
			(xy 93.937125 -152.654267) (xy 93.851742 -152.646355) (xy 93.767452 -152.630599) (xy 93.684976 -152.607132)
			(xy 93.605017 -152.576156) (xy 93.528257 -152.537934) (xy 93.455351 -152.492793) (xy 93.386922 -152.441117)
			(xy 93.323552 -152.383348) (xy 93.265783 -152.319978) (xy 93.214107 -152.251549) (xy 93.168966 -152.178643)
			(xy 93.130744 -152.101883) (xy 93.099768 -152.021924) (xy 93.076301 -151.939448) (xy 93.060545 -151.855158)
			(xy 93.052633 -151.769775) (xy 89.954367 -151.769775) (xy 89.946455 -151.855158) (xy 89.930699 -151.939448)
			(xy 89.907232 -152.021924) (xy 89.876256 -152.101883) (xy 89.838034 -152.178643) (xy 89.792893 -152.251549)
			(xy 89.741217 -152.319978) (xy 89.683448 -152.383348) (xy 89.620078 -152.441117) (xy 89.551649 -152.492793)
			(xy 89.478743 -152.537934) (xy 89.401983 -152.576156) (xy 89.322024 -152.607132) (xy 89.239548 -152.630599)
			(xy 89.155258 -152.646355) (xy 89.069875 -152.654267) (xy 88.984125 -152.654267) (xy 88.898742 -152.646355)
			(xy 88.814452 -152.630599) (xy 88.731976 -152.607132) (xy 88.652017 -152.576156) (xy 88.575257 -152.537934)
			(xy 88.502351 -152.492793) (xy 88.433922 -152.441117) (xy 88.370552 -152.383348) (xy 88.312783 -152.319978)
			(xy 88.261107 -152.251549) (xy 88.215966 -152.178643) (xy 88.177744 -152.101883) (xy 88.146768 -152.021924)
			(xy 88.123301 -151.939448) (xy 88.107545 -151.855158) (xy 88.099633 -151.769775) (xy 87.414367 -151.769775)
			(xy 87.406455 -151.855158) (xy 87.390699 -151.939448) (xy 87.367232 -152.021924) (xy 87.336256 -152.101883)
			(xy 87.298034 -152.178643) (xy 87.252893 -152.251549) (xy 87.201217 -152.319978) (xy 87.143448 -152.383348)
			(xy 87.080078 -152.441117) (xy 87.011649 -152.492793) (xy 86.938743 -152.537934) (xy 86.861983 -152.576156)
			(xy 86.782024 -152.607132) (xy 86.699548 -152.630599) (xy 86.615258 -152.646355) (xy 86.529875 -152.654267)
			(xy 86.444125 -152.654267) (xy 86.358742 -152.646355) (xy 86.274452 -152.630599) (xy 86.191976 -152.607132)
			(xy 86.112017 -152.576156) (xy 86.035257 -152.537934) (xy 85.962351 -152.492793) (xy 85.893922 -152.441117)
			(xy 85.830552 -152.383348) (xy 85.772783 -152.319978) (xy 85.721107 -152.251549) (xy 85.675966 -152.178643)
			(xy 85.637744 -152.101883) (xy 85.606768 -152.021924) (xy 85.583301 -151.939448) (xy 85.567545 -151.855158)
			(xy 85.559633 -151.769775) (xy 83.1088 -151.769775) (xy 83.1088 -154.768804) (xy 87.129112 -154.768804)
			(xy 87.129112 -154.156664) (xy 87.129534 -154.144586) (xy 87.137009 -154.121614) (xy 87.151215 -154.102076)
			(xy 87.170764 -154.087883) (xy 87.193741 -154.080425) (xy 87.20582 -154.079956) (xy 88.3031 -154.079956)
			(xy 88.315171 -154.080464) (xy 88.338132 -154.087922) (xy 88.357666 -154.102108) (xy 88.371862 -154.121636)
			(xy 88.379331 -154.144593) (xy 88.379808 -154.156664) (xy 88.379808 -154.768804) (xy 94.622112 -154.768804)
			(xy 94.622112 -154.156664) (xy 94.622534 -154.144586) (xy 94.630009 -154.121614) (xy 94.644215 -154.102076)
			(xy 94.663764 -154.087883) (xy 94.686741 -154.080425) (xy 94.69882 -154.079956) (xy 95.7961 -154.079956)
			(xy 95.808171 -154.080464) (xy 95.831132 -154.087922) (xy 95.850666 -154.102108) (xy 95.864862 -154.121636)
			(xy 95.872331 -154.144593) (xy 95.872808 -154.156664) (xy 95.872808 -154.768804) (xy 95.872339 -154.780879)
			(xy 95.864876 -154.803846) (xy 95.85068 -154.823383) (xy 95.831142 -154.837577) (xy 95.808175 -154.84504)
			(xy 95.7961 -154.845512) (xy 94.69882 -154.845512) (xy 94.686739 -154.84507) (xy 94.663757 -154.837609)
			(xy 94.644207 -154.82341) (xy 94.630002 -154.803864) (xy 94.622534 -154.780885) (xy 94.622112 -154.768804)
			(xy 88.379808 -154.768804) (xy 88.379339 -154.780879) (xy 88.371876 -154.803846) (xy 88.35768 -154.823383)
			(xy 88.338142 -154.837577) (xy 88.315175 -154.84504) (xy 88.3031 -154.845512) (xy 87.20582 -154.845512)
			(xy 87.193739 -154.84507) (xy 87.170757 -154.837609) (xy 87.151207 -154.82341) (xy 87.137002 -154.803864)
			(xy 87.129534 -154.780885) (xy 87.129112 -154.768804) (xy 83.1088 -154.768804) (xy 83.1088 -158.119775)
			(xy 85.559633 -158.119775) (xy 85.559633 -158.034025) (xy 85.567545 -157.948642) (xy 85.583301 -157.864352)
			(xy 85.606768 -157.781876) (xy 85.637744 -157.701917) (xy 85.675966 -157.625157) (xy 85.721107 -157.552251)
			(xy 85.772783 -157.483822) (xy 85.830552 -157.420452) (xy 85.893922 -157.362683) (xy 85.962351 -157.311007)
			(xy 86.035257 -157.265866) (xy 86.112017 -157.227644) (xy 86.191976 -157.196668) (xy 86.274452 -157.173201)
			(xy 86.358742 -157.157445) (xy 86.444125 -157.149533) (xy 86.529875 -157.149533) (xy 86.615258 -157.157445)
			(xy 86.699548 -157.173201) (xy 86.782024 -157.196668) (xy 86.861983 -157.227644) (xy 86.938743 -157.265866)
			(xy 87.011649 -157.311007) (xy 87.080078 -157.362683) (xy 87.143448 -157.420452) (xy 87.201217 -157.483822)
			(xy 87.252893 -157.552251) (xy 87.298034 -157.625157) (xy 87.336256 -157.701917) (xy 87.367232 -157.781876)
			(xy 87.390699 -157.864352) (xy 87.406455 -157.948642) (xy 87.414367 -158.034025) (xy 87.414862 -158.0769)
			(xy 87.414367 -158.119775) (xy 88.099633 -158.119775) (xy 88.099633 -158.034025) (xy 88.107545 -157.948642)
			(xy 88.123301 -157.864352) (xy 88.146768 -157.781876) (xy 88.177744 -157.701917) (xy 88.215966 -157.625157)
			(xy 88.261107 -157.552251) (xy 88.312783 -157.483822) (xy 88.370552 -157.420452) (xy 88.433922 -157.362683)
			(xy 88.502351 -157.311007) (xy 88.575257 -157.265866) (xy 88.652017 -157.227644) (xy 88.731976 -157.196668)
			(xy 88.814452 -157.173201) (xy 88.898742 -157.157445) (xy 88.984125 -157.149533) (xy 89.069875 -157.149533)
			(xy 89.155258 -157.157445) (xy 89.239548 -157.173201) (xy 89.322024 -157.196668) (xy 89.401983 -157.227644)
			(xy 89.478743 -157.265866) (xy 89.551649 -157.311007) (xy 89.620078 -157.362683) (xy 89.683448 -157.420452)
			(xy 89.741217 -157.483822) (xy 89.792893 -157.552251) (xy 89.838034 -157.625157) (xy 89.876256 -157.701917)
			(xy 89.907232 -157.781876) (xy 89.930699 -157.864352) (xy 89.946455 -157.948642) (xy 89.954367 -158.034025)
			(xy 89.954862 -158.0769) (xy 89.954367 -158.119775) (xy 93.052633 -158.119775) (xy 93.052633 -158.034025)
			(xy 93.060545 -157.948642) (xy 93.076301 -157.864352) (xy 93.099768 -157.781876) (xy 93.130744 -157.701917)
			(xy 93.168966 -157.625157) (xy 93.214107 -157.552251) (xy 93.265783 -157.483822) (xy 93.323552 -157.420452)
			(xy 93.386922 -157.362683) (xy 93.455351 -157.311007) (xy 93.528257 -157.265866) (xy 93.605017 -157.227644)
			(xy 93.684976 -157.196668) (xy 93.767452 -157.173201) (xy 93.851742 -157.157445) (xy 93.937125 -157.149533)
			(xy 94.022875 -157.149533) (xy 94.108258 -157.157445) (xy 94.192548 -157.173201) (xy 94.275024 -157.196668)
			(xy 94.354983 -157.227644) (xy 94.431743 -157.265866) (xy 94.504649 -157.311007) (xy 94.573078 -157.362683)
			(xy 94.636448 -157.420452) (xy 94.694217 -157.483822) (xy 94.745893 -157.552251) (xy 94.791034 -157.625157)
			(xy 94.829256 -157.701917) (xy 94.860232 -157.781876) (xy 94.883699 -157.864352) (xy 94.899455 -157.948642)
			(xy 94.907367 -158.034025) (xy 94.907862 -158.0769) (xy 94.907367 -158.119775) (xy 95.592633 -158.119775)
			(xy 95.592633 -158.034025) (xy 95.600545 -157.948642) (xy 95.616301 -157.864352) (xy 95.639768 -157.781876)
			(xy 95.670744 -157.701917) (xy 95.708966 -157.625157) (xy 95.754107 -157.552251) (xy 95.805783 -157.483822)
			(xy 95.863552 -157.420452) (xy 95.926922 -157.362683) (xy 95.995351 -157.311007) (xy 96.068257 -157.265866)
			(xy 96.145017 -157.227644) (xy 96.224976 -157.196668) (xy 96.307452 -157.173201) (xy 96.391742 -157.157445)
			(xy 96.477125 -157.149533) (xy 96.562875 -157.149533) (xy 96.648258 -157.157445) (xy 96.732548 -157.173201)
			(xy 96.815024 -157.196668) (xy 96.894983 -157.227644) (xy 96.971743 -157.265866) (xy 97.044649 -157.311007)
			(xy 97.113078 -157.362683) (xy 97.176448 -157.420452) (xy 97.234217 -157.483822) (xy 97.285893 -157.552251)
			(xy 97.331034 -157.625157) (xy 97.369256 -157.701917) (xy 97.400232 -157.781876) (xy 97.423699 -157.864352)
			(xy 97.439455 -157.948642) (xy 97.447367 -158.034025) (xy 97.447862 -158.0769) (xy 97.447367 -158.119775)
			(xy 97.439455 -158.205158) (xy 97.423699 -158.289448) (xy 97.400232 -158.371924) (xy 97.369256 -158.451883)
			(xy 97.331034 -158.528643) (xy 97.285893 -158.601549) (xy 97.234217 -158.669978) (xy 97.176448 -158.733348)
			(xy 97.113078 -158.791117) (xy 97.044649 -158.842793) (xy 96.971743 -158.887934) (xy 96.894983 -158.926156)
			(xy 96.815024 -158.957132) (xy 96.732548 -158.980599) (xy 96.648258 -158.996355) (xy 96.562875 -159.004267)
			(xy 96.477125 -159.004267) (xy 96.391742 -158.996355) (xy 96.307452 -158.980599) (xy 96.224976 -158.957132)
			(xy 96.145017 -158.926156) (xy 96.068257 -158.887934) (xy 95.995351 -158.842793) (xy 95.926922 -158.791117)
			(xy 95.863552 -158.733348) (xy 95.805783 -158.669978) (xy 95.754107 -158.601549) (xy 95.708966 -158.528643)
			(xy 95.670744 -158.451883) (xy 95.639768 -158.371924) (xy 95.616301 -158.289448) (xy 95.600545 -158.205158)
			(xy 95.592633 -158.119775) (xy 94.907367 -158.119775) (xy 94.899455 -158.205158) (xy 94.883699 -158.289448)
			(xy 94.860232 -158.371924) (xy 94.829256 -158.451883) (xy 94.791034 -158.528643) (xy 94.745893 -158.601549)
			(xy 94.694217 -158.669978) (xy 94.636448 -158.733348) (xy 94.573078 -158.791117) (xy 94.504649 -158.842793)
			(xy 94.431743 -158.887934) (xy 94.354983 -158.926156) (xy 94.275024 -158.957132) (xy 94.192548 -158.980599)
			(xy 94.108258 -158.996355) (xy 94.022875 -159.004267) (xy 93.937125 -159.004267) (xy 93.851742 -158.996355)
			(xy 93.767452 -158.980599) (xy 93.684976 -158.957132) (xy 93.605017 -158.926156) (xy 93.528257 -158.887934)
			(xy 93.455351 -158.842793) (xy 93.386922 -158.791117) (xy 93.323552 -158.733348) (xy 93.265783 -158.669978)
			(xy 93.214107 -158.601549) (xy 93.168966 -158.528643) (xy 93.130744 -158.451883) (xy 93.099768 -158.371924)
			(xy 93.076301 -158.289448) (xy 93.060545 -158.205158) (xy 93.052633 -158.119775) (xy 89.954367 -158.119775)
			(xy 89.946455 -158.205158) (xy 89.930699 -158.289448) (xy 89.907232 -158.371924) (xy 89.876256 -158.451883)
			(xy 89.838034 -158.528643) (xy 89.792893 -158.601549) (xy 89.741217 -158.669978) (xy 89.683448 -158.733348)
			(xy 89.620078 -158.791117) (xy 89.551649 -158.842793) (xy 89.478743 -158.887934) (xy 89.401983 -158.926156)
			(xy 89.322024 -158.957132) (xy 89.239548 -158.980599) (xy 89.155258 -158.996355) (xy 89.069875 -159.004267)
			(xy 88.984125 -159.004267) (xy 88.898742 -158.996355) (xy 88.814452 -158.980599) (xy 88.731976 -158.957132)
			(xy 88.652017 -158.926156) (xy 88.575257 -158.887934) (xy 88.502351 -158.842793) (xy 88.433922 -158.791117)
			(xy 88.370552 -158.733348) (xy 88.312783 -158.669978) (xy 88.261107 -158.601549) (xy 88.215966 -158.528643)
			(xy 88.177744 -158.451883) (xy 88.146768 -158.371924) (xy 88.123301 -158.289448) (xy 88.107545 -158.205158)
			(xy 88.099633 -158.119775) (xy 87.414367 -158.119775) (xy 87.406455 -158.205158) (xy 87.390699 -158.289448)
			(xy 87.367232 -158.371924) (xy 87.336256 -158.451883) (xy 87.298034 -158.528643) (xy 87.252893 -158.601549)
			(xy 87.201217 -158.669978) (xy 87.143448 -158.733348) (xy 87.080078 -158.791117) (xy 87.011649 -158.842793)
			(xy 86.938743 -158.887934) (xy 86.861983 -158.926156) (xy 86.782024 -158.957132) (xy 86.699548 -158.980599)
			(xy 86.615258 -158.996355) (xy 86.529875 -159.004267) (xy 86.444125 -159.004267) (xy 86.358742 -158.996355)
			(xy 86.274452 -158.980599) (xy 86.191976 -158.957132) (xy 86.112017 -158.926156) (xy 86.035257 -158.887934)
			(xy 85.962351 -158.842793) (xy 85.893922 -158.791117) (xy 85.830552 -158.733348) (xy 85.772783 -158.669978)
			(xy 85.721107 -158.601549) (xy 85.675966 -158.528643) (xy 85.637744 -158.451883) (xy 85.606768 -158.371924)
			(xy 85.583301 -158.289448) (xy 85.567545 -158.205158) (xy 85.559633 -158.119775) (xy 83.1088 -158.119775)
			(xy 83.1088 -169.36446) (xy 92.503995 -169.36446) (xy 92.503995 -169.23532) (xy 92.511945 -169.106425)
			(xy 92.527815 -168.978265) (xy 92.551544 -168.851324) (xy 92.583043 -168.726085) (xy 92.622192 -168.603022)
			(xy 92.668843 -168.482603) (xy 92.722818 -168.365284) (xy 92.783913 -168.25151) (xy 92.851896 -168.141713)
			(xy 92.92651 -168.03631) (xy 93.007471 -167.9357) (xy 93.094471 -167.840265) (xy 93.187182 -167.750366)
			(xy 93.285252 -167.666345) (xy 93.388307 -167.588521) (xy 93.495958 -167.517189) (xy 93.607797 -167.452619)
			(xy 93.723398 -167.395057) (xy 93.842323 -167.34472) (xy 93.964122 -167.3018) (xy 94.088332 -167.266459)
			(xy 94.214481 -167.238832) (xy 94.342093 -167.219023) (xy 94.470682 -167.207107) (xy 94.59976 -167.203131)
			(xy 94.728838 -167.207107) (xy 94.857427 -167.219023) (xy 94.985039 -167.238832) (xy 95.111188 -167.266459)
			(xy 95.235398 -167.3018) (xy 95.357197 -167.34472) (xy 95.476122 -167.395057) (xy 95.591723 -167.452619)
			(xy 95.703562 -167.517189) (xy 95.811213 -167.588521) (xy 95.914268 -167.666345) (xy 96.012338 -167.750366)
			(xy 96.105049 -167.840265) (xy 96.192049 -167.9357) (xy 96.27301 -168.03631) (xy 96.347624 -168.141713)
			(xy 96.415607 -168.25151) (xy 96.476702 -168.365284) (xy 96.530677 -168.482603) (xy 96.577328 -168.603022)
			(xy 96.616477 -168.726085) (xy 96.647976 -168.851324) (xy 96.671705 -168.978265) (xy 96.687575 -169.106425)
			(xy 96.695525 -169.23532) (xy 96.696022 -169.29989) (xy 96.695525 -169.36446) (xy 96.687575 -169.493355)
			(xy 96.671705 -169.621515) (xy 96.647976 -169.748456) (xy 96.616477 -169.873695) (xy 96.577328 -169.996758)
			(xy 96.530677 -170.117177) (xy 96.476702 -170.234496) (xy 96.415607 -170.34827) (xy 96.347624 -170.458067)
			(xy 96.27301 -170.56347) (xy 96.192049 -170.66408) (xy 96.105049 -170.759515) (xy 96.012338 -170.849414)
			(xy 95.914268 -170.933435) (xy 95.811213 -171.011259) (xy 95.703562 -171.082591) (xy 95.591723 -171.147161)
			(xy 95.476122 -171.204723) (xy 95.357197 -171.25506) (xy 95.235398 -171.29798) (xy 95.111188 -171.333321)
			(xy 94.985039 -171.360948) (xy 94.857427 -171.380757) (xy 94.728838 -171.392673) (xy 94.59976 -171.39665)
			(xy 94.470682 -171.392673) (xy 94.342093 -171.380757) (xy 94.214481 -171.360948) (xy 94.088332 -171.333321)
			(xy 93.964122 -171.29798) (xy 93.842323 -171.25506) (xy 93.723398 -171.204723) (xy 93.607797 -171.147161)
			(xy 93.495958 -171.082591) (xy 93.388307 -171.011259) (xy 93.285252 -170.933435) (xy 93.187182 -170.849414)
			(xy 93.094471 -170.759515) (xy 93.007471 -170.66408) (xy 92.92651 -170.56347) (xy 92.851896 -170.458067)
			(xy 92.783913 -170.34827) (xy 92.722818 -170.234496) (xy 92.668843 -170.117177) (xy 92.622192 -169.996758)
			(xy 92.583043 -169.873695) (xy 92.551544 -169.748456) (xy 92.527815 -169.621515) (xy 92.511945 -169.493355)
			(xy 92.503995 -169.36446) (xy 83.1088 -169.36446) (xy 83.1088 -172.353986) (xy 83.1088 -172.356018)
			(xy 83.111166 -172.405878) (xy 83.121718 -172.505148) (xy 83.129882 -172.554392) (xy 83.129882 -172.555408)
			(xy 83.140735 -172.609684) (xy 83.169309 -172.716628) (xy 83.205583 -172.821212) (xy 83.249364 -172.922883)
			(xy 83.30042 -173.021102) (xy 83.35848 -173.115349) (xy 83.423239 -173.205127) (xy 83.494352 -173.289959)
			(xy 83.571445 -173.369397) (xy 83.654108 -173.44302) (xy 83.741905 -173.51044) (xy 83.83437 -173.571298)
			(xy 83.931015 -173.625274) (xy 84.031328 -173.672081) (xy 84.134778 -173.711473) (xy 84.240818 -173.743239)
			(xy 84.348887 -173.767213) (xy 84.458413 -173.783267) (xy 84.568816 -173.791317) (xy 84.624164 -173.79188)
		)
		(stroke
			(width 0)
			(type solid)
		)
		(fill yes)
		(layer "In1.Cu")
		(net "GND1")
	)
	(gr_poly
		(pts
			(xy 28.850082 -85.640926) (xy 28.905852 -85.640405) (xy 29.01708 -85.632071) (xy 29.127375 -85.615449)
			(xy 29.236119 -85.59063) (xy 29.342704 -85.557755) (xy 29.446535 -85.517006) (xy 29.54703 -85.468613)
			(xy 29.643627 -85.412844) (xy 29.735787 -85.350013) (xy 29.822994 -85.280471) (xy 29.904761 -85.204606)
			(xy 29.980629 -85.122843) (xy 30.050175 -85.035639) (xy 30.11301 -84.943482) (xy 30.168783 -84.846886)
			(xy 30.217181 -84.746393) (xy 30.257934 -84.642565) (xy 30.290814 -84.535981) (xy 30.315637 -84.427238)
			(xy 30.332264 -84.316944) (xy 30.340603 -84.205716) (xy 30.341062 -84.149946) (xy 30.341062 -82.00009)
			(xy 30.341556 -81.929708) (xy 30.349449 -81.789165) (xy 30.36521 -81.649285) (xy 30.38879 -81.510509)
			(xy 30.420113 -81.373274) (xy 30.459082 -81.238011) (xy 30.505573 -81.105145) (xy 30.559442 -80.975096)
			(xy 30.620517 -80.848271) (xy 30.688608 -80.725071) (xy 30.763499 -80.605882) (xy 30.844955 -80.49108)
			(xy 30.93272 -80.381025) (xy 31.026518 -80.276065) (xy 31.126053 -80.176529) (xy 31.231013 -80.082731)
			(xy 31.341067 -79.994965) (xy 31.455869 -79.913508) (xy 31.575057 -79.838616) (xy 31.698257 -79.770525)
			(xy 31.825081 -79.709448) (xy 31.955131 -79.655579) (xy 32.087996 -79.609087) (xy 32.223258 -79.570117)
			(xy 32.360494 -79.538793) (xy 32.499269 -79.515212) (xy 32.639149 -79.499451) (xy 32.779692 -79.491556)
			(xy 32.850074 -79.491078) (xy 36.20008 -79.491078) (xy 36.25585 -79.49057) (xy 36.367078 -79.482236)
			(xy 36.477372 -79.465613) (xy 36.586116 -79.440795) (xy 36.692701 -79.407919) (xy 36.796531 -79.36717)
			(xy 36.897025 -79.318775) (xy 36.993622 -79.263006) (xy 37.085781 -79.200174) (xy 37.172987 -79.130631)
			(xy 37.254752 -79.054765) (xy 37.330619 -78.973001) (xy 37.400164 -78.885796) (xy 37.462997 -78.793637)
			(xy 37.518767 -78.697041) (xy 37.567163 -78.596547) (xy 37.607913 -78.492718) (xy 37.64079 -78.386133)
			(xy 37.66561 -78.27739) (xy 37.682234 -78.167096) (xy 37.69057 -78.055868) (xy 37.69106 -78.000098)
			(xy 37.69106 -71.948802) (xy 37.691599 -71.875496) (xy 37.700178 -71.729134) (xy 37.717289 -71.583524)
			(xy 37.742874 -71.439161) (xy 37.776846 -71.296538) (xy 37.819088 -71.156143) (xy 37.869457 -71.018454)
			(xy 37.927781 -70.883942) (xy 37.99386 -70.753065) (xy 38.067469 -70.626269) (xy 38.148356 -70.503989)
			(xy 38.236247 -70.386641) (xy 38.33084 -70.274626) (xy 38.380924 -70.221094) (xy 38.41954 -70.179665)
			(xy 38.491081 -70.091854) (xy 38.555754 -69.998869) (xy 38.613187 -69.901245) (xy 38.663048 -69.799546)
			(xy 38.70505 -69.694357) (xy 38.738951 -69.586285) (xy 38.764555 -69.475952) (xy 38.781716 -69.363995)
			(xy 38.790333 -69.251058) (xy 38.79088 -69.194426) (xy 38.79088 -48.38192) (xy 38.793166 -48.379634)
			(xy 38.793166 -48.30064) (xy 38.79088 -48.298354) (xy 38.79088 -1.998726) (xy 38.790418 -1.94812)
			(xy 38.783485 -1.847145) (xy 38.769729 -1.746871) (xy 38.759892 -1.697228) (xy 38.759892 -1.69672)
			(xy 38.748192 -1.644664) (xy 38.718311 -1.542227) (xy 38.68119 -1.442187) (xy 38.637016 -1.345053)
			(xy 38.586017 -1.251324) (xy 38.528453 -1.161477) (xy 38.464617 -1.075972) (xy 38.394837 -0.995245)
			(xy 38.319468 -0.91971) (xy 38.238895 -0.849751) (xy 38.153531 -0.785727) (xy 38.063812 -0.727964)
			(xy 37.970195 -0.676758) (xy 37.87316 -0.63237) (xy 37.773202 -0.595028) (xy 37.670831 -0.564921)
			(xy 37.566572 -0.542204) (xy 37.460956 -0.526993) (xy 37.354523 -0.519366) (xy 37.30117 -0.518922)
			(xy 2.001266 -0.518922) (xy 1.945459 -0.519444) (xy 1.834157 -0.527785) (xy 1.72379 -0.54442) (xy 1.614975 -0.569257)
			(xy 1.508319 -0.602156) (xy 1.404421 -0.642933) (xy 1.30386 -0.691361) (xy 1.2072 -0.747168) (xy 1.11498 -0.810043)
			(xy 1.027717 -0.879633) (xy 0.945898 -0.95555) (xy 0.869982 -1.037369) (xy 0.800391 -1.124632) (xy 0.737517 -1.216852)
			(xy 0.68171 -1.313512) (xy 0.633283 -1.414073) (xy 0.592505 -1.517971) (xy 0.559607 -1.624626) (xy 0.53477 -1.733442)
			(xy 0.518135 -1.843809) (xy 0.509794 -1.955111) (xy 0.50927 -2.010918) (xy 0.50927 -14.899894) (xy 3.584198 -14.899894)
			(xy 3.588228 -14.757559) (xy 3.600303 -14.615679) (xy 3.620386 -14.474711) (xy 3.648413 -14.335104)
			(xy 3.684293 -14.197306) (xy 3.727911 -14.061759) (xy 3.779128 -13.928897) (xy 3.837779 -13.799145)
			(xy 3.903677 -13.672919) (xy 3.976611 -13.550623) (xy 4.056348 -13.43265) (xy 4.14263 -13.319377)
			(xy 4.235183 -13.211166) (xy 4.33371 -13.108365) (xy 4.437895 -13.011303) (xy 4.547404 -12.920291)
			(xy 4.661887 -12.835619) (xy 4.780977 -12.757561) (xy 4.904292 -12.686365) (xy 5.031438 -12.622259)
			(xy 5.162007 -12.56545) (xy 5.295581 -12.516118) (xy 5.431732 -12.474422) (xy 5.570023 -12.440496)
			(xy 5.710013 -12.414448) (xy 5.851252 -12.396362) (xy 5.993288 -12.386295) (xy 6.135666 -12.38428)
			(xy 6.27793 -12.390323) (xy 6.419624 -12.404405) (xy 6.560294 -12.426481) (xy 6.699491 -12.456481)
			(xy 6.836767 -12.494307) (xy 6.971683 -12.539839) (xy 7.103807 -12.59293) (xy 7.232716 -12.653412)
			(xy 7.357997 -12.72109) (xy 7.479248 -12.795747) (xy 7.596081 -12.877145) (xy 7.708122 -12.965022)
			(xy 7.815012 -13.059097) (xy 7.916409 -13.159069) (xy 8.011987 -13.264617) (xy 8.101441 -13.375403)
			(xy 8.184483 -13.491072) (xy 8.260849 -13.611255) (xy 8.330293 -13.735565) (xy 8.392593 -13.863606)
			(xy 8.447549 -13.994965) (xy 8.494986 -14.129224) (xy 8.53475 -14.265951) (xy 8.566716 -14.404709)
			(xy 8.590781 -14.545053) (xy 8.595466 -14.58626) (xy 31.59149 -14.58626) (xy 31.592597 -14.430603)
			(xy 31.601751 -14.275211) (xy 31.618929 -14.120501) (xy 31.644084 -13.966886) (xy 31.677149 -13.814777)
			(xy 31.718035 -13.664582) (xy 31.766634 -13.516701) (xy 31.822815 -13.371532) (xy 31.886427 -13.229463)
			(xy 31.957301 -13.090873) (xy 32.035247 -12.956133) (xy 32.120056 -12.825604) (xy 32.211502 -12.699636)
			(xy 32.260032 -12.638786) (xy 32.294969 -12.594641) (xy 32.358902 -12.501967) (xy 32.415667 -12.404736)
			(xy 32.464941 -12.303503) (xy 32.506444 -12.198843) (xy 32.539939 -12.091353) (xy 32.565236 -11.981644)
			(xy 32.58219 -11.870339) (xy 32.590706 -11.758074) (xy 32.591248 -11.70178) (xy 32.591248 -11.02995)
			(xy 32.591744 -10.966834) (xy 32.59967 -10.84085) (xy 32.615491 -10.715613) (xy 32.639144 -10.591617)
			(xy 32.670537 -10.46935) (xy 32.709545 -10.349296) (xy 32.756014 -10.231928) (xy 32.809762 -10.11771)
			(xy 32.870574 -10.007091) (xy 32.938213 -9.90051) (xy 33.012411 -9.798386) (xy 33.092874 -9.701122)
			(xy 33.179286 -9.609102) (xy 33.271306 -9.52269) (xy 33.36857 -9.442227) (xy 33.470694 -9.368029)
			(xy 33.577275 -9.30039) (xy 33.687894 -9.239578) (xy 33.802112 -9.18583) (xy 33.91948 -9.139361)
			(xy 34.039534 -9.100353) (xy 34.161801 -9.06896) (xy 34.285797 -9.045307) (xy 34.411034 -9.029486)
			(xy 34.537018 -9.02156) (xy 34.66325 -9.02156) (xy 34.789234 -9.029486) (xy 34.914471 -9.045307)
			(xy 35.038467 -9.06896) (xy 35.160734 -9.100353) (xy 35.280788 -9.139361) (xy 35.398156 -9.18583)
			(xy 35.512374 -9.239578) (xy 35.622993 -9.30039) (xy 35.729574 -9.368029) (xy 35.831698 -9.442227)
			(xy 35.928962 -9.52269) (xy 36.020982 -9.609102) (xy 36.107394 -9.701122) (xy 36.187857 -9.798386)
			(xy 36.262055 -9.90051) (xy 36.329694 -10.007091) (xy 36.390506 -10.11771) (xy 36.444254 -10.231928)
			(xy 36.490723 -10.349296) (xy 36.529731 -10.46935) (xy 36.561124 -10.591617) (xy 36.584777 -10.715613)
			(xy 36.600598 -10.84085) (xy 36.608524 -10.966834) (xy 36.60902 -11.02995) (xy 36.60902 -11.70178)
			(xy 36.609593 -11.758074) (xy 36.618096 -11.870341) (xy 36.635039 -11.981648) (xy 36.660326 -12.09136)
			(xy 36.693814 -12.198853) (xy 36.735311 -12.303515) (xy 36.784581 -12.404751) (xy 36.841345 -12.501983)
			(xy 36.905277 -12.594659) (xy 36.940236 -12.638786) (xy 36.988766 -12.699636) (xy 37.080212 -12.825604)
			(xy 37.165021 -12.956133) (xy 37.242967 -13.090873) (xy 37.313841 -13.229463) (xy 37.377453 -13.371532)
			(xy 37.433634 -13.516701) (xy 37.482233 -13.664582) (xy 37.523119 -13.814777) (xy 37.556184 -13.966886)
			(xy 37.581339 -14.120501) (xy 37.598517 -14.275211) (xy 37.607671 -14.430603) (xy 37.608778 -14.58626)
			(xy 37.601834 -14.741766) (xy 37.586857 -14.896705) (xy 37.563889 -15.050662) (xy 37.53299 -15.203225)
			(xy 37.494243 -15.353987) (xy 37.447752 -15.502543) (xy 37.39364 -15.648496) (xy 37.332054 -15.791456)
			(xy 37.263158 -15.931039) (xy 37.187135 -16.066874) (xy 37.104191 -16.198595) (xy 37.014545 -16.325851)
			(xy 36.918439 -16.448301) (xy 36.81613 -16.565617) (xy 36.70789 -16.677486) (xy 36.594011 -16.783608)
			(xy 36.474796 -16.883699) (xy 36.350565 -16.977491) (xy 36.22165 -17.064734) (xy 36.088396 -17.145193)
			(xy 35.95116 -17.218654) (xy 35.810309 -17.28492) (xy 35.666219 -17.343814) (xy 35.519276 -17.395178)
			(xy 35.369874 -17.438875) (xy 35.218413 -17.474787) (xy 35.065296 -17.502819) (xy 34.910935 -17.522896)
			(xy 34.755743 -17.534963) (xy 34.600134 -17.538989) (xy 34.444525 -17.534963) (xy 34.289333 -17.522896)
			(xy 34.134972 -17.502819) (xy 33.981855 -17.474787) (xy 33.830394 -17.438875) (xy 33.680992 -17.395178)
			(xy 33.534049 -17.343814) (xy 33.389959 -17.28492) (xy 33.249108 -17.218654) (xy 33.111872 -17.145193)
			(xy 32.978618 -17.064734) (xy 32.849703 -16.977491) (xy 32.725472 -16.883699) (xy 32.606257 -16.783608)
			(xy 32.492378 -16.677486) (xy 32.384138 -16.565617) (xy 32.281829 -16.448301) (xy 32.185723 -16.325851)
			(xy 32.096077 -16.198595) (xy 32.013133 -16.066874) (xy 31.93711 -15.931039) (xy 31.868214 -15.791456)
			(xy 31.806628 -15.648496) (xy 31.752516 -15.502543) (xy 31.706025 -15.353987) (xy 31.667278 -15.203225)
			(xy 31.636379 -15.050662) (xy 31.613411 -14.896705) (xy 31.598434 -14.741766) (xy 31.59149 -14.58626)
			(xy 8.595466 -14.58626) (xy 8.606867 -14.686534) (xy 8.614922 -14.828698) (xy 8.615426 -14.899894)
			(xy 8.614922 -14.97109) (xy 8.606867 -15.113254) (xy 8.590781 -15.254735) (xy 8.566716 -15.395079)
			(xy 8.53475 -15.533837) (xy 8.494986 -15.670564) (xy 8.447549 -15.804823) (xy 8.392593 -15.936182)
			(xy 8.330293 -16.064223) (xy 8.260849 -16.188533) (xy 8.184483 -16.308716) (xy 8.101441 -16.424385)
			(xy 8.011987 -16.535171) (xy 7.916409 -16.640719) (xy 7.815012 -16.740691) (xy 7.708122 -16.834766)
			(xy 7.596081 -16.922643) (xy 7.479248 -17.004041) (xy 7.357997 -17.078698) (xy 7.232716 -17.146376)
			(xy 7.103807 -17.206858) (xy 6.971683 -17.259949) (xy 6.836767 -17.305481) (xy 6.699491 -17.343307)
			(xy 6.560294 -17.373307) (xy 6.419624 -17.395383) (xy 6.27793 -17.409465) (xy 6.135666 -17.415508)
			(xy 5.993288 -17.413493) (xy 5.851252 -17.403426) (xy 5.710013 -17.38534) (xy 5.570023 -17.359292)
			(xy 5.431732 -17.325366) (xy 5.295581 -17.28367) (xy 5.162007 -17.234338) (xy 5.031438 -17.177529)
			(xy 4.904292 -17.113423) (xy 4.780977 -17.042227) (xy 4.661887 -16.964169) (xy 4.547404 -16.879497)
			(xy 4.437895 -16.788485) (xy 4.33371 -16.691423) (xy 4.235183 -16.588622) (xy 4.14263 -16.480411)
			(xy 4.056348 -16.367138) (xy 3.976611 -16.249165) (xy 3.903677 -16.126869) (xy 3.837779 -16.000643)
			(xy 3.779128 -15.870891) (xy 3.727911 -15.738029) (xy 3.684293 -15.602482) (xy 3.648413 -15.464684)
			(xy 3.620386 -15.325077) (xy 3.600303 -15.184109) (xy 3.588228 -15.042229) (xy 3.584198 -14.899894)
			(xy 0.50927 -14.899894) (xy 0.50927 -18.32991) (xy 23.337774 -18.32991) (xy 23.338267 -18.290403)
			(xy 23.346474 -18.211817) (xy 23.362759 -18.1345) (xy 23.386947 -18.05928) (xy 23.41878 -17.986963)
			(xy 23.457917 -17.918323) (xy 23.480522 -17.885918) (xy 23.484825 -17.87932) (xy 23.489621 -17.864325)
			(xy 23.48992 -17.856454) (xy 23.48992 -16.802862) (xy 23.489646 -16.794986) (xy 23.484853 -16.779982)
			(xy 23.480522 -16.773398) (xy 23.457958 -16.741022) (xy 23.418861 -16.672468) (xy 23.387069 -16.600235)
			(xy 23.362923 -16.5251) (xy 23.346684 -16.44787) (xy 23.338525 -16.369374) (xy 23.338028 -16.329914)
			(xy 23.338517 -16.291295) (xy 23.346331 -16.214452) (xy 23.361879 -16.138794) (xy 23.385002 -16.065097)
			(xy 23.415461 -15.994118) (xy 23.452946 -15.926584) (xy 23.49707 -15.86319) (xy 23.547381 -15.804584)
			(xy 23.603363 -15.751369) (xy 23.664442 -15.70409) (xy 23.72999 -15.663234) (xy 23.799336 -15.629218)
			(xy 23.871767 -15.602393) (xy 23.94654 -15.583033) (xy 24.022888 -15.571337) (xy 24.100028 -15.567425)
			(xy 24.177168 -15.571337) (xy 24.253516 -15.583033) (xy 24.328289 -15.602393) (xy 24.40072 -15.629218)
			(xy 24.470066 -15.663234) (xy 24.535614 -15.70409) (xy 24.596693 -15.751369) (xy 24.652675 -15.804584)
			(xy 24.702986 -15.86319) (xy 24.74711 -15.926584) (xy 24.784595 -15.994118) (xy 24.815054 -16.065097)
			(xy 24.838177 -16.138794) (xy 24.853725 -16.214452) (xy 24.861539 -16.291295) (xy 24.862028 -16.329914)
			(xy 24.861499 -16.369371) (xy 24.853315 -16.447861) (xy 24.837067 -16.525085) (xy 24.812929 -16.600218)
			(xy 24.781159 -16.672455) (xy 24.742097 -16.741024) (xy 24.719534 -16.773398) (xy 24.71522 -16.77999)
			(xy 24.710432 -16.79499) (xy 24.710136 -16.802862) (xy 24.710136 -17.856454) (xy 24.71041 -17.86433)
			(xy 24.715203 -17.879334) (xy 24.719534 -17.885918) (xy 24.742151 -17.918316) (xy 24.781315 -17.986944)
			(xy 24.813161 -18.05926) (xy 24.837348 -18.134484) (xy 24.853614 -18.211808) (xy 24.861785 -18.290401)
			(xy 24.862282 -18.32991) (xy 24.861793 -18.368542) (xy 24.853976 -18.445411) (xy 24.838423 -18.521094)
			(xy 24.815293 -18.594815) (xy 24.784823 -18.665818) (xy 24.747326 -18.733374) (xy 24.703187 -18.79679)
			(xy 24.652859 -18.855415) (xy 24.596858 -18.908648) (xy 24.535759 -18.955942) (xy 24.470189 -18.996813)
			(xy 24.400821 -19.03084) (xy 24.328365 -19.057674) (xy 24.253567 -19.077041) (xy 24.177194 -19.088741)
			(xy 24.100028 -19.092654) (xy 24.022862 -19.088741) (xy 23.946489 -19.077041) (xy 23.871691 -19.057674)
			(xy 23.799235 -19.03084) (xy 23.729867 -18.996813) (xy 23.664297 -18.955942) (xy 23.603198 -18.908648)
			(xy 23.547197 -18.855415) (xy 23.496869 -18.79679) (xy 23.45273 -18.733374) (xy 23.415233 -18.665818)
			(xy 23.384763 -18.594815) (xy 23.361633 -18.521094) (xy 23.34608 -18.445411) (xy 23.338263 -18.368542)
			(xy 23.337774 -18.32991) (xy 0.50927 -18.32991) (xy 0.50927 -21.404834) (xy 30.242764 -21.404834)
			(xy 30.242764 -20.823936) (xy 30.243183 -20.817055) (xy 30.250088 -20.80515) (xy 30.262042 -20.798334)
			(xy 30.268926 -20.798028) (xy 30.26918 -20.798028) (xy 30.959806 -20.798028) (xy 30.966654 -20.798466)
			(xy 30.978538 -20.805277) (xy 30.985465 -20.817092) (xy 30.985968 -20.823936) (xy 30.985968 -21.404834)
			(xy 32.24276 -21.404834) (xy 32.24276 -20.823936) (xy 32.243183 -20.817055) (xy 32.250086 -20.805152)
			(xy 32.262039 -20.798335) (xy 32.268922 -20.798028) (xy 32.269176 -20.798028) (xy 32.959802 -20.798028)
			(xy 32.96665 -20.798469) (xy 32.978534 -20.805278) (xy 32.985461 -20.817093) (xy 32.985964 -20.823936)
			(xy 32.985964 -21.404834) (xy 32.985542 -21.411727) (xy 32.978639 -21.423662) (xy 32.966696 -21.430551)
			(xy 32.959802 -21.430996) (xy 32.268922 -21.430996) (xy 32.262039 -21.430501) (xy 32.25011 -21.42363)
			(xy 32.243214 -21.411716) (xy 32.24276 -21.404834) (xy 30.985968 -21.404834) (xy 30.985542 -21.411726)
			(xy 30.97864 -21.42366) (xy 30.966699 -21.43055) (xy 30.959806 -21.430996) (xy 30.268926 -21.430996)
			(xy 30.262043 -21.430498) (xy 30.250115 -21.423628) (xy 30.243218 -21.411716) (xy 30.242764 -21.404834)
			(xy 0.50927 -21.404834) (xy 0.50927 -23.616412) (xy 30.920944 -23.616412) (xy 30.920944 -22.526752)
			(xy 30.921395 -22.519875) (xy 30.928286 -22.507975) (xy 30.940227 -22.501154) (xy 30.947106 -22.500844)
			(xy 30.94736 -22.500844) (xy 31.421832 -22.500844) (xy 31.428651 -22.501307) (xy 31.44046 -22.508128)
			(xy 31.447289 -22.519934) (xy 31.44774 -22.526752) (xy 31.44774 -23.616412) (xy 31.770828 -23.616412)
			(xy 31.770828 -22.526752) (xy 31.771197 -22.519861) (xy 31.778116 -22.507944) (xy 31.790096 -22.501136)
			(xy 31.79699 -22.500844) (xy 31.797244 -22.500844) (xy 32.271716 -22.500844) (xy 32.278533 -22.501319)
			(xy 32.290343 -22.508134) (xy 32.297172 -22.519935) (xy 32.297624 -22.526752) (xy 32.297624 -23.616412)
			(xy 32.297176 -23.623234) (xy 32.290353 -23.63505) (xy 32.278538 -23.641875) (xy 32.271716 -23.64232)
			(xy 31.79699 -23.64232) (xy 31.790133 -23.641934) (xy 31.778239 -23.635106) (xy 31.77132 -23.623265)
			(xy 31.770828 -23.616412) (xy 31.44774 -23.616412) (xy 31.447277 -23.623231) (xy 31.440459 -23.635044)
			(xy 31.428651 -23.641872) (xy 31.421832 -23.64232) (xy 30.947106 -23.64232) (xy 30.94025 -23.641922)
			(xy 30.928357 -23.6351) (xy 30.921436 -23.623264) (xy 30.920944 -23.616412) (xy 0.50927 -23.616412)
			(xy 0.50927 -25.163272) (xy 30.901132 -25.163272) (xy 30.901132 -23.988522) (xy 30.901588 -23.981675)
			(xy 30.908388 -23.969791) (xy 30.920198 -23.962863) (xy 30.92704 -23.96236) (xy 31.42869 -23.96236)
			(xy 31.435607 -23.962705) (xy 31.447587 -23.969622) (xy 31.454498 -23.981605) (xy 31.454852 -23.988522)
			(xy 31.454852 -25.163272) (xy 31.751016 -25.163272) (xy 31.751016 -23.988522) (xy 31.751487 -23.981678)
			(xy 31.758282 -23.969797) (xy 31.770085 -23.962867) (xy 31.776924 -23.96236) (xy 32.278574 -23.96236)
			(xy 32.285489 -23.962717) (xy 32.297469 -23.969628) (xy 32.304382 -23.981607) (xy 32.304736 -23.988522)
			(xy 32.304736 -25.163272) (xy 32.304323 -25.170154) (xy 32.297415 -25.182058) (xy 32.285459 -25.188875)
			(xy 32.278574 -25.18918) (xy 32.27832 -25.18918) (xy 31.776924 -25.18918) (xy 31.770074 -25.188834)
			(xy 31.758209 -25.181988) (xy 31.751365 -25.170122) (xy 31.751016 -25.163272) (xy 31.454852 -25.163272)
			(xy 31.454424 -25.170151) (xy 31.447521 -25.182053) (xy 31.435572 -25.188871) (xy 31.42869 -25.18918)
			(xy 31.428436 -25.18918) (xy 30.92704 -25.18918) (xy 30.920192 -25.188822) (xy 30.908327 -25.181982)
			(xy 30.901482 -25.17012) (xy 30.901132 -25.163272) (xy 0.50927 -25.163272) (xy 0.50927 -33.568694)
			(xy 13.395441 -33.568694) (xy 13.395441 -33.439554) (xy 13.403391 -33.310659) (xy 13.419261 -33.182499)
			(xy 13.44299 -33.055558) (xy 13.474489 -32.930319) (xy 13.513638 -32.807256) (xy 13.560289 -32.686837)
			(xy 13.614264 -32.569518) (xy 13.675359 -32.455744) (xy 13.743342 -32.345947) (xy 13.817956 -32.240544)
			(xy 13.898917 -32.139934) (xy 13.985917 -32.044499) (xy 14.078628 -31.9546) (xy 14.176698 -31.870579)
			(xy 14.279753 -31.792755) (xy 14.387404 -31.721423) (xy 14.499243 -31.656853) (xy 14.614844 -31.599291)
			(xy 14.733769 -31.548954) (xy 14.855568 -31.506034) (xy 14.979778 -31.470693) (xy 15.105927 -31.443066)
			(xy 15.233539 -31.423257) (xy 15.362128 -31.411341) (xy 15.491206 -31.407365) (xy 15.620284 -31.411341)
			(xy 15.748873 -31.423257) (xy 15.876485 -31.443066) (xy 16.002634 -31.470693) (xy 16.126844 -31.506034)
			(xy 16.248643 -31.548954) (xy 16.367568 -31.599291) (xy 16.483169 -31.656853) (xy 16.595008 -31.721423)
			(xy 16.702659 -31.792755) (xy 16.805714 -31.870579) (xy 16.903784 -31.9546) (xy 16.996495 -32.044499)
			(xy 17.083495 -32.139934) (xy 17.164456 -32.240544) (xy 17.23907 -32.345947) (xy 17.307053 -32.455744)
			(xy 17.368148 -32.569518) (xy 17.422123 -32.686837) (xy 17.468774 -32.807256) (xy 17.507923 -32.930319)
			(xy 17.539422 -33.055558) (xy 17.563151 -33.182499) (xy 17.579021 -33.310659) (xy 17.586971 -33.439554)
			(xy 17.587468 -33.504124) (xy 17.586971 -33.568694) (xy 17.579021 -33.697589) (xy 17.563151 -33.825749)
			(xy 17.539422 -33.95269) (xy 17.507923 -34.077929) (xy 17.468774 -34.200992) (xy 17.422123 -34.321411)
			(xy 17.368148 -34.43873) (xy 17.307053 -34.552504) (xy 17.23907 -34.662301) (xy 17.164456 -34.767704)
			(xy 17.083495 -34.868314) (xy 16.996495 -34.963749) (xy 16.903784 -35.053648) (xy 16.805714 -35.137669)
			(xy 16.702659 -35.215493) (xy 16.595008 -35.286825) (xy 16.483169 -35.351395) (xy 16.367568 -35.408957)
			(xy 16.248643 -35.459294) (xy 16.126844 -35.502214) (xy 16.002634 -35.537555) (xy 15.876485 -35.565182)
			(xy 15.748873 -35.584991) (xy 15.620284 -35.596907) (xy 15.491206 -35.600884) (xy 15.362128 -35.596907)
			(xy 15.233539 -35.584991) (xy 15.105927 -35.565182) (xy 14.979778 -35.537555) (xy 14.855568 -35.502214)
			(xy 14.733769 -35.459294) (xy 14.614844 -35.408957) (xy 14.499243 -35.351395) (xy 14.387404 -35.286825)
			(xy 14.279753 -35.215493) (xy 14.176698 -35.137669) (xy 14.078628 -35.053648) (xy 13.985917 -34.963749)
			(xy 13.898917 -34.868314) (xy 13.817956 -34.767704) (xy 13.743342 -34.662301) (xy 13.675359 -34.552504)
			(xy 13.614264 -34.43873) (xy 13.560289 -34.321411) (xy 13.513638 -34.200992) (xy 13.474489 -34.077929)
			(xy 13.44299 -33.95269) (xy 13.419261 -33.825749) (xy 13.403391 -33.697589) (xy 13.395441 -33.568694)
			(xy 0.50927 -33.568694) (xy 0.50927 -37.638282) (xy 31.944299 -37.638282) (xy 31.944299 -37.509142)
			(xy 31.952249 -37.380247) (xy 31.968119 -37.252087) (xy 31.991848 -37.125146) (xy 32.023347 -36.999907)
			(xy 32.062496 -36.876844) (xy 32.109147 -36.756425) (xy 32.163122 -36.639106) (xy 32.224217 -36.525332)
			(xy 32.2922 -36.415535) (xy 32.366814 -36.310132) (xy 32.447775 -36.209522) (xy 32.534775 -36.114087)
			(xy 32.627486 -36.024188) (xy 32.725556 -35.940167) (xy 32.828611 -35.862343) (xy 32.936262 -35.791011)
			(xy 33.048101 -35.726441) (xy 33.163702 -35.668879) (xy 33.282627 -35.618542) (xy 33.404426 -35.575622)
			(xy 33.528636 -35.540281) (xy 33.654785 -35.512654) (xy 33.782397 -35.492845) (xy 33.910986 -35.480929)
			(xy 34.040064 -35.476953) (xy 34.169142 -35.480929) (xy 34.297731 -35.492845) (xy 34.425343 -35.512654)
			(xy 34.551492 -35.540281) (xy 34.675702 -35.575622) (xy 34.797501 -35.618542) (xy 34.916426 -35.668879)
			(xy 35.032027 -35.726441) (xy 35.143866 -35.791011) (xy 35.251517 -35.862343) (xy 35.354572 -35.940167)
			(xy 35.452642 -36.024188) (xy 35.545353 -36.114087) (xy 35.632353 -36.209522) (xy 35.713314 -36.310132)
			(xy 35.787928 -36.415535) (xy 35.855911 -36.525332) (xy 35.917006 -36.639106) (xy 35.970981 -36.756425)
			(xy 36.017632 -36.876844) (xy 36.056781 -36.999907) (xy 36.08828 -37.125146) (xy 36.112009 -37.252087)
			(xy 36.127879 -37.380247) (xy 36.135829 -37.509142) (xy 36.136326 -37.573712) (xy 36.135829 -37.638282)
			(xy 36.127879 -37.767177) (xy 36.112009 -37.895337) (xy 36.08828 -38.022278) (xy 36.056781 -38.147517)
			(xy 36.017632 -38.27058) (xy 35.970981 -38.390999) (xy 35.917006 -38.508318) (xy 35.855911 -38.622092)
			(xy 35.787928 -38.731889) (xy 35.713314 -38.837292) (xy 35.632353 -38.937902) (xy 35.545353 -39.033337)
			(xy 35.452642 -39.123236) (xy 35.354572 -39.207257) (xy 35.251517 -39.285081) (xy 35.143866 -39.356413)
			(xy 35.032027 -39.420983) (xy 34.916426 -39.478545) (xy 34.797501 -39.528882) (xy 34.675702 -39.571802)
			(xy 34.551492 -39.607143) (xy 34.425343 -39.63477) (xy 34.297731 -39.654579) (xy 34.169142 -39.666495)
			(xy 34.040064 -39.670472) (xy 33.910986 -39.666495) (xy 33.782397 -39.654579) (xy 33.654785 -39.63477)
			(xy 33.528636 -39.607143) (xy 33.404426 -39.571802) (xy 33.282627 -39.528882) (xy 33.163702 -39.478545)
			(xy 33.048101 -39.420983) (xy 32.936262 -39.356413) (xy 32.828611 -39.285081) (xy 32.725556 -39.207257)
			(xy 32.627486 -39.123236) (xy 32.534775 -39.033337) (xy 32.447775 -38.937902) (xy 32.366814 -38.837292)
			(xy 32.2922 -38.731889) (xy 32.224217 -38.622092) (xy 32.163122 -38.508318) (xy 32.109147 -38.390999)
			(xy 32.062496 -38.27058) (xy 32.023347 -38.147517) (xy 31.991848 -38.022278) (xy 31.968119 -37.895337)
			(xy 31.952249 -37.767177) (xy 31.944299 -37.638282) (xy 0.50927 -37.638282) (xy 0.50927 -64.96157)
			(xy 1.460235 -64.96157) (xy 1.460235 -64.83243) (xy 1.468185 -64.703535) (xy 1.484055 -64.575375)
			(xy 1.507784 -64.448434) (xy 1.539283 -64.323195) (xy 1.578432 -64.200132) (xy 1.625083 -64.079713)
			(xy 1.679058 -63.962394) (xy 1.740153 -63.84862) (xy 1.808136 -63.738823) (xy 1.88275 -63.63342)
			(xy 1.963711 -63.53281) (xy 2.050711 -63.437375) (xy 2.143422 -63.347476) (xy 2.241492 -63.263455)
			(xy 2.344547 -63.185631) (xy 2.452198 -63.114299) (xy 2.564037 -63.049729) (xy 2.679638 -62.992167)
			(xy 2.798563 -62.94183) (xy 2.920362 -62.89891) (xy 3.044572 -62.863569) (xy 3.170721 -62.835942)
			(xy 3.298333 -62.816133) (xy 3.426922 -62.804217) (xy 3.556 -62.800241) (xy 3.685078 -62.804217)
			(xy 3.813667 -62.816133) (xy 3.941279 -62.835942) (xy 4.067428 -62.863569) (xy 4.110844 -62.875922)
			(xy 30.28417 -62.875922) (xy 30.2882 -62.733587) (xy 30.300275 -62.591707) (xy 30.320358 -62.450739)
			(xy 30.348385 -62.311132) (xy 30.384265 -62.173334) (xy 30.427883 -62.037787) (xy 30.4791 -61.904925)
			(xy 30.537751 -61.775173) (xy 30.603649 -61.648947) (xy 30.676583 -61.526651) (xy 30.75632 -61.408678)
			(xy 30.842602 -61.295405) (xy 30.935155 -61.187194) (xy 31.033682 -61.084393) (xy 31.137867 -60.987331)
			(xy 31.247376 -60.896319) (xy 31.361859 -60.811647) (xy 31.480949 -60.733589) (xy 31.604264 -60.662393)
			(xy 31.73141 -60.598287) (xy 31.861979 -60.541478) (xy 31.995553 -60.492146) (xy 32.131704 -60.45045)
			(xy 32.269995 -60.416524) (xy 32.409985 -60.390476) (xy 32.551224 -60.37239) (xy 32.69326 -60.362323)
			(xy 32.835638 -60.360308) (xy 32.977902 -60.366351) (xy 33.119596 -60.380433) (xy 33.260266 -60.402509)
			(xy 33.399463 -60.432509) (xy 33.536739 -60.470335) (xy 33.671655 -60.515867) (xy 33.803779 -60.568958)
			(xy 33.932688 -60.62944) (xy 34.057969 -60.697118) (xy 34.17922 -60.771775) (xy 34.296053 -60.853173)
			(xy 34.408094 -60.94105) (xy 34.514984 -61.035125) (xy 34.616381 -61.135097) (xy 34.711959 -61.240645)
			(xy 34.801413 -61.351431) (xy 34.884455 -61.4671) (xy 34.960821 -61.587283) (xy 35.030265 -61.711593)
			(xy 35.092565 -61.839634) (xy 35.147521 -61.970993) (xy 35.194958 -62.105252) (xy 35.234722 -62.241979)
			(xy 35.266688 -62.380737) (xy 35.290753 -62.521081) (xy 35.306839 -62.662562) (xy 35.314894 -62.804726)
			(xy 35.315398 -62.875922) (xy 35.314894 -62.947118) (xy 35.306839 -63.089282) (xy 35.290753 -63.230763)
			(xy 35.266688 -63.371107) (xy 35.234722 -63.509865) (xy 35.194958 -63.646592) (xy 35.147521 -63.780851)
			(xy 35.092565 -63.91221) (xy 35.030265 -64.040251) (xy 34.960821 -64.164561) (xy 34.884455 -64.284744)
			(xy 34.801413 -64.400413) (xy 34.711959 -64.511199) (xy 34.616381 -64.616747) (xy 34.514984 -64.716719)
			(xy 34.408094 -64.810794) (xy 34.296053 -64.898671) (xy 34.17922 -64.980069) (xy 34.057969 -65.054726)
			(xy 33.932688 -65.122404) (xy 33.803779 -65.182886) (xy 33.671655 -65.235977) (xy 33.536739 -65.281509)
			(xy 33.399463 -65.319335) (xy 33.260266 -65.349335) (xy 33.119596 -65.371411) (xy 32.977902 -65.385493)
			(xy 32.835638 -65.391536) (xy 32.69326 -65.389521) (xy 32.551224 -65.379454) (xy 32.409985 -65.361368)
			(xy 32.269995 -65.33532) (xy 32.131704 -65.301394) (xy 31.995553 -65.259698) (xy 31.861979 -65.210366)
			(xy 31.73141 -65.153557) (xy 31.604264 -65.089451) (xy 31.480949 -65.018255) (xy 31.361859 -64.940197)
			(xy 31.247376 -64.855525) (xy 31.137867 -64.764513) (xy 31.033682 -64.667451) (xy 30.935155 -64.56465)
			(xy 30.842602 -64.456439) (xy 30.75632 -64.343166) (xy 30.676583 -64.225193) (xy 30.603649 -64.102897)
			(xy 30.537751 -63.976671) (xy 30.4791 -63.846919) (xy 30.427883 -63.714057) (xy 30.384265 -63.57851)
			(xy 30.348385 -63.440712) (xy 30.320358 -63.301105) (xy 30.300275 -63.160137) (xy 30.2882 -63.018257)
			(xy 30.28417 -62.875922) (xy 4.110844 -62.875922) (xy 4.191638 -62.89891) (xy 4.313437 -62.94183)
			(xy 4.432362 -62.992167) (xy 4.547963 -63.049729) (xy 4.659802 -63.114299) (xy 4.767453 -63.185631)
			(xy 4.870508 -63.263455) (xy 4.968578 -63.347476) (xy 5.061289 -63.437375) (xy 5.148289 -63.53281)
			(xy 5.22925 -63.63342) (xy 5.303864 -63.738823) (xy 5.371847 -63.84862) (xy 5.432942 -63.962394)
			(xy 5.486917 -64.079713) (xy 5.533568 -64.200132) (xy 5.572717 -64.323195) (xy 5.604216 -64.448434)
			(xy 5.627945 -64.575375) (xy 5.643815 -64.703535) (xy 5.651765 -64.83243) (xy 5.652262 -64.897) (xy 5.651765 -64.96157)
			(xy 5.643815 -65.090465) (xy 5.627945 -65.218625) (xy 5.604216 -65.345566) (xy 5.572717 -65.470805)
			(xy 5.533568 -65.593868) (xy 5.486917 -65.714287) (xy 5.432942 -65.831606) (xy 5.371847 -65.94538)
			(xy 5.303864 -66.055177) (xy 5.22925 -66.16058) (xy 5.148289 -66.26119) (xy 5.061289 -66.356625)
			(xy 4.968578 -66.446524) (xy 4.870508 -66.530545) (xy 4.767453 -66.608369) (xy 4.659802 -66.679701)
			(xy 4.547963 -66.744271) (xy 4.432362 -66.801833) (xy 4.313437 -66.85217) (xy 4.191638 -66.89509)
			(xy 4.067428 -66.930431) (xy 3.941279 -66.958058) (xy 3.813667 -66.977867) (xy 3.685078 -66.989783)
			(xy 3.556 -66.99376) (xy 3.426922 -66.989783) (xy 3.298333 -66.977867) (xy 3.170721 -66.958058) (xy 3.044572 -66.930431)
			(xy 2.920362 -66.89509) (xy 2.798563 -66.85217) (xy 2.679638 -66.801833) (xy 2.564037 -66.744271)
			(xy 2.452198 -66.679701) (xy 2.344547 -66.608369) (xy 2.241492 -66.530545) (xy 2.143422 -66.446524)
			(xy 2.050711 -66.356625) (xy 1.963711 -66.26119) (xy 1.88275 -66.16058) (xy 1.808136 -66.055177)
			(xy 1.740153 -65.94538) (xy 1.679058 -65.831606) (xy 1.625083 -65.714287) (xy 1.578432 -65.593868)
			(xy 1.539283 -65.470805) (xy 1.507784 -65.345566) (xy 1.484055 -65.218625) (xy 1.468185 -65.090465)
			(xy 1.460235 -64.96157) (xy 0.50927 -64.96157) (xy 0.50927 -69.20484) (xy 0.509524 -69.234304) (xy 0.509524 -69.234812)
			(xy 0.5115 -69.289393) (xy 0.522454 -69.39807) (xy 0.541334 -69.505654) (xy 0.568037 -69.611568)
			(xy 0.602421 -69.715244) (xy 0.644301 -69.816124) (xy 0.693453 -69.913669) (xy 0.749612 -70.007354)
			(xy 0.812478 -70.096678) (xy 0.881713 -70.18116) (xy 0.918972 -70.221094) (xy 0.967704 -70.273113)
			(xy 1.059868 -70.381871) (xy 1.14571 -70.495685) (xy 1.224951 -70.614189) (xy 1.297336 -70.737001)
			(xy 1.362633 -70.863724) (xy 1.42063 -70.99395) (xy 1.47114 -71.127258) (xy 1.514 -71.263219) (xy 1.549073 -71.401394)
			(xy 1.576244 -71.541337) (xy 1.595427 -71.682597) (xy 1.606559 -71.824719) (xy 1.608582 -71.89597)
			(xy 1.609344 -71.959978) (xy 1.609344 -74.536356) (xy 3.591292 -74.536356) (xy 3.592399 -74.380699)
			(xy 3.601553 -74.225307) (xy 3.618731 -74.070597) (xy 3.643886 -73.916982) (xy 3.676951 -73.764873)
			(xy 3.717837 -73.614678) (xy 3.766436 -73.466797) (xy 3.822617 -73.321628) (xy 3.886229 -73.179559)
			(xy 3.957103 -73.040969) (xy 4.035049 -72.906229) (xy 4.119858 -72.7757) (xy 4.211304 -72.649732)
			(xy 4.259834 -72.588882) (xy 4.294819 -72.54475) (xy 4.358801 -72.45206) (xy 4.41561 -72.354808)
			(xy 4.464922 -72.253549) (xy 4.506456 -72.148858) (xy 4.539974 -72.041333) (xy 4.565287 -71.931586)
			(xy 4.582249 -71.820242) (xy 4.590765 -71.707936) (xy 4.591304 -71.651622) (xy 4.591304 -70.980046)
			(xy 4.591799 -70.916938) (xy 4.599725 -70.79097) (xy 4.615544 -70.665749) (xy 4.639194 -70.541768)
			(xy 4.670583 -70.419517) (xy 4.709586 -70.299478) (xy 4.756049 -70.182125) (xy 4.80979 -70.067921)
			(xy 4.870595 -69.957317) (xy 4.938225 -69.850749) (xy 5.012413 -69.748637) (xy 5.092867 -69.651386)
			(xy 5.179268 -69.559378) (xy 5.271276 -69.472977) (xy 5.368527 -69.392523) (xy 5.470639 -69.318335)
			(xy 5.577207 -69.250705) (xy 5.687811 -69.1899) (xy 5.802015 -69.136159) (xy 5.919368 -69.089696)
			(xy 6.039407 -69.050693) (xy 6.161658 -69.019304) (xy 6.285639 -68.995654) (xy 6.41086 -68.979835)
			(xy 6.536828 -68.971909) (xy 6.663044 -68.971909) (xy 6.789012 -68.979835) (xy 6.914233 -68.995654)
			(xy 7.038214 -69.019304) (xy 7.160465 -69.050693) (xy 7.280504 -69.089696) (xy 7.397857 -69.136159)
			(xy 7.512061 -69.1899) (xy 7.622665 -69.250705) (xy 7.729233 -69.318335) (xy 7.831345 -69.392523)
			(xy 7.928596 -69.472977) (xy 8.020604 -69.559378) (xy 8.107005 -69.651386) (xy 8.187459 -69.748637)
			(xy 8.261647 -69.850749) (xy 8.329277 -69.957317) (xy 8.390082 -70.067921) (xy 8.443823 -70.182125)
			(xy 8.490286 -70.299478) (xy 8.529289 -70.419517) (xy 8.539255 -70.45833) (xy 25.850088 -70.45833)
			(xy 25.850088 -69.139562) (xy 25.850553 -69.132676) (xy 25.857443 -69.120751) (xy 25.869365 -69.113856)
			(xy 25.87625 -69.1134) (xy 26.834592 -69.1134) (xy 26.841482 -69.113763) (xy 26.853393 -69.12069)
			(xy 26.860203 -69.132669) (xy 26.8605 -69.139562) (xy 26.8605 -69.139816) (xy 26.8605 -70.45833)
			(xy 26.860054 -70.465176) (xy 26.853242 -70.477054) (xy 26.841433 -70.483984) (xy 26.834592 -70.484492)
			(xy 25.87625 -70.484492) (xy 25.86936 -70.484056) (xy 25.857431 -70.477155) (xy 25.850539 -70.46522)
			(xy 25.850088 -70.45833) (xy 8.539255 -70.45833) (xy 8.560678 -70.541768) (xy 8.584328 -70.665749)
			(xy 8.600147 -70.79097) (xy 8.608073 -70.916938) (xy 8.608568 -70.980046) (xy 8.608568 -71.651876)
			(xy 8.609132 -71.708177) (xy 8.617641 -71.820457) (xy 8.634599 -71.931774) (xy 8.659908 -72.041495)
			(xy 8.693423 -72.148993) (xy 8.734954 -72.253656) (xy 8.784264 -72.354887) (xy 8.841072 -72.452108)
			(xy 8.905054 -72.544766) (xy 8.940038 -72.588882) (xy 8.988568 -72.649732) (xy 9.080014 -72.7757)
			(xy 9.164823 -72.906229) (xy 9.242769 -73.040969) (xy 9.313643 -73.179559) (xy 9.377255 -73.321628)
			(xy 9.433436 -73.466797) (xy 9.482035 -73.614678) (xy 9.522921 -73.764873) (xy 9.555986 -73.916982)
			(xy 9.581141 -74.070597) (xy 9.598319 -74.225307) (xy 9.607473 -74.380699) (xy 9.60858 -74.536356)
			(xy 9.601636 -74.691862) (xy 9.586659 -74.846801) (xy 9.586183 -74.84999) (xy 15.206728 -74.84999)
			(xy 15.210775 -74.75599) (xy 15.222889 -74.662686) (xy 15.242978 -74.570769) (xy 15.270895 -74.480919)
			(xy 15.306433 -74.393802) (xy 15.349327 -74.310062) (xy 15.399262 -74.230319) (xy 15.455867 -74.155165)
			(xy 15.518723 -74.085154) (xy 15.587365 -74.020806) (xy 15.661284 -73.962598) (xy 15.739934 -73.910959)
			(xy 15.822732 -73.866272) (xy 15.909064 -73.828868) (xy 15.998293 -73.799025) (xy 16.089756 -73.776962)
			(xy 16.182778 -73.762844) (xy 16.276669 -73.756775) (xy 16.370734 -73.758799) (xy 16.464277 -73.768902)
			(xy 16.556605 -73.787009) (xy 16.647035 -73.812986) (xy 16.734897 -73.846641) (xy 16.81954 -73.887724)
			(xy 16.900338 -73.935932) (xy 16.976694 -73.990907) (xy 17.04804 -74.052242) (xy 17.11385 -74.119483)
			(xy 17.173636 -74.192133) (xy 17.226955 -74.269653) (xy 17.273413 -74.35147) (xy 17.312666 -74.436978)
			(xy 17.344422 -74.525544) (xy 17.368447 -74.616512) (xy 17.384564 -74.709208) (xy 17.392652 -74.802947)
			(xy 17.393158 -74.84999) (xy 26.30602 -74.84999) (xy 26.310069 -74.755947) (xy 26.322188 -74.662599)
			(xy 26.342287 -74.570639) (xy 26.370217 -74.480748) (xy 26.405771 -74.39359) (xy 26.448686 -74.309811)
			(xy 26.498644 -74.230032) (xy 26.555275 -74.154842) (xy 26.61816 -74.084799) (xy 26.686834 -74.020421)
			(xy 26.760788 -73.962185) (xy 26.839474 -73.910522) (xy 26.92231 -73.865815) (xy 27.008683 -73.828394)
			(xy 27.097952 -73.798537) (xy 27.189458 -73.776464) (xy 27.282523 -73.762339) (xy 27.376458 -73.756267)
			(xy 27.470567 -73.758292) (xy 27.564153 -73.7684) (xy 27.656524 -73.786516) (xy 27.746996 -73.812505)
			(xy 27.834898 -73.846175) (xy 27.919581 -73.887277) (xy 28.000417 -73.935507) (xy 28.076808 -73.990508)
			(xy 28.148188 -74.051871) (xy 28.214028 -74.119144) (xy 28.273842 -74.191827) (xy 28.327186 -74.269384)
			(xy 28.373665 -74.351239) (xy 28.412936 -74.436786) (xy 28.444707 -74.525393) (xy 28.468744 -74.616403)
			(xy 28.484868 -74.709143) (xy 28.49296 -74.802925) (xy 28.493466 -74.84999) (xy 28.49296 -74.897055)
			(xy 28.484868 -74.990837) (xy 28.468744 -75.083577) (xy 28.444707 -75.174587) (xy 28.412936 -75.263194)
			(xy 28.373665 -75.348741) (xy 28.327186 -75.430596) (xy 28.273842 -75.508153) (xy 28.214028 -75.580836)
			(xy 28.148188 -75.648109) (xy 28.076808 -75.709472) (xy 28.000417 -75.764473) (xy 27.919581 -75.812703)
			(xy 27.834898 -75.853805) (xy 27.746996 -75.887475) (xy 27.656524 -75.913464) (xy 27.564153 -75.93158)
			(xy 27.470567 -75.941688) (xy 27.376458 -75.943713) (xy 27.282523 -75.937641) (xy 27.189458 -75.923516)
			(xy 27.097952 -75.901443) (xy 27.008683 -75.871586) (xy 26.92231 -75.834165) (xy 26.839474 -75.789458)
			(xy 26.760788 -75.737795) (xy 26.686834 -75.679559) (xy 26.61816 -75.615181) (xy 26.555275 -75.545138)
			(xy 26.498644 -75.469948) (xy 26.448686 -75.390169) (xy 26.405771 -75.30639) (xy 26.370217 -75.219232)
			(xy 26.342287 -75.129341) (xy 26.322188 -75.037381) (xy 26.310069 -74.944033) (xy 26.30602 -74.84999)
			(xy 17.393158 -74.84999) (xy 17.392652 -74.897033) (xy 17.384564 -74.990772) (xy 17.368447 -75.083468)
			(xy 17.344422 -75.174436) (xy 17.312666 -75.263002) (xy 17.273413 -75.34851) (xy 17.226955 -75.430327)
			(xy 17.173636 -75.507847) (xy 17.11385 -75.580497) (xy 17.04804 -75.647738) (xy 16.976694 -75.709073)
			(xy 16.900338 -75.764048) (xy 16.81954 -75.812256) (xy 16.734897 -75.853339) (xy 16.647035 -75.886994)
			(xy 16.556605 -75.912971) (xy 16.464277 -75.931078) (xy 16.370734 -75.941181) (xy 16.276669 -75.943205)
			(xy 16.182778 -75.937136) (xy 16.089756 -75.923018) (xy 15.998293 -75.900955) (xy 15.909064 -75.871112)
			(xy 15.822732 -75.833708) (xy 15.739934 -75.789021) (xy 15.661284 -75.737382) (xy 15.587365 -75.679174)
			(xy 15.518723 -75.614826) (xy 15.455867 -75.544815) (xy 15.399262 -75.469661) (xy 15.349327 -75.389918)
			(xy 15.306433 -75.306178) (xy 15.270895 -75.219061) (xy 15.242978 -75.129211) (xy 15.222889 -75.037294)
			(xy 15.210775 -74.94399) (xy 15.206728 -74.84999) (xy 9.586183 -74.84999) (xy 9.563691 -75.000758)
			(xy 9.532792 -75.153321) (xy 9.494045 -75.304083) (xy 9.447554 -75.452639) (xy 9.393442 -75.598592)
			(xy 9.331856 -75.741552) (xy 9.26296 -75.881135) (xy 9.186937 -76.01697) (xy 9.103993 -76.148691)
			(xy 9.014347 -76.275947) (xy 8.918241 -76.398397) (xy 8.815932 -76.515713) (xy 8.707692 -76.627582)
			(xy 8.593813 -76.733704) (xy 8.474598 -76.833795) (xy 8.350367 -76.927587) (xy 8.221452 -77.01483)
			(xy 8.088198 -77.095289) (xy 7.950962 -77.16875) (xy 7.810111 -77.235016) (xy 7.666021 -77.29391)
			(xy 7.519078 -77.345274) (xy 7.369676 -77.388971) (xy 7.218215 -77.424883) (xy 7.065098 -77.452915)
			(xy 6.910737 -77.472992) (xy 6.755545 -77.485059) (xy 6.599936 -77.489085) (xy 6.444327 -77.485059)
			(xy 6.289135 -77.472992) (xy 6.134774 -77.452915) (xy 5.981657 -77.424883) (xy 5.830196 -77.388971)
			(xy 5.680794 -77.345274) (xy 5.533851 -77.29391) (xy 5.389761 -77.235016) (xy 5.24891 -77.16875)
			(xy 5.111674 -77.095289) (xy 4.97842 -77.01483) (xy 4.849505 -76.927587) (xy 4.725274 -76.833795)
			(xy 4.606059 -76.733704) (xy 4.49218 -76.627582) (xy 4.38394 -76.515713) (xy 4.281631 -76.398397)
			(xy 4.185525 -76.275947) (xy 4.095879 -76.148691) (xy 4.012935 -76.01697) (xy 3.936912 -75.881135)
			(xy 3.868016 -75.741552) (xy 3.80643 -75.598592) (xy 3.752318 -75.452639) (xy 3.705827 -75.304083)
			(xy 3.66708 -75.153321) (xy 3.636181 -75.000758) (xy 3.613213 -74.846801) (xy 3.598236 -74.691862)
			(xy 3.591292 -74.536356) (xy 1.609344 -74.536356) (xy 1.609344 -78.01102) (xy 1.609598 -78.039976)
			(xy 1.609598 -78.040484) (xy 1.611579 -78.095259) (xy 1.622586 -78.204322) (xy 1.641574 -78.312282)
			(xy 1.668439 -78.418555) (xy 1.703038 -78.522569) (xy 1.745182 -78.62376) (xy 1.794645 -78.721583)
			(xy 1.851159 -78.815509) (xy 1.914419 -78.90503) (xy 1.984083 -78.989663) (xy 2.059775 -79.068951)
			(xy 2.141086 -79.142466) (xy 2.227577 -79.20981) (xy 2.318781 -79.270619) (xy 2.414204 -79.324566)
			(xy 2.513332 -79.371358) (xy 2.615629 -79.410744) (xy 2.720542 -79.442509) (xy 2.827505 -79.466484)
			(xy 2.93594 -79.482537) (xy 3.045262 -79.490583) (xy 3.10007 -79.491078) (xy 10.849864 -79.491078)
			(xy 10.921875 -79.491591) (xy 11.06566 -79.499855) (xy 11.208734 -79.516353) (xy 11.350626 -79.541031)
			(xy 11.490869 -79.573809) (xy 11.629 -79.614577) (xy 11.764565 -79.663202) (xy 11.897118 -79.719524)
			(xy 12.026222 -79.783357) (xy 12.151451 -79.85449) (xy 12.272394 -79.93269) (xy 12.388651 -80.0177)
			(xy 12.499841 -80.109238) (xy 12.605596 -80.207004) (xy 12.705569 -80.310675) (xy 12.79943 -80.419911)
			(xy 12.886871 -80.534351) (xy 12.967602 -80.653619) (xy 13.041359 -80.777321) (xy 13.107899 -80.905051)
			(xy 13.167001 -81.036387) (xy 13.218473 -81.170898) (xy 13.262143 -81.308139) (xy 13.297869 -81.44766)
			(xy 13.325532 -81.589001) (xy 13.345042 -81.731695) (xy 13.356334 -81.875274) (xy 13.358368 -81.947258)
			(xy 13.35913 -82.011012) (xy 13.35913 -84.160868) (xy 13.359384 -84.189824) (xy 13.359384 -84.190332)
			(xy 13.361365 -84.245107) (xy 13.372372 -84.35417) (xy 13.391359 -84.46213) (xy 13.418225 -84.568404)
			(xy 13.452823 -84.672418) (xy 13.494968 -84.77361) (xy 13.54443 -84.871433) (xy 13.600944 -84.965359)
			(xy 13.664204 -85.05488) (xy 13.733868 -85.139514) (xy 13.80956 -85.218802) (xy 13.890871 -85.292317)
			(xy 13.977362 -85.359661) (xy 14.068566 -85.420471) (xy 14.163989 -85.474418) (xy 14.263117 -85.52121)
			(xy 14.365414 -85.560596) (xy 14.470328 -85.592362) (xy 14.577291 -85.616337) (xy 14.685726 -85.63239)
			(xy 14.795047 -85.640437) (xy 14.849856 -85.640926)
		)
		(stroke
			(width 0)
			(type solid)
		)
		(fill yes)
		(layer "In1.Cu")
		(net "GND")
	)
	(gr_line
		(start 0.00127 -69.20484)
		(end 0.00127 -2.010918)
		(stroke
			(width 1.016)
			(type default)
		)
		(layer "In1.Cu")
	)
	(gr_arc
		(start 0.00127 -69.20484)
		(mid 0.143811 -69.946541)
		(end 0.55118 -70.582536)
		(stroke
			(width 1.016)
			(type default)
		)
		(layer "In1.Cu")
	)
	(gr_line
		(start 1.100074 -78.000098)
		(end 1.100074 -71.949056)
		(stroke
			(width 0.2)
			(type default)
		)
		(layer "In1.Cu")
	)
	(gr_arc
		(start 1.100074 -78.000098)
		(mid 1.685859 -79.41431)
		(end 3.10007 -80.000094)
		(stroke
			(width 0.2)
			(type default)
		)
		(layer "In1.Cu")
	)
	(gr_arc
		(start 1.100074 -71.949056)
		(mid 0.957397 -71.207453)
		(end 0.54991 -70.571614)
		(stroke
			(width 0.2)
			(type default)
		)
		(layer "In1.Cu")
	)
	(gr_line
		(start 1.101344 -78.01102)
		(end 1.101344 -71.959978)
		(stroke
			(width 1.016)
			(type default)
		)
		(layer "In1.Cu")
	)
	(gr_arc
		(start 1.101344 -78.01102)
		(mid 1.687129 -79.425231)
		(end 3.10134 -80.011016)
		(stroke
			(width 1.016)
			(type default)
		)
		(layer "In1.Cu")
	)
	(gr_arc
		(start 1.101344 -71.959978)
		(mid 0.958667 -71.218375)
		(end 0.55118 -70.582536)
		(stroke
			(width 1.016)
			(type default)
		)
		(layer "In1.Cu")
	)
	(gr_arc
		(start 1.999996 0)
		(mid 0.585785 -0.585785)
		(end 0 -1.999996)
		(stroke
			(width 0.2)
			(type default)
		)
		(layer "In1.Cu")
	)
	(gr_line
		(start 1.999996 0)
		(end 37.2999 0)
		(stroke
			(width 0.2)
			(type default)
		)
		(layer "In1.Cu")
	)
	(gr_arc
		(start 2.001266 -0.010922)
		(mid 0.587055 -0.596707)
		(end 0.00127 -2.010918)
		(stroke
			(width 1.016)
			(type default)
		)
		(layer "In1.Cu")
	)
	(gr_line
		(start 2.001266 -0.010922)
		(end 37.30117 -0.010922)
		(stroke
			(width 1.016)
			(type default)
		)
		(layer "In1.Cu")
	)
	(gr_line
		(start 10.849864 -80.000094)
		(end 3.10007 -80.000094)
		(stroke
			(width 0.2)
			(type default)
		)
		(layer "In1.Cu")
	)
	(gr_line
		(start 10.851134 -80.011016)
		(end 3.10134 -80.011016)
		(stroke
			(width 1.016)
			(type default)
		)
		(layer "In1.Cu")
	)
	(gr_line
		(start 12.84986 -84.149946)
		(end 12.84986 -82.00009)
		(stroke
			(width 0.2)
			(type default)
		)
		(layer "In1.Cu")
	)
	(gr_arc
		(start 12.84986 -84.149946)
		(mid 13.435644 -85.564161)
		(end 14.849856 -86.149942)
		(stroke
			(width 0.2)
			(type default)
		)
		(layer "In1.Cu")
	)
	(gr_arc
		(start 12.84986 -82.00009)
		(mid 12.264075 -80.585879)
		(end 10.849864 -80.000094)
		(stroke
			(width 0.2)
			(type default)
		)
		(layer "In1.Cu")
	)
	(gr_line
		(start 12.85113 -84.160868)
		(end 12.85113 -82.011012)
		(stroke
			(width 1.016)
			(type default)
		)
		(layer "In1.Cu")
	)
	(gr_arc
		(start 12.85113 -84.160868)
		(mid 13.436914 -85.575081)
		(end 14.851126 -86.160864)
		(stroke
			(width 1.016)
			(type default)
		)
		(layer "In1.Cu")
	)
	(gr_arc
		(start 12.85113 -82.011012)
		(mid 12.265345 -80.596801)
		(end 10.851134 -80.011016)
		(stroke
			(width 1.016)
			(type default)
		)
		(layer "In1.Cu")
	)
	(gr_line
		(start 28.850082 -86.149942)
		(end 14.849856 -86.149942)
		(stroke
			(width 0.2)
			(type default)
		)
		(layer "In1.Cu")
	)
	(gr_arc
		(start 28.850082 -86.149942)
		(mid 30.26429 -85.564156)
		(end 30.850078 -84.149946)
		(stroke
			(width 0.2)
			(type default)
		)
		(layer "In1.Cu")
	)
	(gr_line
		(start 28.851352 -86.160864)
		(end 14.851126 -86.160864)
		(stroke
			(width 1.016)
			(type default)
		)
		(layer "In1.Cu")
	)
	(gr_arc
		(start 28.851352 -86.160864)
		(mid 30.265561 -85.575078)
		(end 30.851348 -84.160868)
		(stroke
			(width 1.016)
			(type default)
		)
		(layer "In1.Cu")
	)
	(gr_line
		(start 30.850078 -82.00009)
		(end 30.850078 -84.149946)
		(stroke
			(width 0.2)
			(type default)
		)
		(layer "In1.Cu")
	)
	(gr_line
		(start 30.851348 -82.011012)
		(end 30.851348 -84.160868)
		(stroke
			(width 1.016)
			(type default)
		)
		(layer "In1.Cu")
	)
	(gr_arc
		(start 32.850074 -80.000094)
		(mid 31.435863 -80.585879)
		(end 30.850078 -82.00009)
		(stroke
			(width 0.2)
			(type default)
		)
		(layer "In1.Cu")
	)
	(gr_arc
		(start 32.851344 -80.011016)
		(mid 31.437133 -80.596801)
		(end 30.851348 -82.011012)
		(stroke
			(width 1.016)
			(type default)
		)
		(layer "In1.Cu")
	)
	(gr_line
		(start 36.20008 -80.000094)
		(end 32.850074 -80.000094)
		(stroke
			(width 0.2)
			(type default)
		)
		(layer "In1.Cu")
	)
	(gr_arc
		(start 36.20008 -80.000094)
		(mid 37.614303 -79.414316)
		(end 38.200076 -78.000098)
		(stroke
			(width 0.2)
			(type default)
		)
		(layer "In1.Cu")
	)
	(gr_line
		(start 36.20135 -80.011016)
		(end 32.851344 -80.011016)
		(stroke
			(width 1.016)
			(type default)
		)
		(layer "In1.Cu")
	)
	(gr_arc
		(start 36.20135 -80.011016)
		(mid 37.615561 -79.425231)
		(end 38.201346 -78.01102)
		(stroke
			(width 1.016)
			(type default)
		)
		(layer "In1.Cu")
	)
	(gr_line
		(start 38.200076 -71.949056)
		(end 38.200076 -78.000098)
		(stroke
			(width 0.2)
			(type default)
		)
		(layer "In1.Cu")
	)
	(gr_line
		(start 38.201346 -78.01102)
		(end 38.201346 -71.959978)
		(stroke
			(width 1.016)
			(type default)
		)
		(layer "In1.Cu")
	)
	(gr_arc
		(start 38.749986 -70.571614)
		(mid 38.342614 -71.207474)
		(end 38.200076 -71.949056)
		(stroke
			(width 0.2)
			(type default)
		)
		(layer "In1.Cu")
	)
	(gr_arc
		(start 38.749986 -70.571614)
		(mid 39.157396 -69.935635)
		(end 39.299896 -69.193918)
		(stroke
			(width 0.2)
			(type default)
		)
		(layer "In1.Cu")
	)
	(gr_arc
		(start 38.751256 -70.582536)
		(mid 38.343908 -71.218402)
		(end 38.201346 -71.959978)
		(stroke
			(width 1.016)
			(type default)
		)
		(layer "In1.Cu")
	)
	(gr_arc
		(start 38.751256 -70.582536)
		(mid 39.158647 -69.946554)
		(end 39.301166 -69.20484)
		(stroke
			(width 1.016)
			(type default)
		)
		(layer "In1.Cu")
	)
	(gr_arc
		(start 39.299896 -1.999996)
		(mid 38.714109 -0.585788)
		(end 37.2999 0)
		(stroke
			(width 0.2)
			(type default)
		)
		(layer "In1.Cu")
	)
	(gr_line
		(start 39.299896 -1.999996)
		(end 39.299896 -69.193918)
		(stroke
			(width 0.2)
			(type default)
		)
		(layer "In1.Cu")
	)
	(gr_arc
		(start 39.301166 -2.010918)
		(mid 38.715385 -0.596706)
		(end 37.30117 -0.010922)
		(stroke
			(width 1.016)
			(type default)
		)
		(layer "In1.Cu")
	)
	(gr_line
		(start 39.301166 -2.010918)
		(end 39.301166 -69.20484)
		(stroke
			(width 1.016)
			(type default)
		)
		(layer "In1.Cu")
	)
	(gr_poly
		(pts
			(xy 99.039934 -69.308726) (xy 99.049939 -69.308233) (xy 99.068424 -69.300568) (xy 99.082572 -69.286417)
			(xy 99.090234 -69.267931) (xy 99.090734 -69.257926) (xy 99.090734 -2.008378) (xy 99.090209 -1.952315)
			(xy 99.081828 -1.840503) (xy 99.065115 -1.72963) (xy 99.040163 -1.620317) (xy 99.007112 -1.513173)
			(xy 98.966147 -1.408799) (xy 98.917496 -1.307778) (xy 98.861432 -1.210675) (xy 98.798268 -1.118034)
			(xy 98.728358 -1.030371) (xy 98.652092 -0.948179) (xy 98.569897 -0.871915) (xy 98.482233 -0.802007)
			(xy 98.389589 -0.738846) (xy 98.292485 -0.682784) (xy 98.191463 -0.634136) (xy 98.087087 -0.593174)
			(xy 97.979943 -0.560126) (xy 97.870628 -0.535177) (xy 97.759755 -0.518467) (xy 97.647943 -0.510089)
			(xy 97.59188 -0.509524) (xy 84.637118 -0.509524) (xy 84.620862 -0.509524) (xy 84.620354 -0.509524)
			(xy 84.566389 -0.510014) (xy 84.458734 -0.51773) (xy 84.351904 -0.533104) (xy 84.246442 -0.556059)
			(xy 84.142887 -0.586478) (xy 84.041765 -0.624205) (xy 83.943591 -0.669049) (xy 83.848866 -0.720781)
			(xy 83.758071 -0.779137) (xy 83.671671 -0.843821) (xy 83.590104 -0.914502) (xy 83.513786 -0.990821)
			(xy 83.443106 -1.072389) (xy 83.378423 -1.158791) (xy 83.320068 -1.249586) (xy 83.268338 -1.344312)
			(xy 83.223496 -1.442487) (xy 83.18577 -1.54361) (xy 83.155353 -1.647166) (xy 83.1324 -1.752628) (xy 83.117027 -1.859458)
			(xy 83.109313 -1.967113) (xy 83.1088 -2.021078) (xy 83.1088 -2.021586) (xy 83.1088 -2.037842) (xy 83.1088 -5.06456)
			(xy 92.503995 -5.06456) (xy 92.503995 -4.93542) (xy 92.511945 -4.806525) (xy 92.527815 -4.678365)
			(xy 92.551544 -4.551424) (xy 92.583043 -4.426185) (xy 92.622192 -4.303122) (xy 92.668843 -4.182703)
			(xy 92.722818 -4.065384) (xy 92.783913 -3.95161) (xy 92.851896 -3.841813) (xy 92.92651 -3.73641)
			(xy 93.007471 -3.6358) (xy 93.094471 -3.540365) (xy 93.187182 -3.450466) (xy 93.285252 -3.366445)
			(xy 93.388307 -3.288621) (xy 93.495958 -3.217289) (xy 93.607797 -3.152719) (xy 93.723398 -3.095157)
			(xy 93.842323 -3.04482) (xy 93.964122 -3.0019) (xy 94.088332 -2.966559) (xy 94.214481 -2.938932)
			(xy 94.342093 -2.919123) (xy 94.470682 -2.907207) (xy 94.59976 -2.903231) (xy 94.728838 -2.907207)
			(xy 94.857427 -2.919123) (xy 94.985039 -2.938932) (xy 95.111188 -2.966559) (xy 95.235398 -3.0019)
			(xy 95.357197 -3.04482) (xy 95.476122 -3.095157) (xy 95.591723 -3.152719) (xy 95.703562 -3.217289)
			(xy 95.811213 -3.288621) (xy 95.914268 -3.366445) (xy 96.012338 -3.450466) (xy 96.105049 -3.540365)
			(xy 96.192049 -3.6358) (xy 96.27301 -3.73641) (xy 96.347624 -3.841813) (xy 96.415607 -3.95161) (xy 96.476702 -4.065384)
			(xy 96.530677 -4.182703) (xy 96.577328 -4.303122) (xy 96.616477 -4.426185) (xy 96.647976 -4.551424)
			(xy 96.671705 -4.678365) (xy 96.687575 -4.806525) (xy 96.695525 -4.93542) (xy 96.696022 -4.99999)
			(xy 96.695525 -5.06456) (xy 96.687575 -5.193455) (xy 96.671705 -5.321615) (xy 96.647976 -5.448556)
			(xy 96.616477 -5.573795) (xy 96.577328 -5.696858) (xy 96.530677 -5.817277) (xy 96.476702 -5.934596)
			(xy 96.415607 -6.04837) (xy 96.347624 -6.158167) (xy 96.27301 -6.26357) (xy 96.192049 -6.36418) (xy 96.105049 -6.459615)
			(xy 96.012338 -6.549514) (xy 95.914268 -6.633535) (xy 95.811213 -6.711359) (xy 95.703562 -6.782691)
			(xy 95.591723 -6.847261) (xy 95.476122 -6.904823) (xy 95.357197 -6.95516) (xy 95.235398 -6.99808)
			(xy 95.111188 -7.033421) (xy 94.985039 -7.061048) (xy 94.857427 -7.080857) (xy 94.728838 -7.092773)
			(xy 94.59976 -7.09675) (xy 94.470682 -7.092773) (xy 94.342093 -7.080857) (xy 94.214481 -7.061048)
			(xy 94.088332 -7.033421) (xy 93.964122 -6.99808) (xy 93.842323 -6.95516) (xy 93.723398 -6.904823)
			(xy 93.607797 -6.847261) (xy 93.495958 -6.782691) (xy 93.388307 -6.711359) (xy 93.285252 -6.633535)
			(xy 93.187182 -6.549514) (xy 93.094471 -6.459615) (xy 93.007471 -6.36418) (xy 92.92651 -6.26357)
			(xy 92.851896 -6.158167) (xy 92.783913 -6.04837) (xy 92.722818 -5.934596) (xy 92.668843 -5.817277)
			(xy 92.622192 -5.696858) (xy 92.583043 -5.573795) (xy 92.551544 -5.448556) (xy 92.527815 -5.321615)
			(xy 92.511945 -5.193455) (xy 92.503995 -5.06456) (xy 83.1088 -5.06456) (xy 83.1088 -47.75962) (xy 83.107784 -47.760636)
			(xy 83.107784 -48.899064) (xy 83.1088 -48.90008) (xy 83.1088 -69.257926) (xy 83.109293 -69.26793)
			(xy 83.116957 -69.286413) (xy 83.131109 -69.300558) (xy 83.149596 -69.308212) (xy 83.1596 -69.308726)
		)
		(stroke
			(width 0)
			(type solid)
		)
		(fill yes)
		(layer "In2.Cu")
		(net "GND_TDR")
	)
	(gr_poly
		(pts
			(xy 97.59188 -173.79188) (xy 97.647944 -173.791357) (xy 97.75976 -173.782979) (xy 97.870636 -173.766268)
			(xy 97.979954 -173.741319) (xy 98.087102 -173.70827) (xy 98.19148 -173.667306) (xy 98.292505 -173.618657)
			(xy 98.389613 -173.562594) (xy 98.482259 -173.499431) (xy 98.569925 -173.429521) (xy 98.652123 -173.353255)
			(xy 98.728391 -173.27106) (xy 98.798304 -173.183396) (xy 98.861469 -173.090751) (xy 98.917535 -172.993646)
			(xy 98.966188 -172.892622) (xy 99.007155 -172.788245) (xy 99.040207 -172.681099) (xy 99.06516 -172.571782)
			(xy 99.081874 -172.460905) (xy 99.090255 -172.34909) (xy 99.090734 -172.293026) (xy 99.090734 -69.867526)
			(xy 99.090251 -69.857512) (xy 99.082597 -69.839006) (xy 99.068445 -69.824836) (xy 99.049947 -69.817161)
			(xy 99.039934 -69.816726) (xy 83.1596 -69.816726) (xy 83.149581 -69.817146) (xy 83.131068 -69.824817)
			(xy 83.116902 -69.83899) (xy 83.109241 -69.857506) (xy 83.1088 -69.867526) (xy 83.1088 -80.392219)
			(xy 93.052633 -80.392219) (xy 93.052633 -80.306469) (xy 93.060545 -80.221086) (xy 93.076301 -80.136796)
			(xy 93.099768 -80.05432) (xy 93.130744 -79.974361) (xy 93.168966 -79.897601) (xy 93.214107 -79.824695)
			(xy 93.265783 -79.756266) (xy 93.323552 -79.692896) (xy 93.386922 -79.635127) (xy 93.455351 -79.583451)
			(xy 93.528257 -79.53831) (xy 93.605017 -79.500088) (xy 93.684976 -79.469112) (xy 93.767452 -79.445645)
			(xy 93.851742 -79.429889) (xy 93.937125 -79.421977) (xy 94.022875 -79.421977) (xy 94.108258 -79.429889)
			(xy 94.192548 -79.445645) (xy 94.275024 -79.469112) (xy 94.354983 -79.500088) (xy 94.431743 -79.53831)
			(xy 94.504649 -79.583451) (xy 94.573078 -79.635127) (xy 94.636448 -79.692896) (xy 94.694217 -79.756266)
			(xy 94.745893 -79.824695) (xy 94.791034 -79.897601) (xy 94.829256 -79.974361) (xy 94.860232 -80.05432)
			(xy 94.883699 -80.136796) (xy 94.899455 -80.221086) (xy 94.907367 -80.306469) (xy 94.907862 -80.349344)
			(xy 94.907367 -80.392219) (xy 95.592633 -80.392219) (xy 95.592633 -80.306469) (xy 95.600545 -80.221086)
			(xy 95.616301 -80.136796) (xy 95.639768 -80.05432) (xy 95.670744 -79.974361) (xy 95.708966 -79.897601)
			(xy 95.754107 -79.824695) (xy 95.805783 -79.756266) (xy 95.863552 -79.692896) (xy 95.926922 -79.635127)
			(xy 95.995351 -79.583451) (xy 96.068257 -79.53831) (xy 96.145017 -79.500088) (xy 96.224976 -79.469112)
			(xy 96.307452 -79.445645) (xy 96.391742 -79.429889) (xy 96.477125 -79.421977) (xy 96.562875 -79.421977)
			(xy 96.648258 -79.429889) (xy 96.732548 -79.445645) (xy 96.815024 -79.469112) (xy 96.894983 -79.500088)
			(xy 96.971743 -79.53831) (xy 97.044649 -79.583451) (xy 97.113078 -79.635127) (xy 97.176448 -79.692896)
			(xy 97.234217 -79.756266) (xy 97.285893 -79.824695) (xy 97.331034 -79.897601) (xy 97.369256 -79.974361)
			(xy 97.400232 -80.05432) (xy 97.423699 -80.136796) (xy 97.439455 -80.221086) (xy 97.447367 -80.306469)
			(xy 97.447862 -80.349344) (xy 97.447367 -80.392219) (xy 97.439455 -80.477602) (xy 97.423699 -80.561892)
			(xy 97.400232 -80.644368) (xy 97.369256 -80.724327) (xy 97.331034 -80.801087) (xy 97.285893 -80.873993)
			(xy 97.234217 -80.942422) (xy 97.176448 -81.005792) (xy 97.113078 -81.063561) (xy 97.044649 -81.115237)
			(xy 96.971743 -81.160378) (xy 96.894983 -81.1986) (xy 96.815024 -81.229576) (xy 96.732548 -81.253043)
			(xy 96.648258 -81.268799) (xy 96.562875 -81.276711) (xy 96.477125 -81.276711) (xy 96.391742 -81.268799)
			(xy 96.307452 -81.253043) (xy 96.224976 -81.229576) (xy 96.145017 -81.1986) (xy 96.068257 -81.160378)
			(xy 95.995351 -81.115237) (xy 95.926922 -81.063561) (xy 95.863552 -81.005792) (xy 95.805783 -80.942422)
			(xy 95.754107 -80.873993) (xy 95.708966 -80.801087) (xy 95.670744 -80.724327) (xy 95.639768 -80.644368)
			(xy 95.616301 -80.561892) (xy 95.600545 -80.477602) (xy 95.592633 -80.392219) (xy 94.907367 -80.392219)
			(xy 94.899455 -80.477602) (xy 94.883699 -80.561892) (xy 94.860232 -80.644368) (xy 94.829256 -80.724327)
			(xy 94.791034 -80.801087) (xy 94.745893 -80.873993) (xy 94.694217 -80.942422) (xy 94.636448 -81.005792)
			(xy 94.573078 -81.063561) (xy 94.504649 -81.115237) (xy 94.431743 -81.160378) (xy 94.354983 -81.1986)
			(xy 94.275024 -81.229576) (xy 94.192548 -81.253043) (xy 94.108258 -81.268799) (xy 94.022875 -81.276711)
			(xy 93.937125 -81.276711) (xy 93.851742 -81.268799) (xy 93.767452 -81.253043) (xy 93.684976 -81.229576)
			(xy 93.605017 -81.1986) (xy 93.528257 -81.160378) (xy 93.455351 -81.115237) (xy 93.386922 -81.063561)
			(xy 93.323552 -81.005792) (xy 93.265783 -80.942422) (xy 93.214107 -80.873993) (xy 93.168966 -80.801087)
			(xy 93.130744 -80.724327) (xy 93.099768 -80.644368) (xy 93.076301 -80.561892) (xy 93.060545 -80.477602)
			(xy 93.052633 -80.392219) (xy 83.1088 -80.392219) (xy 83.1088 -86.742219) (xy 93.052633 -86.742219)
			(xy 93.052633 -86.656469) (xy 93.060545 -86.571086) (xy 93.076301 -86.486796) (xy 93.099768 -86.40432)
			(xy 93.130744 -86.324361) (xy 93.168966 -86.247601) (xy 93.214107 -86.174695) (xy 93.265783 -86.106266)
			(xy 93.323552 -86.042896) (xy 93.386922 -85.985127) (xy 93.455351 -85.933451) (xy 93.528257 -85.88831)
			(xy 93.605017 -85.850088) (xy 93.684976 -85.819112) (xy 93.767452 -85.795645) (xy 93.851742 -85.779889)
			(xy 93.937125 -85.771977) (xy 94.022875 -85.771977) (xy 94.108258 -85.779889) (xy 94.192548 -85.795645)
			(xy 94.275024 -85.819112) (xy 94.354983 -85.850088) (xy 94.431743 -85.88831) (xy 94.504649 -85.933451)
			(xy 94.573078 -85.985127) (xy 94.636448 -86.042896) (xy 94.694217 -86.106266) (xy 94.745893 -86.174695)
			(xy 94.791034 -86.247601) (xy 94.829256 -86.324361) (xy 94.860232 -86.40432) (xy 94.883699 -86.486796)
			(xy 94.899455 -86.571086) (xy 94.907367 -86.656469) (xy 94.907862 -86.699344) (xy 94.907367 -86.742219)
			(xy 95.592633 -86.742219) (xy 95.592633 -86.656469) (xy 95.600545 -86.571086) (xy 95.616301 -86.486796)
			(xy 95.639768 -86.40432) (xy 95.670744 -86.324361) (xy 95.708966 -86.247601) (xy 95.754107 -86.174695)
			(xy 95.805783 -86.106266) (xy 95.863552 -86.042896) (xy 95.926922 -85.985127) (xy 95.995351 -85.933451)
			(xy 96.068257 -85.88831) (xy 96.145017 -85.850088) (xy 96.224976 -85.819112) (xy 96.307452 -85.795645)
			(xy 96.391742 -85.779889) (xy 96.477125 -85.771977) (xy 96.562875 -85.771977) (xy 96.648258 -85.779889)
			(xy 96.732548 -85.795645) (xy 96.815024 -85.819112) (xy 96.894983 -85.850088) (xy 96.971743 -85.88831)
			(xy 97.044649 -85.933451) (xy 97.113078 -85.985127) (xy 97.176448 -86.042896) (xy 97.234217 -86.106266)
			(xy 97.285893 -86.174695) (xy 97.331034 -86.247601) (xy 97.369256 -86.324361) (xy 97.400232 -86.40432)
			(xy 97.423699 -86.486796) (xy 97.439455 -86.571086) (xy 97.447367 -86.656469) (xy 97.447862 -86.699344)
			(xy 97.447367 -86.742219) (xy 97.439455 -86.827602) (xy 97.423699 -86.911892) (xy 97.400232 -86.994368)
			(xy 97.369256 -87.074327) (xy 97.331034 -87.151087) (xy 97.285893 -87.223993) (xy 97.234217 -87.292422)
			(xy 97.176448 -87.355792) (xy 97.113078 -87.413561) (xy 97.044649 -87.465237) (xy 96.971743 -87.510378)
			(xy 96.894983 -87.5486) (xy 96.815024 -87.579576) (xy 96.732548 -87.603043) (xy 96.648258 -87.618799)
			(xy 96.562875 -87.626711) (xy 96.477125 -87.626711) (xy 96.391742 -87.618799) (xy 96.307452 -87.603043)
			(xy 96.224976 -87.579576) (xy 96.145017 -87.5486) (xy 96.068257 -87.510378) (xy 95.995351 -87.465237)
			(xy 95.926922 -87.413561) (xy 95.863552 -87.355792) (xy 95.805783 -87.292422) (xy 95.754107 -87.223993)
			(xy 95.708966 -87.151087) (xy 95.670744 -87.074327) (xy 95.639768 -86.994368) (xy 95.616301 -86.911892)
			(xy 95.600545 -86.827602) (xy 95.592633 -86.742219) (xy 94.907367 -86.742219) (xy 94.899455 -86.827602)
			(xy 94.883699 -86.911892) (xy 94.860232 -86.994368) (xy 94.829256 -87.074327) (xy 94.791034 -87.151087)
			(xy 94.745893 -87.223993) (xy 94.694217 -87.292422) (xy 94.636448 -87.355792) (xy 94.573078 -87.413561)
			(xy 94.504649 -87.465237) (xy 94.431743 -87.510378) (xy 94.354983 -87.5486) (xy 94.275024 -87.579576)
			(xy 94.192548 -87.603043) (xy 94.108258 -87.618799) (xy 94.022875 -87.626711) (xy 93.937125 -87.626711)
			(xy 93.851742 -87.618799) (xy 93.767452 -87.603043) (xy 93.684976 -87.579576) (xy 93.605017 -87.5486)
			(xy 93.528257 -87.510378) (xy 93.455351 -87.465237) (xy 93.386922 -87.413561) (xy 93.323552 -87.355792)
			(xy 93.265783 -87.292422) (xy 93.214107 -87.223993) (xy 93.168966 -87.151087) (xy 93.130744 -87.074327)
			(xy 93.099768 -86.994368) (xy 93.076301 -86.911892) (xy 93.060545 -86.827602) (xy 93.052633 -86.742219)
			(xy 83.1088 -86.742219) (xy 83.1088 -106.760975) (xy 85.559633 -106.760975) (xy 85.559633 -106.675225)
			(xy 85.567545 -106.589842) (xy 85.583301 -106.505552) (xy 85.606768 -106.423076) (xy 85.637744 -106.343117)
			(xy 85.675966 -106.266357) (xy 85.721107 -106.193451) (xy 85.772783 -106.125022) (xy 85.830552 -106.061652)
			(xy 85.893922 -106.003883) (xy 85.962351 -105.952207) (xy 86.035257 -105.907066) (xy 86.112017 -105.868844)
			(xy 86.191976 -105.837868) (xy 86.274452 -105.814401) (xy 86.358742 -105.798645) (xy 86.444125 -105.790733)
			(xy 86.529875 -105.790733) (xy 86.615258 -105.798645) (xy 86.699548 -105.814401) (xy 86.782024 -105.837868)
			(xy 86.861983 -105.868844) (xy 86.938743 -105.907066) (xy 87.011649 -105.952207) (xy 87.080078 -106.003883)
			(xy 87.143448 -106.061652) (xy 87.201217 -106.125022) (xy 87.252893 -106.193451) (xy 87.298034 -106.266357)
			(xy 87.336256 -106.343117) (xy 87.367232 -106.423076) (xy 87.390699 -106.505552) (xy 87.406455 -106.589842)
			(xy 87.414367 -106.675225) (xy 87.414862 -106.7181) (xy 87.414367 -106.760975) (xy 88.099633 -106.760975)
			(xy 88.099633 -106.675225) (xy 88.107545 -106.589842) (xy 88.123301 -106.505552) (xy 88.146768 -106.423076)
			(xy 88.177744 -106.343117) (xy 88.215966 -106.266357) (xy 88.261107 -106.193451) (xy 88.312783 -106.125022)
			(xy 88.370552 -106.061652) (xy 88.433922 -106.003883) (xy 88.502351 -105.952207) (xy 88.575257 -105.907066)
			(xy 88.652017 -105.868844) (xy 88.731976 -105.837868) (xy 88.814452 -105.814401) (xy 88.898742 -105.798645)
			(xy 88.984125 -105.790733) (xy 89.069875 -105.790733) (xy 89.155258 -105.798645) (xy 89.239548 -105.814401)
			(xy 89.322024 -105.837868) (xy 89.401983 -105.868844) (xy 89.478743 -105.907066) (xy 89.551649 -105.952207)
			(xy 89.620078 -106.003883) (xy 89.683448 -106.061652) (xy 89.741217 -106.125022) (xy 89.792893 -106.193451)
			(xy 89.838034 -106.266357) (xy 89.876256 -106.343117) (xy 89.907232 -106.423076) (xy 89.930699 -106.505552)
			(xy 89.946455 -106.589842) (xy 89.954367 -106.675225) (xy 89.954862 -106.7181) (xy 89.954367 -106.760975)
			(xy 89.946455 -106.846358) (xy 89.930699 -106.930648) (xy 89.907232 -107.013124) (xy 89.876256 -107.093083)
			(xy 89.838034 -107.169843) (xy 89.792893 -107.242749) (xy 89.741217 -107.311178) (xy 89.683448 -107.374548)
			(xy 89.620078 -107.432317) (xy 89.551649 -107.483993) (xy 89.478743 -107.529134) (xy 89.401983 -107.567356)
			(xy 89.322024 -107.598332) (xy 89.239548 -107.621799) (xy 89.155258 -107.637555) (xy 89.069875 -107.645467)
			(xy 88.984125 -107.645467) (xy 88.898742 -107.637555) (xy 88.814452 -107.621799) (xy 88.731976 -107.598332)
			(xy 88.652017 -107.567356) (xy 88.575257 -107.529134) (xy 88.502351 -107.483993) (xy 88.433922 -107.432317)
			(xy 88.370552 -107.374548) (xy 88.312783 -107.311178) (xy 88.261107 -107.242749) (xy 88.215966 -107.169843)
			(xy 88.177744 -107.093083) (xy 88.146768 -107.013124) (xy 88.123301 -106.930648) (xy 88.107545 -106.846358)
			(xy 88.099633 -106.760975) (xy 87.414367 -106.760975) (xy 87.406455 -106.846358) (xy 87.390699 -106.930648)
			(xy 87.367232 -107.013124) (xy 87.336256 -107.093083) (xy 87.298034 -107.169843) (xy 87.252893 -107.242749)
			(xy 87.201217 -107.311178) (xy 87.143448 -107.374548) (xy 87.080078 -107.432317) (xy 87.011649 -107.483993)
			(xy 86.938743 -107.529134) (xy 86.861983 -107.567356) (xy 86.782024 -107.598332) (xy 86.699548 -107.621799)
			(xy 86.615258 -107.637555) (xy 86.529875 -107.645467) (xy 86.444125 -107.645467) (xy 86.358742 -107.637555)
			(xy 86.274452 -107.621799) (xy 86.191976 -107.598332) (xy 86.112017 -107.567356) (xy 86.035257 -107.529134)
			(xy 85.962351 -107.483993) (xy 85.893922 -107.432317) (xy 85.830552 -107.374548) (xy 85.772783 -107.311178)
			(xy 85.721107 -107.242749) (xy 85.675966 -107.169843) (xy 85.637744 -107.093083) (xy 85.606768 -107.013124)
			(xy 85.583301 -106.930648) (xy 85.567545 -106.846358) (xy 85.559633 -106.760975) (xy 83.1088 -106.760975)
			(xy 83.1088 -113.110975) (xy 85.559633 -113.110975) (xy 85.559633 -113.025225) (xy 85.567545 -112.939842)
			(xy 85.583301 -112.855552) (xy 85.606768 -112.773076) (xy 85.637744 -112.693117) (xy 85.675966 -112.616357)
			(xy 85.721107 -112.543451) (xy 85.772783 -112.475022) (xy 85.830552 -112.411652) (xy 85.893922 -112.353883)
			(xy 85.962351 -112.302207) (xy 86.035257 -112.257066) (xy 86.112017 -112.218844) (xy 86.191976 -112.187868)
			(xy 86.274452 -112.164401) (xy 86.358742 -112.148645) (xy 86.444125 -112.140733) (xy 86.529875 -112.140733)
			(xy 86.615258 -112.148645) (xy 86.699548 -112.164401) (xy 86.782024 -112.187868) (xy 86.861983 -112.218844)
			(xy 86.938743 -112.257066) (xy 87.011649 -112.302207) (xy 87.080078 -112.353883) (xy 87.143448 -112.411652)
			(xy 87.201217 -112.475022) (xy 87.252893 -112.543451) (xy 87.298034 -112.616357) (xy 87.336256 -112.693117)
			(xy 87.367232 -112.773076) (xy 87.390699 -112.855552) (xy 87.406455 -112.939842) (xy 87.414367 -113.025225)
			(xy 87.414862 -113.0681) (xy 87.414367 -113.110975) (xy 88.099633 -113.110975) (xy 88.099633 -113.025225)
			(xy 88.107545 -112.939842) (xy 88.123301 -112.855552) (xy 88.146768 -112.773076) (xy 88.177744 -112.693117)
			(xy 88.215966 -112.616357) (xy 88.261107 -112.543451) (xy 88.312783 -112.475022) (xy 88.370552 -112.411652)
			(xy 88.433922 -112.353883) (xy 88.502351 -112.302207) (xy 88.575257 -112.257066) (xy 88.652017 -112.218844)
			(xy 88.731976 -112.187868) (xy 88.814452 -112.164401) (xy 88.898742 -112.148645) (xy 88.984125 -112.140733)
			(xy 89.069875 -112.140733) (xy 89.155258 -112.148645) (xy 89.239548 -112.164401) (xy 89.322024 -112.187868)
			(xy 89.401983 -112.218844) (xy 89.478743 -112.257066) (xy 89.551649 -112.302207) (xy 89.620078 -112.353883)
			(xy 89.683448 -112.411652) (xy 89.741217 -112.475022) (xy 89.792893 -112.543451) (xy 89.838034 -112.616357)
			(xy 89.876256 -112.693117) (xy 89.907232 -112.773076) (xy 89.930699 -112.855552) (xy 89.946455 -112.939842)
			(xy 89.954367 -113.025225) (xy 89.954862 -113.0681) (xy 89.954367 -113.110975) (xy 89.946455 -113.196358)
			(xy 89.930699 -113.280648) (xy 89.907232 -113.363124) (xy 89.876256 -113.443083) (xy 89.838034 -113.519843)
			(xy 89.792893 -113.592749) (xy 89.741217 -113.661178) (xy 89.683448 -113.724548) (xy 89.620078 -113.782317)
			(xy 89.551649 -113.833993) (xy 89.478743 -113.879134) (xy 89.401983 -113.917356) (xy 89.322024 -113.948332)
			(xy 89.239548 -113.971799) (xy 89.155258 -113.987555) (xy 89.069875 -113.995467) (xy 88.984125 -113.995467)
			(xy 88.898742 -113.987555) (xy 88.814452 -113.971799) (xy 88.731976 -113.948332) (xy 88.652017 -113.917356)
			(xy 88.575257 -113.879134) (xy 88.502351 -113.833993) (xy 88.433922 -113.782317) (xy 88.370552 -113.724548)
			(xy 88.312783 -113.661178) (xy 88.261107 -113.592749) (xy 88.215966 -113.519843) (xy 88.177744 -113.443083)
			(xy 88.146768 -113.363124) (xy 88.123301 -113.280648) (xy 88.107545 -113.196358) (xy 88.099633 -113.110975)
			(xy 87.414367 -113.110975) (xy 87.406455 -113.196358) (xy 87.390699 -113.280648) (xy 87.367232 -113.363124)
			(xy 87.336256 -113.443083) (xy 87.298034 -113.519843) (xy 87.252893 -113.592749) (xy 87.201217 -113.661178)
			(xy 87.143448 -113.724548) (xy 87.080078 -113.782317) (xy 87.011649 -113.833993) (xy 86.938743 -113.879134)
			(xy 86.861983 -113.917356) (xy 86.782024 -113.948332) (xy 86.699548 -113.971799) (xy 86.615258 -113.987555)
			(xy 86.529875 -113.995467) (xy 86.444125 -113.995467) (xy 86.358742 -113.987555) (xy 86.274452 -113.971799)
			(xy 86.191976 -113.948332) (xy 86.112017 -113.917356) (xy 86.035257 -113.879134) (xy 85.962351 -113.833993)
			(xy 85.893922 -113.782317) (xy 85.830552 -113.724548) (xy 85.772783 -113.661178) (xy 85.721107 -113.592749)
			(xy 85.675966 -113.519843) (xy 85.637744 -113.443083) (xy 85.606768 -113.363124) (xy 85.583301 -113.280648)
			(xy 85.567545 -113.196358) (xy 85.559633 -113.110975) (xy 83.1088 -113.110975) (xy 83.1088 -151.769775)
			(xy 85.559633 -151.769775) (xy 85.559633 -151.684025) (xy 85.567545 -151.598642) (xy 85.583301 -151.514352)
			(xy 85.606768 -151.431876) (xy 85.637744 -151.351917) (xy 85.675966 -151.275157) (xy 85.721107 -151.202251)
			(xy 85.772783 -151.133822) (xy 85.830552 -151.070452) (xy 85.893922 -151.012683) (xy 85.962351 -150.961007)
			(xy 86.035257 -150.915866) (xy 86.112017 -150.877644) (xy 86.191976 -150.846668) (xy 86.274452 -150.823201)
			(xy 86.358742 -150.807445) (xy 86.444125 -150.799533) (xy 86.529875 -150.799533) (xy 86.615258 -150.807445)
			(xy 86.699548 -150.823201) (xy 86.782024 -150.846668) (xy 86.861983 -150.877644) (xy 86.938743 -150.915866)
			(xy 87.011649 -150.961007) (xy 87.080078 -151.012683) (xy 87.143448 -151.070452) (xy 87.201217 -151.133822)
			(xy 87.252893 -151.202251) (xy 87.298034 -151.275157) (xy 87.336256 -151.351917) (xy 87.367232 -151.431876)
			(xy 87.390699 -151.514352) (xy 87.406455 -151.598642) (xy 87.414367 -151.684025) (xy 87.414862 -151.7269)
			(xy 87.414367 -151.769775) (xy 88.099633 -151.769775) (xy 88.099633 -151.684025) (xy 88.107545 -151.598642)
			(xy 88.123301 -151.514352) (xy 88.146768 -151.431876) (xy 88.177744 -151.351917) (xy 88.215966 -151.275157)
			(xy 88.261107 -151.202251) (xy 88.312783 -151.133822) (xy 88.370552 -151.070452) (xy 88.433922 -151.012683)
			(xy 88.502351 -150.961007) (xy 88.575257 -150.915866) (xy 88.652017 -150.877644) (xy 88.731976 -150.846668)
			(xy 88.814452 -150.823201) (xy 88.898742 -150.807445) (xy 88.984125 -150.799533) (xy 89.069875 -150.799533)
			(xy 89.155258 -150.807445) (xy 89.239548 -150.823201) (xy 89.322024 -150.846668) (xy 89.401983 -150.877644)
			(xy 89.478743 -150.915866) (xy 89.551649 -150.961007) (xy 89.620078 -151.012683) (xy 89.683448 -151.070452)
			(xy 89.741217 -151.133822) (xy 89.792893 -151.202251) (xy 89.838034 -151.275157) (xy 89.876256 -151.351917)
			(xy 89.907232 -151.431876) (xy 89.930699 -151.514352) (xy 89.946455 -151.598642) (xy 89.954367 -151.684025)
			(xy 89.954862 -151.7269) (xy 89.954367 -151.769775) (xy 93.052633 -151.769775) (xy 93.052633 -151.684025)
			(xy 93.060545 -151.598642) (xy 93.076301 -151.514352) (xy 93.099768 -151.431876) (xy 93.130744 -151.351917)
			(xy 93.168966 -151.275157) (xy 93.214107 -151.202251) (xy 93.265783 -151.133822) (xy 93.323552 -151.070452)
			(xy 93.386922 -151.012683) (xy 93.455351 -150.961007) (xy 93.528257 -150.915866) (xy 93.605017 -150.877644)
			(xy 93.684976 -150.846668) (xy 93.767452 -150.823201) (xy 93.851742 -150.807445) (xy 93.937125 -150.799533)
			(xy 94.022875 -150.799533) (xy 94.108258 -150.807445) (xy 94.192548 -150.823201) (xy 94.275024 -150.846668)
			(xy 94.354983 -150.877644) (xy 94.431743 -150.915866) (xy 94.504649 -150.961007) (xy 94.573078 -151.012683)
			(xy 94.636448 -151.070452) (xy 94.694217 -151.133822) (xy 94.745893 -151.202251) (xy 94.791034 -151.275157)
			(xy 94.829256 -151.351917) (xy 94.860232 -151.431876) (xy 94.883699 -151.514352) (xy 94.899455 -151.598642)
			(xy 94.907367 -151.684025) (xy 94.907862 -151.7269) (xy 94.907367 -151.769775) (xy 95.592633 -151.769775)
			(xy 95.592633 -151.684025) (xy 95.600545 -151.598642) (xy 95.616301 -151.514352) (xy 95.639768 -151.431876)
			(xy 95.670744 -151.351917) (xy 95.708966 -151.275157) (xy 95.754107 -151.202251) (xy 95.805783 -151.133822)
			(xy 95.863552 -151.070452) (xy 95.926922 -151.012683) (xy 95.995351 -150.961007) (xy 96.068257 -150.915866)
			(xy 96.145017 -150.877644) (xy 96.224976 -150.846668) (xy 96.307452 -150.823201) (xy 96.391742 -150.807445)
			(xy 96.477125 -150.799533) (xy 96.562875 -150.799533) (xy 96.648258 -150.807445) (xy 96.732548 -150.823201)
			(xy 96.815024 -150.846668) (xy 96.894983 -150.877644) (xy 96.971743 -150.915866) (xy 97.044649 -150.961007)
			(xy 97.113078 -151.012683) (xy 97.176448 -151.070452) (xy 97.234217 -151.133822) (xy 97.285893 -151.202251)
			(xy 97.331034 -151.275157) (xy 97.369256 -151.351917) (xy 97.400232 -151.431876) (xy 97.423699 -151.514352)
			(xy 97.439455 -151.598642) (xy 97.447367 -151.684025) (xy 97.447862 -151.7269) (xy 97.447367 -151.769775)
			(xy 97.439455 -151.855158) (xy 97.423699 -151.939448) (xy 97.400232 -152.021924) (xy 97.369256 -152.101883)
			(xy 97.331034 -152.178643) (xy 97.285893 -152.251549) (xy 97.234217 -152.319978) (xy 97.176448 -152.383348)
			(xy 97.113078 -152.441117) (xy 97.044649 -152.492793) (xy 96.971743 -152.537934) (xy 96.894983 -152.576156)
			(xy 96.815024 -152.607132) (xy 96.732548 -152.630599) (xy 96.648258 -152.646355) (xy 96.562875 -152.654267)
			(xy 96.477125 -152.654267) (xy 96.391742 -152.646355) (xy 96.307452 -152.630599) (xy 96.224976 -152.607132)
			(xy 96.145017 -152.576156) (xy 96.068257 -152.537934) (xy 95.995351 -152.492793) (xy 95.926922 -152.441117)
			(xy 95.863552 -152.383348) (xy 95.805783 -152.319978) (xy 95.754107 -152.251549) (xy 95.708966 -152.178643)
			(xy 95.670744 -152.101883) (xy 95.639768 -152.021924) (xy 95.616301 -151.939448) (xy 95.600545 -151.855158)
			(xy 95.592633 -151.769775) (xy 94.907367 -151.769775) (xy 94.899455 -151.855158) (xy 94.883699 -151.939448)
			(xy 94.860232 -152.021924) (xy 94.829256 -152.101883) (xy 94.791034 -152.178643) (xy 94.745893 -152.251549)
			(xy 94.694217 -152.319978) (xy 94.636448 -152.383348) (xy 94.573078 -152.441117) (xy 94.504649 -152.492793)
			(xy 94.431743 -152.537934) (xy 94.354983 -152.576156) (xy 94.275024 -152.607132) (xy 94.192548 -152.630599)
			(xy 94.108258 -152.646355) (xy 94.022875 -152.654267) (xy 93.937125 -152.654267) (xy 93.851742 -152.646355)
			(xy 93.767452 -152.630599) (xy 93.684976 -152.607132) (xy 93.605017 -152.576156) (xy 93.528257 -152.537934)
			(xy 93.455351 -152.492793) (xy 93.386922 -152.441117) (xy 93.323552 -152.383348) (xy 93.265783 -152.319978)
			(xy 93.214107 -152.251549) (xy 93.168966 -152.178643) (xy 93.130744 -152.101883) (xy 93.099768 -152.021924)
			(xy 93.076301 -151.939448) (xy 93.060545 -151.855158) (xy 93.052633 -151.769775) (xy 89.954367 -151.769775)
			(xy 89.946455 -151.855158) (xy 89.930699 -151.939448) (xy 89.907232 -152.021924) (xy 89.876256 -152.101883)
			(xy 89.838034 -152.178643) (xy 89.792893 -152.251549) (xy 89.741217 -152.319978) (xy 89.683448 -152.383348)
			(xy 89.620078 -152.441117) (xy 89.551649 -152.492793) (xy 89.478743 -152.537934) (xy 89.401983 -152.576156)
			(xy 89.322024 -152.607132) (xy 89.239548 -152.630599) (xy 89.155258 -152.646355) (xy 89.069875 -152.654267)
			(xy 88.984125 -152.654267) (xy 88.898742 -152.646355) (xy 88.814452 -152.630599) (xy 88.731976 -152.607132)
			(xy 88.652017 -152.576156) (xy 88.575257 -152.537934) (xy 88.502351 -152.492793) (xy 88.433922 -152.441117)
			(xy 88.370552 -152.383348) (xy 88.312783 -152.319978) (xy 88.261107 -152.251549) (xy 88.215966 -152.178643)
			(xy 88.177744 -152.101883) (xy 88.146768 -152.021924) (xy 88.123301 -151.939448) (xy 88.107545 -151.855158)
			(xy 88.099633 -151.769775) (xy 87.414367 -151.769775) (xy 87.406455 -151.855158) (xy 87.390699 -151.939448)
			(xy 87.367232 -152.021924) (xy 87.336256 -152.101883) (xy 87.298034 -152.178643) (xy 87.252893 -152.251549)
			(xy 87.201217 -152.319978) (xy 87.143448 -152.383348) (xy 87.080078 -152.441117) (xy 87.011649 -152.492793)
			(xy 86.938743 -152.537934) (xy 86.861983 -152.576156) (xy 86.782024 -152.607132) (xy 86.699548 -152.630599)
			(xy 86.615258 -152.646355) (xy 86.529875 -152.654267) (xy 86.444125 -152.654267) (xy 86.358742 -152.646355)
			(xy 86.274452 -152.630599) (xy 86.191976 -152.607132) (xy 86.112017 -152.576156) (xy 86.035257 -152.537934)
			(xy 85.962351 -152.492793) (xy 85.893922 -152.441117) (xy 85.830552 -152.383348) (xy 85.772783 -152.319978)
			(xy 85.721107 -152.251549) (xy 85.675966 -152.178643) (xy 85.637744 -152.101883) (xy 85.606768 -152.021924)
			(xy 85.583301 -151.939448) (xy 85.567545 -151.855158) (xy 85.559633 -151.769775) (xy 83.1088 -151.769775)
			(xy 83.1088 -158.119775) (xy 85.559633 -158.119775) (xy 85.559633 -158.034025) (xy 85.567545 -157.948642)
			(xy 85.583301 -157.864352) (xy 85.606768 -157.781876) (xy 85.637744 -157.701917) (xy 85.675966 -157.625157)
			(xy 85.721107 -157.552251) (xy 85.772783 -157.483822) (xy 85.830552 -157.420452) (xy 85.893922 -157.362683)
			(xy 85.962351 -157.311007) (xy 86.035257 -157.265866) (xy 86.112017 -157.227644) (xy 86.191976 -157.196668)
			(xy 86.274452 -157.173201) (xy 86.358742 -157.157445) (xy 86.444125 -157.149533) (xy 86.529875 -157.149533)
			(xy 86.615258 -157.157445) (xy 86.699548 -157.173201) (xy 86.782024 -157.196668) (xy 86.861983 -157.227644)
			(xy 86.938743 -157.265866) (xy 87.011649 -157.311007) (xy 87.080078 -157.362683) (xy 87.143448 -157.420452)
			(xy 87.201217 -157.483822) (xy 87.252893 -157.552251) (xy 87.298034 -157.625157) (xy 87.336256 -157.701917)
			(xy 87.367232 -157.781876) (xy 87.390699 -157.864352) (xy 87.406455 -157.948642) (xy 87.414367 -158.034025)
			(xy 87.414862 -158.0769) (xy 87.414367 -158.119775) (xy 88.099633 -158.119775) (xy 88.099633 -158.034025)
			(xy 88.107545 -157.948642) (xy 88.123301 -157.864352) (xy 88.146768 -157.781876) (xy 88.177744 -157.701917)
			(xy 88.215966 -157.625157) (xy 88.261107 -157.552251) (xy 88.312783 -157.483822) (xy 88.370552 -157.420452)
			(xy 88.433922 -157.362683) (xy 88.502351 -157.311007) (xy 88.575257 -157.265866) (xy 88.652017 -157.227644)
			(xy 88.731976 -157.196668) (xy 88.814452 -157.173201) (xy 88.898742 -157.157445) (xy 88.984125 -157.149533)
			(xy 89.069875 -157.149533) (xy 89.155258 -157.157445) (xy 89.239548 -157.173201) (xy 89.322024 -157.196668)
			(xy 89.401983 -157.227644) (xy 89.478743 -157.265866) (xy 89.551649 -157.311007) (xy 89.620078 -157.362683)
			(xy 89.683448 -157.420452) (xy 89.741217 -157.483822) (xy 89.792893 -157.552251) (xy 89.838034 -157.625157)
			(xy 89.876256 -157.701917) (xy 89.907232 -157.781876) (xy 89.930699 -157.864352) (xy 89.946455 -157.948642)
			(xy 89.954367 -158.034025) (xy 89.954862 -158.0769) (xy 89.954367 -158.119775) (xy 93.052633 -158.119775)
			(xy 93.052633 -158.034025) (xy 93.060545 -157.948642) (xy 93.076301 -157.864352) (xy 93.099768 -157.781876)
			(xy 93.130744 -157.701917) (xy 93.168966 -157.625157) (xy 93.214107 -157.552251) (xy 93.265783 -157.483822)
			(xy 93.323552 -157.420452) (xy 93.386922 -157.362683) (xy 93.455351 -157.311007) (xy 93.528257 -157.265866)
			(xy 93.605017 -157.227644) (xy 93.684976 -157.196668) (xy 93.767452 -157.173201) (xy 93.851742 -157.157445)
			(xy 93.937125 -157.149533) (xy 94.022875 -157.149533) (xy 94.108258 -157.157445) (xy 94.192548 -157.173201)
			(xy 94.275024 -157.196668) (xy 94.354983 -157.227644) (xy 94.431743 -157.265866) (xy 94.504649 -157.311007)
			(xy 94.573078 -157.362683) (xy 94.636448 -157.420452) (xy 94.694217 -157.483822) (xy 94.745893 -157.552251)
			(xy 94.791034 -157.625157) (xy 94.829256 -157.701917) (xy 94.860232 -157.781876) (xy 94.883699 -157.864352)
			(xy 94.899455 -157.948642) (xy 94.907367 -158.034025) (xy 94.907862 -158.0769) (xy 94.907367 -158.119775)
			(xy 95.592633 -158.119775) (xy 95.592633 -158.034025) (xy 95.600545 -157.948642) (xy 95.616301 -157.864352)
			(xy 95.639768 -157.781876) (xy 95.670744 -157.701917) (xy 95.708966 -157.625157) (xy 95.754107 -157.552251)
			(xy 95.805783 -157.483822) (xy 95.863552 -157.420452) (xy 95.926922 -157.362683) (xy 95.995351 -157.311007)
			(xy 96.068257 -157.265866) (xy 96.145017 -157.227644) (xy 96.224976 -157.196668) (xy 96.307452 -157.173201)
			(xy 96.391742 -157.157445) (xy 96.477125 -157.149533) (xy 96.562875 -157.149533) (xy 96.648258 -157.157445)
			(xy 96.732548 -157.173201) (xy 96.815024 -157.196668) (xy 96.894983 -157.227644) (xy 96.971743 -157.265866)
			(xy 97.044649 -157.311007) (xy 97.113078 -157.362683) (xy 97.176448 -157.420452) (xy 97.234217 -157.483822)
			(xy 97.285893 -157.552251) (xy 97.331034 -157.625157) (xy 97.369256 -157.701917) (xy 97.400232 -157.781876)
			(xy 97.423699 -157.864352) (xy 97.439455 -157.948642) (xy 97.447367 -158.034025) (xy 97.447862 -158.0769)
			(xy 97.447367 -158.119775) (xy 97.439455 -158.205158) (xy 97.423699 -158.289448) (xy 97.400232 -158.371924)
			(xy 97.369256 -158.451883) (xy 97.331034 -158.528643) (xy 97.285893 -158.601549) (xy 97.234217 -158.669978)
			(xy 97.176448 -158.733348) (xy 97.113078 -158.791117) (xy 97.044649 -158.842793) (xy 96.971743 -158.887934)
			(xy 96.894983 -158.926156) (xy 96.815024 -158.957132) (xy 96.732548 -158.980599) (xy 96.648258 -158.996355)
			(xy 96.562875 -159.004267) (xy 96.477125 -159.004267) (xy 96.391742 -158.996355) (xy 96.307452 -158.980599)
			(xy 96.224976 -158.957132) (xy 96.145017 -158.926156) (xy 96.068257 -158.887934) (xy 95.995351 -158.842793)
			(xy 95.926922 -158.791117) (xy 95.863552 -158.733348) (xy 95.805783 -158.669978) (xy 95.754107 -158.601549)
			(xy 95.708966 -158.528643) (xy 95.670744 -158.451883) (xy 95.639768 -158.371924) (xy 95.616301 -158.289448)
			(xy 95.600545 -158.205158) (xy 95.592633 -158.119775) (xy 94.907367 -158.119775) (xy 94.899455 -158.205158)
			(xy 94.883699 -158.289448) (xy 94.860232 -158.371924) (xy 94.829256 -158.451883) (xy 94.791034 -158.528643)
			(xy 94.745893 -158.601549) (xy 94.694217 -158.669978) (xy 94.636448 -158.733348) (xy 94.573078 -158.791117)
			(xy 94.504649 -158.842793) (xy 94.431743 -158.887934) (xy 94.354983 -158.926156) (xy 94.275024 -158.957132)
			(xy 94.192548 -158.980599) (xy 94.108258 -158.996355) (xy 94.022875 -159.004267) (xy 93.937125 -159.004267)
			(xy 93.851742 -158.996355) (xy 93.767452 -158.980599) (xy 93.684976 -158.957132) (xy 93.605017 -158.926156)
			(xy 93.528257 -158.887934) (xy 93.455351 -158.842793) (xy 93.386922 -158.791117) (xy 93.323552 -158.733348)
			(xy 93.265783 -158.669978) (xy 93.214107 -158.601549) (xy 93.168966 -158.528643) (xy 93.130744 -158.451883)
			(xy 93.099768 -158.371924) (xy 93.076301 -158.289448) (xy 93.060545 -158.205158) (xy 93.052633 -158.119775)
			(xy 89.954367 -158.119775) (xy 89.946455 -158.205158) (xy 89.930699 -158.289448) (xy 89.907232 -158.371924)
			(xy 89.876256 -158.451883) (xy 89.838034 -158.528643) (xy 89.792893 -158.601549) (xy 89.741217 -158.669978)
			(xy 89.683448 -158.733348) (xy 89.620078 -158.791117) (xy 89.551649 -158.842793) (xy 89.478743 -158.887934)
			(xy 89.401983 -158.926156) (xy 89.322024 -158.957132) (xy 89.239548 -158.980599) (xy 89.155258 -158.996355)
			(xy 89.069875 -159.004267) (xy 88.984125 -159.004267) (xy 88.898742 -158.996355) (xy 88.814452 -158.980599)
			(xy 88.731976 -158.957132) (xy 88.652017 -158.926156) (xy 88.575257 -158.887934) (xy 88.502351 -158.842793)
			(xy 88.433922 -158.791117) (xy 88.370552 -158.733348) (xy 88.312783 -158.669978) (xy 88.261107 -158.601549)
			(xy 88.215966 -158.528643) (xy 88.177744 -158.451883) (xy 88.146768 -158.371924) (xy 88.123301 -158.289448)
			(xy 88.107545 -158.205158) (xy 88.099633 -158.119775) (xy 87.414367 -158.119775) (xy 87.406455 -158.205158)
			(xy 87.390699 -158.289448) (xy 87.367232 -158.371924) (xy 87.336256 -158.451883) (xy 87.298034 -158.528643)
			(xy 87.252893 -158.601549) (xy 87.201217 -158.669978) (xy 87.143448 -158.733348) (xy 87.080078 -158.791117)
			(xy 87.011649 -158.842793) (xy 86.938743 -158.887934) (xy 86.861983 -158.926156) (xy 86.782024 -158.957132)
			(xy 86.699548 -158.980599) (xy 86.615258 -158.996355) (xy 86.529875 -159.004267) (xy 86.444125 -159.004267)
			(xy 86.358742 -158.996355) (xy 86.274452 -158.980599) (xy 86.191976 -158.957132) (xy 86.112017 -158.926156)
			(xy 86.035257 -158.887934) (xy 85.962351 -158.842793) (xy 85.893922 -158.791117) (xy 85.830552 -158.733348)
			(xy 85.772783 -158.669978) (xy 85.721107 -158.601549) (xy 85.675966 -158.528643) (xy 85.637744 -158.451883)
			(xy 85.606768 -158.371924) (xy 85.583301 -158.289448) (xy 85.567545 -158.205158) (xy 85.559633 -158.119775)
			(xy 83.1088 -158.119775) (xy 83.1088 -169.36446) (xy 92.503995 -169.36446) (xy 92.503995 -169.23532)
			(xy 92.511945 -169.106425) (xy 92.527815 -168.978265) (xy 92.551544 -168.851324) (xy 92.583043 -168.726085)
			(xy 92.622192 -168.603022) (xy 92.668843 -168.482603) (xy 92.722818 -168.365284) (xy 92.783913 -168.25151)
			(xy 92.851896 -168.141713) (xy 92.92651 -168.03631) (xy 93.007471 -167.9357) (xy 93.094471 -167.840265)
			(xy 93.187182 -167.750366) (xy 93.285252 -167.666345) (xy 93.388307 -167.588521) (xy 93.495958 -167.517189)
			(xy 93.607797 -167.452619) (xy 93.723398 -167.395057) (xy 93.842323 -167.34472) (xy 93.964122 -167.3018)
			(xy 94.088332 -167.266459) (xy 94.214481 -167.238832) (xy 94.342093 -167.219023) (xy 94.470682 -167.207107)
			(xy 94.59976 -167.203131) (xy 94.728838 -167.207107) (xy 94.857427 -167.219023) (xy 94.985039 -167.238832)
			(xy 95.111188 -167.266459) (xy 95.235398 -167.3018) (xy 95.357197 -167.34472) (xy 95.476122 -167.395057)
			(xy 95.591723 -167.452619) (xy 95.703562 -167.517189) (xy 95.811213 -167.588521) (xy 95.914268 -167.666345)
			(xy 96.012338 -167.750366) (xy 96.105049 -167.840265) (xy 96.192049 -167.9357) (xy 96.27301 -168.03631)
			(xy 96.347624 -168.141713) (xy 96.415607 -168.25151) (xy 96.476702 -168.365284) (xy 96.530677 -168.482603)
			(xy 96.577328 -168.603022) (xy 96.616477 -168.726085) (xy 96.647976 -168.851324) (xy 96.671705 -168.978265)
			(xy 96.687575 -169.106425) (xy 96.695525 -169.23532) (xy 96.696022 -169.29989) (xy 96.695525 -169.36446)
			(xy 96.687575 -169.493355) (xy 96.671705 -169.621515) (xy 96.647976 -169.748456) (xy 96.616477 -169.873695)
			(xy 96.577328 -169.996758) (xy 96.530677 -170.117177) (xy 96.476702 -170.234496) (xy 96.415607 -170.34827)
			(xy 96.347624 -170.458067) (xy 96.27301 -170.56347) (xy 96.192049 -170.66408) (xy 96.105049 -170.759515)
			(xy 96.012338 -170.849414) (xy 95.914268 -170.933435) (xy 95.811213 -171.011259) (xy 95.703562 -171.082591)
			(xy 95.591723 -171.147161) (xy 95.476122 -171.204723) (xy 95.357197 -171.25506) (xy 95.235398 -171.29798)
			(xy 95.111188 -171.333321) (xy 94.985039 -171.360948) (xy 94.857427 -171.380757) (xy 94.728838 -171.392673)
			(xy 94.59976 -171.39665) (xy 94.470682 -171.392673) (xy 94.342093 -171.380757) (xy 94.214481 -171.360948)
			(xy 94.088332 -171.333321) (xy 93.964122 -171.29798) (xy 93.842323 -171.25506) (xy 93.723398 -171.204723)
			(xy 93.607797 -171.147161) (xy 93.495958 -171.082591) (xy 93.388307 -171.011259) (xy 93.285252 -170.933435)
			(xy 93.187182 -170.849414) (xy 93.094471 -170.759515) (xy 93.007471 -170.66408) (xy 92.92651 -170.56347)
			(xy 92.851896 -170.458067) (xy 92.783913 -170.34827) (xy 92.722818 -170.234496) (xy 92.668843 -170.117177)
			(xy 92.622192 -169.996758) (xy 92.583043 -169.873695) (xy 92.551544 -169.748456) (xy 92.527815 -169.621515)
			(xy 92.511945 -169.493355) (xy 92.503995 -169.36446) (xy 83.1088 -169.36446) (xy 83.1088 -172.359066)
			(xy 83.1088 -172.361098) (xy 83.111306 -172.409684) (xy 83.121856 -172.506408) (xy 83.129882 -172.554392)
			(xy 83.129882 -172.555408) (xy 83.140735 -172.609684) (xy 83.169309 -172.716628) (xy 83.205583 -172.821212)
			(xy 83.249364 -172.922883) (xy 83.30042 -173.021102) (xy 83.35848 -173.115349) (xy 83.423239 -173.205127)
			(xy 83.494352 -173.289959) (xy 83.571445 -173.369397) (xy 83.654108 -173.44302) (xy 83.741905 -173.51044)
			(xy 83.83437 -173.571298) (xy 83.931015 -173.625274) (xy 84.031328 -173.672081) (xy 84.134778 -173.711473)
			(xy 84.240818 -173.743239) (xy 84.348887 -173.767213) (xy 84.458413 -173.783267) (xy 84.568816 -173.791317)
			(xy 84.624164 -173.79188)
		)
		(stroke
			(width 0)
			(type solid)
		)
		(fill yes)
		(layer "In2.Cu")
		(net "GND1")
	)
	(gr_poly
		(pts
			(xy 28.850082 -85.640926) (xy 28.905852 -85.640405) (xy 29.01708 -85.632071) (xy 29.127375 -85.615449)
			(xy 29.236119 -85.59063) (xy 29.342704 -85.557755) (xy 29.446535 -85.517006) (xy 29.54703 -85.468613)
			(xy 29.643627 -85.412844) (xy 29.735787 -85.350013) (xy 29.822994 -85.280471) (xy 29.904761 -85.204606)
			(xy 29.980629 -85.122843) (xy 30.050175 -85.035639) (xy 30.11301 -84.943482) (xy 30.168783 -84.846886)
			(xy 30.217181 -84.746393) (xy 30.257934 -84.642565) (xy 30.290814 -84.535981) (xy 30.315637 -84.427238)
			(xy 30.332264 -84.316944) (xy 30.340603 -84.205716) (xy 30.341062 -84.149946) (xy 30.341062 -82.00009)
			(xy 30.341556 -81.929708) (xy 30.349449 -81.789165) (xy 30.36521 -81.649285) (xy 30.38879 -81.510509)
			(xy 30.420113 -81.373274) (xy 30.459082 -81.238011) (xy 30.505573 -81.105145) (xy 30.559442 -80.975096)
			(xy 30.620517 -80.848271) (xy 30.688608 -80.725071) (xy 30.763499 -80.605882) (xy 30.844955 -80.49108)
			(xy 30.93272 -80.381025) (xy 31.026518 -80.276065) (xy 31.126053 -80.176529) (xy 31.231013 -80.082731)
			(xy 31.341067 -79.994965) (xy 31.455869 -79.913508) (xy 31.575057 -79.838616) (xy 31.698257 -79.770525)
			(xy 31.825081 -79.709448) (xy 31.955131 -79.655579) (xy 32.087996 -79.609087) (xy 32.223258 -79.570117)
			(xy 32.360494 -79.538793) (xy 32.499269 -79.515212) (xy 32.639149 -79.499451) (xy 32.779692 -79.491556)
			(xy 32.850074 -79.491078) (xy 36.20008 -79.491078) (xy 36.25585 -79.49057) (xy 36.367078 -79.482236)
			(xy 36.477372 -79.465613) (xy 36.586116 -79.440795) (xy 36.692701 -79.407919) (xy 36.796531 -79.36717)
			(xy 36.897025 -79.318775) (xy 36.993622 -79.263006) (xy 37.085781 -79.200174) (xy 37.172987 -79.130631)
			(xy 37.254752 -79.054765) (xy 37.330619 -78.973001) (xy 37.400164 -78.885796) (xy 37.462997 -78.793637)
			(xy 37.518767 -78.697041) (xy 37.567163 -78.596547) (xy 37.607913 -78.492718) (xy 37.64079 -78.386133)
			(xy 37.66561 -78.27739) (xy 37.682234 -78.167096) (xy 37.69057 -78.055868) (xy 37.69106 -78.000098)
			(xy 37.69106 -71.948802) (xy 37.691599 -71.875496) (xy 37.700178 -71.729134) (xy 37.717289 -71.583524)
			(xy 37.742874 -71.439161) (xy 37.776846 -71.296538) (xy 37.819088 -71.156143) (xy 37.869457 -71.018454)
			(xy 37.927781 -70.883942) (xy 37.99386 -70.753065) (xy 38.067469 -70.626269) (xy 38.148356 -70.503989)
			(xy 38.236247 -70.386641) (xy 38.33084 -70.274626) (xy 38.380924 -70.221094) (xy 38.41954 -70.179665)
			(xy 38.491081 -70.091854) (xy 38.555754 -69.998869) (xy 38.613187 -69.901245) (xy 38.663048 -69.799546)
			(xy 38.70505 -69.694357) (xy 38.738951 -69.586285) (xy 38.764555 -69.475952) (xy 38.781716 -69.363995)
			(xy 38.790333 -69.251058) (xy 38.79088 -69.194426) (xy 38.79088 -48.38192) (xy 38.793166 -48.379634)
			(xy 38.793166 -48.30064) (xy 38.79088 -48.298354) (xy 38.79088 -1.998726) (xy 38.790418 -1.94812)
			(xy 38.783485 -1.847145) (xy 38.769729 -1.746871) (xy 38.759892 -1.697228) (xy 38.759892 -1.69672)
			(xy 38.748192 -1.644664) (xy 38.718311 -1.542227) (xy 38.68119 -1.442187) (xy 38.637016 -1.345053)
			(xy 38.586017 -1.251324) (xy 38.528453 -1.161477) (xy 38.464617 -1.075972) (xy 38.394837 -0.995245)
			(xy 38.319468 -0.91971) (xy 38.238895 -0.849751) (xy 38.153531 -0.785727) (xy 38.063812 -0.727964)
			(xy 37.970195 -0.676758) (xy 37.87316 -0.63237) (xy 37.773202 -0.595028) (xy 37.670831 -0.564921)
			(xy 37.566572 -0.542204) (xy 37.460956 -0.526993) (xy 37.354523 -0.519366) (xy 37.30117 -0.518922)
			(xy 2.001266 -0.518922) (xy 1.945459 -0.519444) (xy 1.834157 -0.527785) (xy 1.72379 -0.54442) (xy 1.614975 -0.569257)
			(xy 1.508319 -0.602156) (xy 1.404421 -0.642933) (xy 1.30386 -0.691361) (xy 1.2072 -0.747168) (xy 1.11498 -0.810043)
			(xy 1.027717 -0.879633) (xy 0.945898 -0.95555) (xy 0.869982 -1.037369) (xy 0.800391 -1.124632) (xy 0.737517 -1.216852)
			(xy 0.68171 -1.313512) (xy 0.633283 -1.414073) (xy 0.592505 -1.517971) (xy 0.559607 -1.624626) (xy 0.53477 -1.733442)
			(xy 0.518135 -1.843809) (xy 0.509794 -1.955111) (xy 0.50927 -2.010918) (xy 0.50927 -14.899894) (xy 3.584198 -14.899894)
			(xy 3.588228 -14.757559) (xy 3.600303 -14.615679) (xy 3.620386 -14.474711) (xy 3.648413 -14.335104)
			(xy 3.684293 -14.197306) (xy 3.727911 -14.061759) (xy 3.779128 -13.928897) (xy 3.837779 -13.799145)
			(xy 3.903677 -13.672919) (xy 3.976611 -13.550623) (xy 4.056348 -13.43265) (xy 4.14263 -13.319377)
			(xy 4.235183 -13.211166) (xy 4.33371 -13.108365) (xy 4.437895 -13.011303) (xy 4.547404 -12.920291)
			(xy 4.661887 -12.835619) (xy 4.780977 -12.757561) (xy 4.904292 -12.686365) (xy 5.031438 -12.622259)
			(xy 5.162007 -12.56545) (xy 5.295581 -12.516118) (xy 5.431732 -12.474422) (xy 5.570023 -12.440496)
			(xy 5.710013 -12.414448) (xy 5.851252 -12.396362) (xy 5.993288 -12.386295) (xy 6.135666 -12.38428)
			(xy 6.27793 -12.390323) (xy 6.419624 -12.404405) (xy 6.560294 -12.426481) (xy 6.699491 -12.456481)
			(xy 6.836767 -12.494307) (xy 6.971683 -12.539839) (xy 7.103807 -12.59293) (xy 7.232716 -12.653412)
			(xy 7.357997 -12.72109) (xy 7.479248 -12.795747) (xy 7.596081 -12.877145) (xy 7.708122 -12.965022)
			(xy 7.815012 -13.059097) (xy 7.916409 -13.159069) (xy 8.011987 -13.264617) (xy 8.101441 -13.375403)
			(xy 8.184483 -13.491072) (xy 8.260849 -13.611255) (xy 8.330293 -13.735565) (xy 8.392593 -13.863606)
			(xy 8.447549 -13.994965) (xy 8.494986 -14.129224) (xy 8.53475 -14.265951) (xy 8.566716 -14.404709)
			(xy 8.590781 -14.545053) (xy 8.595466 -14.58626) (xy 31.59149 -14.58626) (xy 31.592597 -14.430603)
			(xy 31.601751 -14.275211) (xy 31.618929 -14.120501) (xy 31.644084 -13.966886) (xy 31.677149 -13.814777)
			(xy 31.718035 -13.664582) (xy 31.766634 -13.516701) (xy 31.822815 -13.371532) (xy 31.886427 -13.229463)
			(xy 31.957301 -13.090873) (xy 32.035247 -12.956133) (xy 32.120056 -12.825604) (xy 32.211502 -12.699636)
			(xy 32.260032 -12.638786) (xy 32.294969 -12.594641) (xy 32.358902 -12.501967) (xy 32.415667 -12.404736)
			(xy 32.464941 -12.303503) (xy 32.506444 -12.198843) (xy 32.539939 -12.091353) (xy 32.565236 -11.981644)
			(xy 32.58219 -11.870339) (xy 32.590706 -11.758074) (xy 32.591248 -11.70178) (xy 32.591248 -11.02995)
			(xy 32.591744 -10.966834) (xy 32.59967 -10.84085) (xy 32.615491 -10.715613) (xy 32.639144 -10.591617)
			(xy 32.670537 -10.46935) (xy 32.709545 -10.349296) (xy 32.756014 -10.231928) (xy 32.809762 -10.11771)
			(xy 32.870574 -10.007091) (xy 32.938213 -9.90051) (xy 33.012411 -9.798386) (xy 33.092874 -9.701122)
			(xy 33.179286 -9.609102) (xy 33.271306 -9.52269) (xy 33.36857 -9.442227) (xy 33.470694 -9.368029)
			(xy 33.577275 -9.30039) (xy 33.687894 -9.239578) (xy 33.802112 -9.18583) (xy 33.91948 -9.139361)
			(xy 34.039534 -9.100353) (xy 34.161801 -9.06896) (xy 34.285797 -9.045307) (xy 34.411034 -9.029486)
			(xy 34.537018 -9.02156) (xy 34.66325 -9.02156) (xy 34.789234 -9.029486) (xy 34.914471 -9.045307)
			(xy 35.038467 -9.06896) (xy 35.160734 -9.100353) (xy 35.280788 -9.139361) (xy 35.398156 -9.18583)
			(xy 35.512374 -9.239578) (xy 35.622993 -9.30039) (xy 35.729574 -9.368029) (xy 35.831698 -9.442227)
			(xy 35.928962 -9.52269) (xy 36.020982 -9.609102) (xy 36.107394 -9.701122) (xy 36.187857 -9.798386)
			(xy 36.262055 -9.90051) (xy 36.329694 -10.007091) (xy 36.390506 -10.11771) (xy 36.444254 -10.231928)
			(xy 36.490723 -10.349296) (xy 36.529731 -10.46935) (xy 36.561124 -10.591617) (xy 36.584777 -10.715613)
			(xy 36.600598 -10.84085) (xy 36.608524 -10.966834) (xy 36.60902 -11.02995) (xy 36.60902 -11.70178)
			(xy 36.609593 -11.758074) (xy 36.618096 -11.870341) (xy 36.635039 -11.981648) (xy 36.660326 -12.09136)
			(xy 36.693814 -12.198853) (xy 36.735311 -12.303515) (xy 36.784581 -12.404751) (xy 36.841345 -12.501983)
			(xy 36.905277 -12.594659) (xy 36.940236 -12.638786) (xy 36.988766 -12.699636) (xy 37.080212 -12.825604)
			(xy 37.165021 -12.956133) (xy 37.242967 -13.090873) (xy 37.313841 -13.229463) (xy 37.377453 -13.371532)
			(xy 37.433634 -13.516701) (xy 37.482233 -13.664582) (xy 37.523119 -13.814777) (xy 37.556184 -13.966886)
			(xy 37.581339 -14.120501) (xy 37.598517 -14.275211) (xy 37.607671 -14.430603) (xy 37.608778 -14.58626)
			(xy 37.601834 -14.741766) (xy 37.586857 -14.896705) (xy 37.563889 -15.050662) (xy 37.53299 -15.203225)
			(xy 37.494243 -15.353987) (xy 37.447752 -15.502543) (xy 37.39364 -15.648496) (xy 37.332054 -15.791456)
			(xy 37.263158 -15.931039) (xy 37.187135 -16.066874) (xy 37.104191 -16.198595) (xy 37.014545 -16.325851)
			(xy 36.918439 -16.448301) (xy 36.81613 -16.565617) (xy 36.70789 -16.677486) (xy 36.594011 -16.783608)
			(xy 36.474796 -16.883699) (xy 36.350565 -16.977491) (xy 36.22165 -17.064734) (xy 36.088396 -17.145193)
			(xy 35.95116 -17.218654) (xy 35.810309 -17.28492) (xy 35.666219 -17.343814) (xy 35.519276 -17.395178)
			(xy 35.369874 -17.438875) (xy 35.218413 -17.474787) (xy 35.065296 -17.502819) (xy 34.910935 -17.522896)
			(xy 34.755743 -17.534963) (xy 34.600134 -17.538989) (xy 34.444525 -17.534963) (xy 34.289333 -17.522896)
			(xy 34.134972 -17.502819) (xy 33.981855 -17.474787) (xy 33.830394 -17.438875) (xy 33.680992 -17.395178)
			(xy 33.534049 -17.343814) (xy 33.389959 -17.28492) (xy 33.249108 -17.218654) (xy 33.111872 -17.145193)
			(xy 32.978618 -17.064734) (xy 32.849703 -16.977491) (xy 32.725472 -16.883699) (xy 32.606257 -16.783608)
			(xy 32.492378 -16.677486) (xy 32.384138 -16.565617) (xy 32.281829 -16.448301) (xy 32.185723 -16.325851)
			(xy 32.096077 -16.198595) (xy 32.013133 -16.066874) (xy 31.93711 -15.931039) (xy 31.868214 -15.791456)
			(xy 31.806628 -15.648496) (xy 31.752516 -15.502543) (xy 31.706025 -15.353987) (xy 31.667278 -15.203225)
			(xy 31.636379 -15.050662) (xy 31.613411 -14.896705) (xy 31.598434 -14.741766) (xy 31.59149 -14.58626)
			(xy 8.595466 -14.58626) (xy 8.606867 -14.686534) (xy 8.614922 -14.828698) (xy 8.615426 -14.899894)
			(xy 8.614922 -14.97109) (xy 8.606867 -15.113254) (xy 8.590781 -15.254735) (xy 8.566716 -15.395079)
			(xy 8.53475 -15.533837) (xy 8.494986 -15.670564) (xy 8.447549 -15.804823) (xy 8.392593 -15.936182)
			(xy 8.330293 -16.064223) (xy 8.260849 -16.188533) (xy 8.184483 -16.308716) (xy 8.101441 -16.424385)
			(xy 8.011987 -16.535171) (xy 7.916409 -16.640719) (xy 7.815012 -16.740691) (xy 7.708122 -16.834766)
			(xy 7.596081 -16.922643) (xy 7.479248 -17.004041) (xy 7.357997 -17.078698) (xy 7.232716 -17.146376)
			(xy 7.103807 -17.206858) (xy 6.971683 -17.259949) (xy 6.836767 -17.305481) (xy 6.699491 -17.343307)
			(xy 6.560294 -17.373307) (xy 6.419624 -17.395383) (xy 6.27793 -17.409465) (xy 6.135666 -17.415508)
			(xy 5.993288 -17.413493) (xy 5.851252 -17.403426) (xy 5.710013 -17.38534) (xy 5.570023 -17.359292)
			(xy 5.431732 -17.325366) (xy 5.295581 -17.28367) (xy 5.162007 -17.234338) (xy 5.031438 -17.177529)
			(xy 4.904292 -17.113423) (xy 4.780977 -17.042227) (xy 4.661887 -16.964169) (xy 4.547404 -16.879497)
			(xy 4.437895 -16.788485) (xy 4.33371 -16.691423) (xy 4.235183 -16.588622) (xy 4.14263 -16.480411)
			(xy 4.056348 -16.367138) (xy 3.976611 -16.249165) (xy 3.903677 -16.126869) (xy 3.837779 -16.000643)
			(xy 3.779128 -15.870891) (xy 3.727911 -15.738029) (xy 3.684293 -15.602482) (xy 3.648413 -15.464684)
			(xy 3.620386 -15.325077) (xy 3.600303 -15.184109) (xy 3.588228 -15.042229) (xy 3.584198 -14.899894)
			(xy 0.50927 -14.899894) (xy 0.50927 -18.32991) (xy 23.337774 -18.32991) (xy 23.338267 -18.290403)
			(xy 23.346474 -18.211817) (xy 23.362759 -18.1345) (xy 23.386947 -18.05928) (xy 23.41878 -17.986963)
			(xy 23.457917 -17.918323) (xy 23.480522 -17.885918) (xy 23.484825 -17.87932) (xy 23.489621 -17.864325)
			(xy 23.48992 -17.856454) (xy 23.48992 -16.802862) (xy 23.489646 -16.794986) (xy 23.484853 -16.779982)
			(xy 23.480522 -16.773398) (xy 23.457958 -16.741022) (xy 23.418861 -16.672468) (xy 23.387069 -16.600235)
			(xy 23.362923 -16.5251) (xy 23.346684 -16.44787) (xy 23.338525 -16.369374) (xy 23.338028 -16.329914)
			(xy 23.338517 -16.291295) (xy 23.346331 -16.214452) (xy 23.361879 -16.138794) (xy 23.385002 -16.065097)
			(xy 23.415461 -15.994118) (xy 23.452946 -15.926584) (xy 23.49707 -15.86319) (xy 23.547381 -15.804584)
			(xy 23.603363 -15.751369) (xy 23.664442 -15.70409) (xy 23.72999 -15.663234) (xy 23.799336 -15.629218)
			(xy 23.871767 -15.602393) (xy 23.94654 -15.583033) (xy 24.022888 -15.571337) (xy 24.100028 -15.567425)
			(xy 24.177168 -15.571337) (xy 24.253516 -15.583033) (xy 24.328289 -15.602393) (xy 24.40072 -15.629218)
			(xy 24.470066 -15.663234) (xy 24.535614 -15.70409) (xy 24.596693 -15.751369) (xy 24.652675 -15.804584)
			(xy 24.702986 -15.86319) (xy 24.74711 -15.926584) (xy 24.784595 -15.994118) (xy 24.815054 -16.065097)
			(xy 24.838177 -16.138794) (xy 24.853725 -16.214452) (xy 24.861539 -16.291295) (xy 24.862028 -16.329914)
			(xy 24.861499 -16.369371) (xy 24.853315 -16.447861) (xy 24.837067 -16.525085) (xy 24.812929 -16.600218)
			(xy 24.781159 -16.672455) (xy 24.742097 -16.741024) (xy 24.719534 -16.773398) (xy 24.71522 -16.77999)
			(xy 24.710432 -16.79499) (xy 24.710136 -16.802862) (xy 24.710136 -17.856454) (xy 24.71041 -17.86433)
			(xy 24.715203 -17.879334) (xy 24.719534 -17.885918) (xy 24.742151 -17.918316) (xy 24.781315 -17.986944)
			(xy 24.813161 -18.05926) (xy 24.837348 -18.134484) (xy 24.853614 -18.211808) (xy 24.861785 -18.290401)
			(xy 24.862282 -18.32991) (xy 24.861793 -18.368542) (xy 24.853976 -18.445411) (xy 24.838423 -18.521094)
			(xy 24.815293 -18.594815) (xy 24.784823 -18.665818) (xy 24.747326 -18.733374) (xy 24.703187 -18.79679)
			(xy 24.652859 -18.855415) (xy 24.596858 -18.908648) (xy 24.535759 -18.955942) (xy 24.470189 -18.996813)
			(xy 24.400821 -19.03084) (xy 24.328365 -19.057674) (xy 24.253567 -19.077041) (xy 24.177194 -19.088741)
			(xy 24.100028 -19.092654) (xy 24.022862 -19.088741) (xy 23.946489 -19.077041) (xy 23.871691 -19.057674)
			(xy 23.799235 -19.03084) (xy 23.729867 -18.996813) (xy 23.664297 -18.955942) (xy 23.603198 -18.908648)
			(xy 23.547197 -18.855415) (xy 23.496869 -18.79679) (xy 23.45273 -18.733374) (xy 23.415233 -18.665818)
			(xy 23.384763 -18.594815) (xy 23.361633 -18.521094) (xy 23.34608 -18.445411) (xy 23.338263 -18.368542)
			(xy 23.337774 -18.32991) (xy 0.50927 -18.32991) (xy 0.50927 -33.568694) (xy 13.395441 -33.568694)
			(xy 13.395441 -33.439554) (xy 13.403391 -33.310659) (xy 13.419261 -33.182499) (xy 13.44299 -33.055558)
			(xy 13.474489 -32.930319) (xy 13.513638 -32.807256) (xy 13.560289 -32.686837) (xy 13.614264 -32.569518)
			(xy 13.675359 -32.455744) (xy 13.743342 -32.345947) (xy 13.817956 -32.240544) (xy 13.898917 -32.139934)
			(xy 13.985917 -32.044499) (xy 14.078628 -31.9546) (xy 14.176698 -31.870579) (xy 14.279753 -31.792755)
			(xy 14.387404 -31.721423) (xy 14.499243 -31.656853) (xy 14.614844 -31.599291) (xy 14.733769 -31.548954)
			(xy 14.855568 -31.506034) (xy 14.979778 -31.470693) (xy 15.105927 -31.443066) (xy 15.233539 -31.423257)
			(xy 15.362128 -31.411341) (xy 15.491206 -31.407365) (xy 15.620284 -31.411341) (xy 15.748873 -31.423257)
			(xy 15.876485 -31.443066) (xy 16.002634 -31.470693) (xy 16.126844 -31.506034) (xy 16.248643 -31.548954)
			(xy 16.367568 -31.599291) (xy 16.483169 -31.656853) (xy 16.595008 -31.721423) (xy 16.702659 -31.792755)
			(xy 16.805714 -31.870579) (xy 16.903784 -31.9546) (xy 16.996495 -32.044499) (xy 17.083495 -32.139934)
			(xy 17.164456 -32.240544) (xy 17.23907 -32.345947) (xy 17.307053 -32.455744) (xy 17.368148 -32.569518)
			(xy 17.422123 -32.686837) (xy 17.468774 -32.807256) (xy 17.507923 -32.930319) (xy 17.539422 -33.055558)
			(xy 17.563151 -33.182499) (xy 17.579021 -33.310659) (xy 17.586971 -33.439554) (xy 17.587468 -33.504124)
			(xy 17.586971 -33.568694) (xy 17.579021 -33.697589) (xy 17.563151 -33.825749) (xy 17.539422 -33.95269)
			(xy 17.507923 -34.077929) (xy 17.468774 -34.200992) (xy 17.422123 -34.321411) (xy 17.368148 -34.43873)
			(xy 17.307053 -34.552504) (xy 17.23907 -34.662301) (xy 17.164456 -34.767704) (xy 17.083495 -34.868314)
			(xy 16.996495 -34.963749) (xy 16.903784 -35.053648) (xy 16.805714 -35.137669) (xy 16.702659 -35.215493)
			(xy 16.595008 -35.286825) (xy 16.483169 -35.351395) (xy 16.367568 -35.408957) (xy 16.248643 -35.459294)
			(xy 16.126844 -35.502214) (xy 16.002634 -35.537555) (xy 15.876485 -35.565182) (xy 15.748873 -35.584991)
			(xy 15.620284 -35.596907) (xy 15.491206 -35.600884) (xy 15.362128 -35.596907) (xy 15.233539 -35.584991)
			(xy 15.105927 -35.565182) (xy 14.979778 -35.537555) (xy 14.855568 -35.502214) (xy 14.733769 -35.459294)
			(xy 14.614844 -35.408957) (xy 14.499243 -35.351395) (xy 14.387404 -35.286825) (xy 14.279753 -35.215493)
			(xy 14.176698 -35.137669) (xy 14.078628 -35.053648) (xy 13.985917 -34.963749) (xy 13.898917 -34.868314)
			(xy 13.817956 -34.767704) (xy 13.743342 -34.662301) (xy 13.675359 -34.552504) (xy 13.614264 -34.43873)
			(xy 13.560289 -34.321411) (xy 13.513638 -34.200992) (xy 13.474489 -34.077929) (xy 13.44299 -33.95269)
			(xy 13.419261 -33.825749) (xy 13.403391 -33.697589) (xy 13.395441 -33.568694) (xy 0.50927 -33.568694)
			(xy 0.50927 -37.638282) (xy 31.944299 -37.638282) (xy 31.944299 -37.509142) (xy 31.952249 -37.380247)
			(xy 31.968119 -37.252087) (xy 31.991848 -37.125146) (xy 32.023347 -36.999907) (xy 32.062496 -36.876844)
			(xy 32.109147 -36.756425) (xy 32.163122 -36.639106) (xy 32.224217 -36.525332) (xy 32.2922 -36.415535)
			(xy 32.366814 -36.310132) (xy 32.447775 -36.209522) (xy 32.534775 -36.114087) (xy 32.627486 -36.024188)
			(xy 32.725556 -35.940167) (xy 32.828611 -35.862343) (xy 32.936262 -35.791011) (xy 33.048101 -35.726441)
			(xy 33.163702 -35.668879) (xy 33.282627 -35.618542) (xy 33.404426 -35.575622) (xy 33.528636 -35.540281)
			(xy 33.654785 -35.512654) (xy 33.782397 -35.492845) (xy 33.910986 -35.480929) (xy 34.040064 -35.476953)
			(xy 34.169142 -35.480929) (xy 34.297731 -35.492845) (xy 34.425343 -35.512654) (xy 34.551492 -35.540281)
			(xy 34.675702 -35.575622) (xy 34.797501 -35.618542) (xy 34.916426 -35.668879) (xy 35.032027 -35.726441)
			(xy 35.143866 -35.791011) (xy 35.251517 -35.862343) (xy 35.354572 -35.940167) (xy 35.452642 -36.024188)
			(xy 35.545353 -36.114087) (xy 35.632353 -36.209522) (xy 35.713314 -36.310132) (xy 35.787928 -36.415535)
			(xy 35.855911 -36.525332) (xy 35.917006 -36.639106) (xy 35.970981 -36.756425) (xy 36.017632 -36.876844)
			(xy 36.056781 -36.999907) (xy 36.08828 -37.125146) (xy 36.112009 -37.252087) (xy 36.127879 -37.380247)
			(xy 36.135829 -37.509142) (xy 36.136326 -37.573712) (xy 36.135829 -37.638282) (xy 36.127879 -37.767177)
			(xy 36.112009 -37.895337) (xy 36.08828 -38.022278) (xy 36.056781 -38.147517) (xy 36.017632 -38.27058)
			(xy 35.970981 -38.390999) (xy 35.917006 -38.508318) (xy 35.855911 -38.622092) (xy 35.787928 -38.731889)
			(xy 35.713314 -38.837292) (xy 35.632353 -38.937902) (xy 35.545353 -39.033337) (xy 35.452642 -39.123236)
			(xy 35.354572 -39.207257) (xy 35.251517 -39.285081) (xy 35.143866 -39.356413) (xy 35.032027 -39.420983)
			(xy 34.916426 -39.478545) (xy 34.797501 -39.528882) (xy 34.675702 -39.571802) (xy 34.551492 -39.607143)
			(xy 34.425343 -39.63477) (xy 34.297731 -39.654579) (xy 34.169142 -39.666495) (xy 34.040064 -39.670472)
			(xy 33.910986 -39.666495) (xy 33.782397 -39.654579) (xy 33.654785 -39.63477) (xy 33.528636 -39.607143)
			(xy 33.404426 -39.571802) (xy 33.282627 -39.528882) (xy 33.163702 -39.478545) (xy 33.048101 -39.420983)
			(xy 32.936262 -39.356413) (xy 32.828611 -39.285081) (xy 32.725556 -39.207257) (xy 32.627486 -39.123236)
			(xy 32.534775 -39.033337) (xy 32.447775 -38.937902) (xy 32.366814 -38.837292) (xy 32.2922 -38.731889)
			(xy 32.224217 -38.622092) (xy 32.163122 -38.508318) (xy 32.109147 -38.390999) (xy 32.062496 -38.27058)
			(xy 32.023347 -38.147517) (xy 31.991848 -38.022278) (xy 31.968119 -37.895337) (xy 31.952249 -37.767177)
			(xy 31.944299 -37.638282) (xy 0.50927 -37.638282) (xy 0.50927 -64.96157) (xy 1.460235 -64.96157)
			(xy 1.460235 -64.83243) (xy 1.468185 -64.703535) (xy 1.484055 -64.575375) (xy 1.507784 -64.448434)
			(xy 1.539283 -64.323195) (xy 1.578432 -64.200132) (xy 1.625083 -64.079713) (xy 1.679058 -63.962394)
			(xy 1.740153 -63.84862) (xy 1.808136 -63.738823) (xy 1.88275 -63.63342) (xy 1.963711 -63.53281) (xy 2.050711 -63.437375)
			(xy 2.143422 -63.347476) (xy 2.241492 -63.263455) (xy 2.344547 -63.185631) (xy 2.452198 -63.114299)
			(xy 2.564037 -63.049729) (xy 2.679638 -62.992167) (xy 2.798563 -62.94183) (xy 2.920362 -62.89891)
			(xy 3.044572 -62.863569) (xy 3.170721 -62.835942) (xy 3.298333 -62.816133) (xy 3.426922 -62.804217)
			(xy 3.556 -62.800241) (xy 3.685078 -62.804217) (xy 3.813667 -62.816133) (xy 3.941279 -62.835942)
			(xy 4.067428 -62.863569) (xy 4.110844 -62.875922) (xy 30.28417 -62.875922) (xy 30.2882 -62.733587)
			(xy 30.300275 -62.591707) (xy 30.320358 -62.450739) (xy 30.348385 -62.311132) (xy 30.384265 -62.173334)
			(xy 30.427883 -62.037787) (xy 30.4791 -61.904925) (xy 30.537751 -61.775173) (xy 30.603649 -61.648947)
			(xy 30.676583 -61.526651) (xy 30.75632 -61.408678) (xy 30.842602 -61.295405) (xy 30.935155 -61.187194)
			(xy 31.033682 -61.084393) (xy 31.137867 -60.987331) (xy 31.247376 -60.896319) (xy 31.361859 -60.811647)
			(xy 31.480949 -60.733589) (xy 31.604264 -60.662393) (xy 31.73141 -60.598287) (xy 31.861979 -60.541478)
			(xy 31.995553 -60.492146) (xy 32.131704 -60.45045) (xy 32.269995 -60.416524) (xy 32.409985 -60.390476)
			(xy 32.551224 -60.37239) (xy 32.69326 -60.362323) (xy 32.835638 -60.360308) (xy 32.977902 -60.366351)
			(xy 33.119596 -60.380433) (xy 33.260266 -60.402509) (xy 33.399463 -60.432509) (xy 33.536739 -60.470335)
			(xy 33.671655 -60.515867) (xy 33.803779 -60.568958) (xy 33.932688 -60.62944) (xy 34.057969 -60.697118)
			(xy 34.17922 -60.771775) (xy 34.296053 -60.853173) (xy 34.408094 -60.94105) (xy 34.514984 -61.035125)
			(xy 34.616381 -61.135097) (xy 34.711959 -61.240645) (xy 34.801413 -61.351431) (xy 34.884455 -61.4671)
			(xy 34.960821 -61.587283) (xy 35.030265 -61.711593) (xy 35.092565 -61.839634) (xy 35.147521 -61.970993)
			(xy 35.194958 -62.105252) (xy 35.234722 -62.241979) (xy 35.266688 -62.380737) (xy 35.290753 -62.521081)
			(xy 35.306839 -62.662562) (xy 35.314894 -62.804726) (xy 35.315398 -62.875922) (xy 35.314894 -62.947118)
			(xy 35.306839 -63.089282) (xy 35.290753 -63.230763) (xy 35.266688 -63.371107) (xy 35.234722 -63.509865)
			(xy 35.194958 -63.646592) (xy 35.147521 -63.780851) (xy 35.092565 -63.91221) (xy 35.030265 -64.040251)
			(xy 34.960821 -64.164561) (xy 34.884455 -64.284744) (xy 34.801413 -64.400413) (xy 34.711959 -64.511199)
			(xy 34.616381 -64.616747) (xy 34.514984 -64.716719) (xy 34.408094 -64.810794) (xy 34.296053 -64.898671)
			(xy 34.17922 -64.980069) (xy 34.057969 -65.054726) (xy 33.932688 -65.122404) (xy 33.803779 -65.182886)
			(xy 33.671655 -65.235977) (xy 33.536739 -65.281509) (xy 33.399463 -65.319335) (xy 33.260266 -65.349335)
			(xy 33.119596 -65.371411) (xy 32.977902 -65.385493) (xy 32.835638 -65.391536) (xy 32.69326 -65.389521)
			(xy 32.551224 -65.379454) (xy 32.409985 -65.361368) (xy 32.269995 -65.33532) (xy 32.131704 -65.301394)
			(xy 31.995553 -65.259698) (xy 31.861979 -65.210366) (xy 31.73141 -65.153557) (xy 31.604264 -65.089451)
			(xy 31.480949 -65.018255) (xy 31.361859 -64.940197) (xy 31.247376 -64.855525) (xy 31.137867 -64.764513)
			(xy 31.033682 -64.667451) (xy 30.935155 -64.56465) (xy 30.842602 -64.456439) (xy 30.75632 -64.343166)
			(xy 30.676583 -64.225193) (xy 30.603649 -64.102897) (xy 30.537751 -63.976671) (xy 30.4791 -63.846919)
			(xy 30.427883 -63.714057) (xy 30.384265 -63.57851) (xy 30.348385 -63.440712) (xy 30.320358 -63.301105)
			(xy 30.300275 -63.160137) (xy 30.2882 -63.018257) (xy 30.28417 -62.875922) (xy 4.110844 -62.875922)
			(xy 4.191638 -62.89891) (xy 4.313437 -62.94183) (xy 4.432362 -62.992167) (xy 4.547963 -63.049729)
			(xy 4.659802 -63.114299) (xy 4.767453 -63.185631) (xy 4.870508 -63.263455) (xy 4.968578 -63.347476)
			(xy 5.061289 -63.437375) (xy 5.148289 -63.53281) (xy 5.22925 -63.63342) (xy 5.303864 -63.738823)
			(xy 5.371847 -63.84862) (xy 5.432942 -63.962394) (xy 5.486917 -64.079713) (xy 5.533568 -64.200132)
			(xy 5.572717 -64.323195) (xy 5.604216 -64.448434) (xy 5.627945 -64.575375) (xy 5.643815 -64.703535)
			(xy 5.651765 -64.83243) (xy 5.652262 -64.897) (xy 5.651765 -64.96157) (xy 5.643815 -65.090465) (xy 5.627945 -65.218625)
			(xy 5.604216 -65.345566) (xy 5.572717 -65.470805) (xy 5.533568 -65.593868) (xy 5.486917 -65.714287)
			(xy 5.432942 -65.831606) (xy 5.371847 -65.94538) (xy 5.303864 -66.055177) (xy 5.22925 -66.16058)
			(xy 5.148289 -66.26119) (xy 5.061289 -66.356625) (xy 4.968578 -66.446524) (xy 4.870508 -66.530545)
			(xy 4.767453 -66.608369) (xy 4.659802 -66.679701) (xy 4.547963 -66.744271) (xy 4.432362 -66.801833)
			(xy 4.313437 -66.85217) (xy 4.191638 -66.89509) (xy 4.067428 -66.930431) (xy 3.941279 -66.958058)
			(xy 3.813667 -66.977867) (xy 3.685078 -66.989783) (xy 3.556 -66.99376) (xy 3.426922 -66.989783) (xy 3.298333 -66.977867)
			(xy 3.170721 -66.958058) (xy 3.044572 -66.930431) (xy 2.920362 -66.89509) (xy 2.798563 -66.85217)
			(xy 2.679638 -66.801833) (xy 2.564037 -66.744271) (xy 2.452198 -66.679701) (xy 2.344547 -66.608369)
			(xy 2.241492 -66.530545) (xy 2.143422 -66.446524) (xy 2.050711 -66.356625) (xy 1.963711 -66.26119)
			(xy 1.88275 -66.16058) (xy 1.808136 -66.055177) (xy 1.740153 -65.94538) (xy 1.679058 -65.831606)
			(xy 1.625083 -65.714287) (xy 1.578432 -65.593868) (xy 1.539283 -65.470805) (xy 1.507784 -65.345566)
			(xy 1.484055 -65.218625) (xy 1.468185 -65.090465) (xy 1.460235 -64.96157) (xy 0.50927 -64.96157)
			(xy 0.50927 -69.20484) (xy 0.509524 -69.234304) (xy 0.509524 -69.234812) (xy 0.5115 -69.289393) (xy 0.522454 -69.39807)
			(xy 0.541334 -69.505654) (xy 0.568037 -69.611568) (xy 0.602421 -69.715244) (xy 0.644301 -69.816124)
			(xy 0.693453 -69.913669) (xy 0.749612 -70.007354) (xy 0.812478 -70.096678) (xy 0.881713 -70.18116)
			(xy 0.918972 -70.221094) (xy 0.967704 -70.273113) (xy 1.059868 -70.381871) (xy 1.14571 -70.495685)
			(xy 1.224951 -70.614189) (xy 1.297336 -70.737001) (xy 1.362633 -70.863724) (xy 1.42063 -70.99395)
			(xy 1.47114 -71.127258) (xy 1.514 -71.263219) (xy 1.549073 -71.401394) (xy 1.576244 -71.541337) (xy 1.595427 -71.682597)
			(xy 1.606559 -71.824719) (xy 1.608582 -71.89597) (xy 1.609344 -71.959978) (xy 1.609344 -74.536356)
			(xy 3.591292 -74.536356) (xy 3.592399 -74.380699) (xy 3.601553 -74.225307) (xy 3.618731 -74.070597)
			(xy 3.643886 -73.916982) (xy 3.676951 -73.764873) (xy 3.717837 -73.614678) (xy 3.766436 -73.466797)
			(xy 3.822617 -73.321628) (xy 3.886229 -73.179559) (xy 3.957103 -73.040969) (xy 4.035049 -72.906229)
			(xy 4.119858 -72.7757) (xy 4.211304 -72.649732) (xy 4.259834 -72.588882) (xy 4.294819 -72.54475)
			(xy 4.358801 -72.45206) (xy 4.41561 -72.354808) (xy 4.464922 -72.253549) (xy 4.506456 -72.148858)
			(xy 4.539974 -72.041333) (xy 4.565287 -71.931586) (xy 4.582249 -71.820242) (xy 4.590765 -71.707936)
			(xy 4.591304 -71.651622) (xy 4.591304 -70.980046) (xy 4.591799 -70.916938) (xy 4.599725 -70.79097)
			(xy 4.615544 -70.665749) (xy 4.639194 -70.541768) (xy 4.670583 -70.419517) (xy 4.709586 -70.299478)
			(xy 4.756049 -70.182125) (xy 4.80979 -70.067921) (xy 4.870595 -69.957317) (xy 4.938225 -69.850749)
			(xy 5.012413 -69.748637) (xy 5.092867 -69.651386) (xy 5.179268 -69.559378) (xy 5.271276 -69.472977)
			(xy 5.368527 -69.392523) (xy 5.470639 -69.318335) (xy 5.577207 -69.250705) (xy 5.687811 -69.1899)
			(xy 5.802015 -69.136159) (xy 5.919368 -69.089696) (xy 6.039407 -69.050693) (xy 6.161658 -69.019304)
			(xy 6.285639 -68.995654) (xy 6.41086 -68.979835) (xy 6.536828 -68.971909) (xy 6.663044 -68.971909)
			(xy 6.789012 -68.979835) (xy 6.914233 -68.995654) (xy 7.038214 -69.019304) (xy 7.160465 -69.050693)
			(xy 7.280504 -69.089696) (xy 7.397857 -69.136159) (xy 7.512061 -69.1899) (xy 7.622665 -69.250705)
			(xy 7.729233 -69.318335) (xy 7.831345 -69.392523) (xy 7.928596 -69.472977) (xy 8.020604 -69.559378)
			(xy 8.107005 -69.651386) (xy 8.187459 -69.748637) (xy 8.261647 -69.850749) (xy 8.329277 -69.957317)
			(xy 8.390082 -70.067921) (xy 8.443823 -70.182125) (xy 8.490286 -70.299478) (xy 8.529289 -70.419517)
			(xy 8.560678 -70.541768) (xy 8.584328 -70.665749) (xy 8.600147 -70.79097) (xy 8.608073 -70.916938)
			(xy 8.608568 -70.980046) (xy 8.608568 -71.651876) (xy 8.609132 -71.708177) (xy 8.617641 -71.820457)
			(xy 8.634599 -71.931774) (xy 8.659908 -72.041495) (xy 8.693423 -72.148993) (xy 8.734954 -72.253656)
			(xy 8.784264 -72.354887) (xy 8.841072 -72.452108) (xy 8.905054 -72.544766) (xy 8.940038 -72.588882)
			(xy 8.988568 -72.649732) (xy 9.080014 -72.7757) (xy 9.164823 -72.906229) (xy 9.242769 -73.040969)
			(xy 9.313643 -73.179559) (xy 9.377255 -73.321628) (xy 9.433436 -73.466797) (xy 9.482035 -73.614678)
			(xy 9.522921 -73.764873) (xy 9.555986 -73.916982) (xy 9.581141 -74.070597) (xy 9.598319 -74.225307)
			(xy 9.607473 -74.380699) (xy 9.60858 -74.536356) (xy 9.601636 -74.691862) (xy 9.586659 -74.846801)
			(xy 9.586183 -74.84999) (xy 15.206728 -74.84999) (xy 15.210775 -74.75599) (xy 15.222889 -74.662686)
			(xy 15.242978 -74.570769) (xy 15.270895 -74.480919) (xy 15.306433 -74.393802) (xy 15.349327 -74.310062)
			(xy 15.399262 -74.230319) (xy 15.455867 -74.155165) (xy 15.518723 -74.085154) (xy 15.587365 -74.020806)
			(xy 15.661284 -73.962598) (xy 15.739934 -73.910959) (xy 15.822732 -73.866272) (xy 15.909064 -73.828868)
			(xy 15.998293 -73.799025) (xy 16.089756 -73.776962) (xy 16.182778 -73.762844) (xy 16.276669 -73.756775)
			(xy 16.370734 -73.758799) (xy 16.464277 -73.768902) (xy 16.556605 -73.787009) (xy 16.647035 -73.812986)
			(xy 16.734897 -73.846641) (xy 16.81954 -73.887724) (xy 16.900338 -73.935932) (xy 16.976694 -73.990907)
			(xy 17.04804 -74.052242) (xy 17.11385 -74.119483) (xy 17.173636 -74.192133) (xy 17.226955 -74.269653)
			(xy 17.273413 -74.35147) (xy 17.312666 -74.436978) (xy 17.344422 -74.525544) (xy 17.368447 -74.616512)
			(xy 17.384564 -74.709208) (xy 17.392652 -74.802947) (xy 17.393158 -74.84999) (xy 26.30602 -74.84999)
			(xy 26.310069 -74.755947) (xy 26.322188 -74.662599) (xy 26.342287 -74.570639) (xy 26.370217 -74.480748)
			(xy 26.405771 -74.39359) (xy 26.448686 -74.309811) (xy 26.498644 -74.230032) (xy 26.555275 -74.154842)
			(xy 26.61816 -74.084799) (xy 26.686834 -74.020421) (xy 26.760788 -73.962185) (xy 26.839474 -73.910522)
			(xy 26.92231 -73.865815) (xy 27.008683 -73.828394) (xy 27.097952 -73.798537) (xy 27.189458 -73.776464)
			(xy 27.282523 -73.762339) (xy 27.376458 -73.756267) (xy 27.470567 -73.758292) (xy 27.564153 -73.7684)
			(xy 27.656524 -73.786516) (xy 27.746996 -73.812505) (xy 27.834898 -73.846175) (xy 27.919581 -73.887277)
			(xy 28.000417 -73.935507) (xy 28.076808 -73.990508) (xy 28.148188 -74.051871) (xy 28.214028 -74.119144)
			(xy 28.273842 -74.191827) (xy 28.327186 -74.269384) (xy 28.373665 -74.351239) (xy 28.412936 -74.436786)
			(xy 28.444707 -74.525393) (xy 28.468744 -74.616403) (xy 28.484868 -74.709143) (xy 28.49296 -74.802925)
			(xy 28.493466 -74.84999) (xy 28.49296 -74.897055) (xy 28.484868 -74.990837) (xy 28.468744 -75.083577)
			(xy 28.444707 -75.174587) (xy 28.412936 -75.263194) (xy 28.373665 -75.348741) (xy 28.327186 -75.430596)
			(xy 28.273842 -75.508153) (xy 28.214028 -75.580836) (xy 28.148188 -75.648109) (xy 28.076808 -75.709472)
			(xy 28.000417 -75.764473) (xy 27.919581 -75.812703) (xy 27.834898 -75.853805) (xy 27.746996 -75.887475)
			(xy 27.656524 -75.913464) (xy 27.564153 -75.93158) (xy 27.470567 -75.941688) (xy 27.376458 -75.943713)
			(xy 27.282523 -75.937641) (xy 27.189458 -75.923516) (xy 27.097952 -75.901443) (xy 27.008683 -75.871586)
			(xy 26.92231 -75.834165) (xy 26.839474 -75.789458) (xy 26.760788 -75.737795) (xy 26.686834 -75.679559)
			(xy 26.61816 -75.615181) (xy 26.555275 -75.545138) (xy 26.498644 -75.469948) (xy 26.448686 -75.390169)
			(xy 26.405771 -75.30639) (xy 26.370217 -75.219232) (xy 26.342287 -75.129341) (xy 26.322188 -75.037381)
			(xy 26.310069 -74.944033) (xy 26.30602 -74.84999) (xy 17.393158 -74.84999) (xy 17.392652 -74.897033)
			(xy 17.384564 -74.990772) (xy 17.368447 -75.083468) (xy 17.344422 -75.174436) (xy 17.312666 -75.263002)
			(xy 17.273413 -75.34851) (xy 17.226955 -75.430327) (xy 17.173636 -75.507847) (xy 17.11385 -75.580497)
			(xy 17.04804 -75.647738) (xy 16.976694 -75.709073) (xy 16.900338 -75.764048) (xy 16.81954 -75.812256)
			(xy 16.734897 -75.853339) (xy 16.647035 -75.886994) (xy 16.556605 -75.912971) (xy 16.464277 -75.931078)
			(xy 16.370734 -75.941181) (xy 16.276669 -75.943205) (xy 16.182778 -75.937136) (xy 16.089756 -75.923018)
			(xy 15.998293 -75.900955) (xy 15.909064 -75.871112) (xy 15.822732 -75.833708) (xy 15.739934 -75.789021)
			(xy 15.661284 -75.737382) (xy 15.587365 -75.679174) (xy 15.518723 -75.614826) (xy 15.455867 -75.544815)
			(xy 15.399262 -75.469661) (xy 15.349327 -75.389918) (xy 15.306433 -75.306178) (xy 15.270895 -75.219061)
			(xy 15.242978 -75.129211) (xy 15.222889 -75.037294) (xy 15.210775 -74.94399) (xy 15.206728 -74.84999)
			(xy 9.586183 -74.84999) (xy 9.563691 -75.000758) (xy 9.532792 -75.153321) (xy 9.494045 -75.304083)
			(xy 9.447554 -75.452639) (xy 9.393442 -75.598592) (xy 9.331856 -75.741552) (xy 9.26296 -75.881135)
			(xy 9.186937 -76.01697) (xy 9.103993 -76.148691) (xy 9.014347 -76.275947) (xy 8.918241 -76.398397)
			(xy 8.815932 -76.515713) (xy 8.707692 -76.627582) (xy 8.593813 -76.733704) (xy 8.474598 -76.833795)
			(xy 8.350367 -76.927587) (xy 8.221452 -77.01483) (xy 8.088198 -77.095289) (xy 7.950962 -77.16875)
			(xy 7.810111 -77.235016) (xy 7.666021 -77.29391) (xy 7.519078 -77.345274) (xy 7.369676 -77.388971)
			(xy 7.218215 -77.424883) (xy 7.065098 -77.452915) (xy 6.910737 -77.472992) (xy 6.755545 -77.485059)
			(xy 6.599936 -77.489085) (xy 6.444327 -77.485059) (xy 6.289135 -77.472992) (xy 6.134774 -77.452915)
			(xy 5.981657 -77.424883) (xy 5.830196 -77.388971) (xy 5.680794 -77.345274) (xy 5.533851 -77.29391)
			(xy 5.389761 -77.235016) (xy 5.24891 -77.16875) (xy 5.111674 -77.095289) (xy 4.97842 -77.01483) (xy 4.849505 -76.927587)
			(xy 4.725274 -76.833795) (xy 4.606059 -76.733704) (xy 4.49218 -76.627582) (xy 4.38394 -76.515713)
			(xy 4.281631 -76.398397) (xy 4.185525 -76.275947) (xy 4.095879 -76.148691) (xy 4.012935 -76.01697)
			(xy 3.936912 -75.881135) (xy 3.868016 -75.741552) (xy 3.80643 -75.598592) (xy 3.752318 -75.452639)
			(xy 3.705827 -75.304083) (xy 3.66708 -75.153321) (xy 3.636181 -75.000758) (xy 3.613213 -74.846801)
			(xy 3.598236 -74.691862) (xy 3.591292 -74.536356) (xy 1.609344 -74.536356) (xy 1.609344 -78.01102)
			(xy 1.609598 -78.039976) (xy 1.609598 -78.040484) (xy 1.611579 -78.095259) (xy 1.622586 -78.204322)
			(xy 1.641574 -78.312282) (xy 1.668439 -78.418555) (xy 1.703038 -78.522569) (xy 1.745182 -78.62376)
			(xy 1.794645 -78.721583) (xy 1.851159 -78.815509) (xy 1.914419 -78.90503) (xy 1.984083 -78.989663)
			(xy 2.059775 -79.068951) (xy 2.141086 -79.142466) (xy 2.227577 -79.20981) (xy 2.318781 -79.270619)
			(xy 2.414204 -79.324566) (xy 2.513332 -79.371358) (xy 2.615629 -79.410744) (xy 2.720542 -79.442509)
			(xy 2.827505 -79.466484) (xy 2.93594 -79.482537) (xy 3.045262 -79.490583) (xy 3.10007 -79.491078)
			(xy 10.849864 -79.491078) (xy 10.921875 -79.491591) (xy 11.06566 -79.499855) (xy 11.208734 -79.516353)
			(xy 11.350626 -79.541031) (xy 11.490869 -79.573809) (xy 11.629 -79.614577) (xy 11.764565 -79.663202)
			(xy 11.897118 -79.719524) (xy 12.026222 -79.783357) (xy 12.151451 -79.85449) (xy 12.272394 -79.93269)
			(xy 12.388651 -80.0177) (xy 12.499841 -80.109238) (xy 12.605596 -80.207004) (xy 12.705569 -80.310675)
			(xy 12.79943 -80.419911) (xy 12.886871 -80.534351) (xy 12.967602 -80.653619) (xy 13.041359 -80.777321)
			(xy 13.107899 -80.905051) (xy 13.167001 -81.036387) (xy 13.218473 -81.170898) (xy 13.262143 -81.308139)
			(xy 13.297869 -81.44766) (xy 13.325532 -81.589001) (xy 13.345042 -81.731695) (xy 13.356334 -81.875274)
			(xy 13.358368 -81.947258) (xy 13.35913 -82.011012) (xy 13.35913 -84.160868) (xy 13.359384 -84.189824)
			(xy 13.359384 -84.190332) (xy 13.361365 -84.245107) (xy 13.372372 -84.35417) (xy 13.391359 -84.46213)
			(xy 13.418225 -84.568404) (xy 13.452823 -84.672418) (xy 13.494968 -84.77361) (xy 13.54443 -84.871433)
			(xy 13.600944 -84.965359) (xy 13.664204 -85.05488) (xy 13.733868 -85.139514) (xy 13.80956 -85.218802)
			(xy 13.890871 -85.292317) (xy 13.977362 -85.359661) (xy 14.068566 -85.420471) (xy 14.163989 -85.474418)
			(xy 14.263117 -85.52121) (xy 14.365414 -85.560596) (xy 14.470328 -85.592362) (xy 14.577291 -85.616337)
			(xy 14.685726 -85.63239) (xy 14.795047 -85.640437) (xy 14.849856 -85.640926)
		)
		(stroke
			(width 0)
			(type solid)
		)
		(fill yes)
		(layer "In2.Cu")
		(net "GND")
	)
	(gr_line
		(start 0.00127 -69.20484)
		(end 0.00127 -2.010918)
		(stroke
			(width 1.016)
			(type default)
		)
		(layer "In2.Cu")
	)
	(gr_arc
		(start 0.00127 -69.20484)
		(mid 0.143811 -69.946541)
		(end 0.55118 -70.582536)
		(stroke
			(width 1.016)
			(type default)
		)
		(layer "In2.Cu")
	)
	(gr_line
		(start 1.101344 -78.01102)
		(end 1.101344 -71.959978)
		(stroke
			(width 1.016)
			(type default)
		)
		(layer "In2.Cu")
	)
	(gr_arc
		(start 1.101344 -78.01102)
		(mid 1.687129 -79.425231)
		(end 3.10134 -80.011016)
		(stroke
			(width 1.016)
			(type default)
		)
		(layer "In2.Cu")
	)
	(gr_arc
		(start 1.101344 -71.959978)
		(mid 0.958667 -71.218375)
		(end 0.55118 -70.582536)
		(stroke
			(width 1.016)
			(type default)
		)
		(layer "In2.Cu")
	)
	(gr_arc
		(start 2.001266 -0.010922)
		(mid 0.587055 -0.596707)
		(end 0.00127 -2.010918)
		(stroke
			(width 1.016)
			(type default)
		)
		(layer "In2.Cu")
	)
	(gr_line
		(start 2.001266 -0.010922)
		(end 37.30117 -0.010922)
		(stroke
			(width 1.016)
			(type default)
		)
		(layer "In2.Cu")
	)
	(gr_line
		(start 10.851134 -80.011016)
		(end 3.10134 -80.011016)
		(stroke
			(width 1.016)
			(type default)
		)
		(layer "In2.Cu")
	)
	(gr_line
		(start 12.85113 -84.160868)
		(end 12.85113 -82.011012)
		(stroke
			(width 1.016)
			(type default)
		)
		(layer "In2.Cu")
	)
	(gr_arc
		(start 12.85113 -84.160868)
		(mid 13.436914 -85.575081)
		(end 14.851126 -86.160864)
		(stroke
			(width 1.016)
			(type default)
		)
		(layer "In2.Cu")
	)
	(gr_arc
		(start 12.85113 -82.011012)
		(mid 12.265345 -80.596801)
		(end 10.851134 -80.011016)
		(stroke
			(width 1.016)
			(type default)
		)
		(layer "In2.Cu")
	)
	(gr_line
		(start 28.851352 -86.160864)
		(end 14.851126 -86.160864)
		(stroke
			(width 1.016)
			(type default)
		)
		(layer "In2.Cu")
	)
	(gr_arc
		(start 28.851352 -86.160864)
		(mid 30.265561 -85.575078)
		(end 30.851348 -84.160868)
		(stroke
			(width 1.016)
			(type default)
		)
		(layer "In2.Cu")
	)
	(gr_line
		(start 30.851348 -82.011012)
		(end 30.851348 -84.160868)
		(stroke
			(width 1.016)
			(type default)
		)
		(layer "In2.Cu")
	)
	(gr_arc
		(start 32.851344 -80.011016)
		(mid 31.437133 -80.596801)
		(end 30.851348 -82.011012)
		(stroke
			(width 1.016)
			(type default)
		)
		(layer "In2.Cu")
	)
	(gr_line
		(start 36.20135 -80.011016)
		(end 32.851344 -80.011016)
		(stroke
			(width 1.016)
			(type default)
		)
		(layer "In2.Cu")
	)
	(gr_arc
		(start 36.20135 -80.011016)
		(mid 37.615561 -79.425231)
		(end 38.201346 -78.01102)
		(stroke
			(width 1.016)
			(type default)
		)
		(layer "In2.Cu")
	)
	(gr_line
		(start 38.201346 -78.01102)
		(end 38.201346 -71.959978)
		(stroke
			(width 1.016)
			(type default)
		)
		(layer "In2.Cu")
	)
	(gr_arc
		(start 38.751256 -70.582536)
		(mid 38.343908 -71.218402)
		(end 38.201346 -71.959978)
		(stroke
			(width 1.016)
			(type default)
		)
		(layer "In2.Cu")
	)
	(gr_arc
		(start 38.751256 -70.582536)
		(mid 39.158647 -69.946554)
		(end 39.301166 -69.20484)
		(stroke
			(width 1.016)
			(type default)
		)
		(layer "In2.Cu")
	)
	(gr_arc
		(start 39.301166 -2.010918)
		(mid 38.715385 -0.596706)
		(end 37.30117 -0.010922)
		(stroke
			(width 1.016)
			(type default)
		)
		(layer "In2.Cu")
	)
	(gr_line
		(start 39.301166 -2.010918)
		(end 39.301166 -69.20484)
		(stroke
			(width 1.016)
			(type default)
		)
		(layer "In2.Cu")
	)
	(gr_line
		(start 0 -69.193918)
		(end 0 -1.999996)
		(stroke
			(width 0.05)
			(type default)
		)
		(layer "Edge.Cuts")
	)
	(gr_arc
		(start 0 -69.193918)
		(mid 0.14254 -69.935502)
		(end 0.54991 -70.57136)
		(stroke
			(width 0.05)
			(type default)
		)
		(layer "Edge.Cuts")
	)
	(gr_line
		(start 1.100074 -78.000098)
		(end 1.100074 -71.949056)
		(stroke
			(width 0.05)
			(type default)
		)
		(layer "Edge.Cuts")
	)
	(gr_arc
		(start 1.100074 -78.000098)
		(mid 1.685859 -79.41431)
		(end 3.10007 -80.000094)
		(stroke
			(width 0.05)
			(type default)
		)
		(layer "Edge.Cuts")
	)
	(gr_arc
		(start 1.100074 -71.949056)
		(mid 0.957458 -71.207304)
		(end 0.54991 -70.57136)
		(stroke
			(width 0.05)
			(type default)
		)
		(layer "Edge.Cuts")
	)
	(gr_arc
		(start 1.999996 0)
		(mid 0.585785 -0.585785)
		(end 0 -1.999996)
		(stroke
			(width 0.05)
			(type default)
		)
		(layer "Edge.Cuts")
	)
	(gr_line
		(start 1.999996 0)
		(end 37.2999 0)
		(stroke
			(width 0.05)
			(type default)
		)
		(layer "Edge.Cuts")
	)
	(gr_line
		(start 10.850118 -80.000094)
		(end 3.10007 -80.000094)
		(stroke
			(width 0.05)
			(type default)
		)
		(layer "Edge.Cuts")
	)
	(gr_line
		(start 12.850114 -84.149946)
		(end 12.850114 -82.00009)
		(stroke
			(width 0.05)
			(type default)
		)
		(layer "Edge.Cuts")
	)
	(gr_arc
		(start 12.850114 -84.149946)
		(mid 13.435916 -85.564123)
		(end 14.85011 -86.149942)
		(stroke
			(width 0.05)
			(type default)
		)
		(layer "Edge.Cuts")
	)
	(gr_arc
		(start 12.850114 -82.00009)
		(mid 12.264329 -80.585879)
		(end 10.850118 -80.000094)
		(stroke
			(width 0.05)
			(type default)
		)
		(layer "Edge.Cuts")
	)
	(gr_line
		(start 28.850082 -86.149942)
		(end 14.85011 -86.149942)
		(stroke
			(width 0.05)
			(type default)
		)
		(layer "Edge.Cuts")
	)
	(gr_arc
		(start 28.850082 -86.149942)
		(mid 30.26429 -85.564156)
		(end 30.850078 -84.149946)
		(stroke
			(width 0.05)
			(type default)
		)
		(layer "Edge.Cuts")
	)
	(gr_line
		(start 30.850078 -82.00009)
		(end 30.850078 -84.149946)
		(stroke
			(width 0.05)
			(type default)
		)
		(layer "Edge.Cuts")
	)
	(gr_arc
		(start 32.850074 -80.000094)
		(mid 31.435863 -80.585879)
		(end 30.850078 -82.00009)
		(stroke
			(width 0.05)
			(type default)
		)
		(layer "Edge.Cuts")
	)
	(gr_line
		(start 36.20008 -80.000094)
		(end 32.850074 -80.000094)
		(stroke
			(width 0.05)
			(type default)
		)
		(layer "Edge.Cuts")
	)
	(gr_arc
		(start 36.20008 -80.000094)
		(mid 37.614303 -79.414316)
		(end 38.200076 -78.000098)
		(stroke
			(width 0.05)
			(type default)
		)
		(layer "Edge.Cuts")
	)
	(gr_line
		(start 38.200076 -71.949056)
		(end 38.200076 -78.000098)
		(stroke
			(width 0.05)
			(type default)
		)
		(layer "Edge.Cuts")
	)
	(gr_arc
		(start 38.749986 -70.57136)
		(mid 38.342617 -71.20735)
		(end 38.200076 -71.949056)
		(stroke
			(width 0.05)
			(type default)
		)
		(layer "Edge.Cuts")
	)
	(gr_arc
		(start 38.749986 -70.57136)
		(mid 39.157324 -69.935491)
		(end 39.299896 -69.193918)
		(stroke
			(width 0.05)
			(type default)
		)
		(layer "Edge.Cuts")
	)
	(gr_arc
		(start 39.299896 -1.999996)
		(mid 38.714109 -0.585788)
		(end 37.2999 0)
		(stroke
			(width 0.05)
			(type default)
		)
		(layer "Edge.Cuts")
	)
	(gr_line
		(start 39.299896 -1.999996)
		(end 39.299896 -69.193918)
		(stroke
			(width 0.05)
			(type default)
		)
		(layer "Edge.Cuts")
	)
	(segment
		(start 97.902522 -130.44932)
		(end 98.06432 -131.36753)
		(width 0.14732)
		(layer "F.Cu")
		(net "DELTA_L_85_10INCH_TOP_DN")
	)
	(segment
		(start 92.493084 -109.469936)
		(end 97.559114 -108.576872)
		(width 0.14732)
		(layer "F.Cu")
		(net "DELTA_L_85_10INCH_TOP_DN")
	)
	(segment
		(start 92.529914 -131.098036)
		(end 97.561654 -130.210052)
		(width 0.14732)
		(layer "F.Cu")
		(net "DELTA_L_85_10INCH_TOP_DN")
	)
	(segment
		(start 97.849436 -128.098804)
		(end 92.177362 -129.098548)
		(width 0.14732)
		(layer "F.Cu")
		(net "DELTA_L_85_10INCH_TOP_DN")
	)
	(segment
		(start 91.967812 -119.822214)
		(end 91.967558 -119.822214)
		(width 0.14732)
		(layer "F.Cu")
		(net "DELTA_L_85_10INCH_TOP_DN")
	)
	(segment
		(start 97.826068 -124.497084)
		(end 92.18422 -125.491748)
		(width 0.14732)
		(layer "F.Cu")
		(net "DELTA_L_85_10INCH_TOP_DN")
	)
	(segment
		(start 92.008706 -112.710722)
		(end 92.522294 -113.07064)
		(width 0.14732)
		(layer "F.Cu")
		(net "DELTA_L_85_10INCH_TOP_DN")
	)
	(segment
		(start 98.07321 -98.914458)
		(end 97.83445 -99.255326)
		(width 0.14732)
		(layer "F.Cu")
		(net "DELTA_L_85_10INCH_TOP_DN")
	)
	(segment
		(start 98.07321 -138.57732)
		(end 97.833942 -138.918442)
		(width 0.14732)
		(layer "F.Cu")
		(net "DELTA_L_85_10INCH_TOP_DN")
	)
	(segment
		(start 91.990672 -123.42368)
		(end 91.990418 -123.42368)
		(width 0.14732)
		(layer "F.Cu")
		(net "DELTA_L_85_10INCH_TOP_DN")
	)
	(segment
		(start 92.029534 -116.312696)
		(end 92.54363 -116.67236)
		(width 0.14732)
		(layer "F.Cu")
		(net "DELTA_L_85_10INCH_TOP_DN")
	)
	(segment
		(start 92.00896 -123.527566)
		(end 92.523056 -123.88723)
		(width 0.14732)
		(layer "F.Cu")
		(net "DELTA_L_85_10INCH_TOP_DN")
	)
	(segment
		(start 97.91446 -105.207308)
		(end 98.076258 -106.125518)
		(width 0.14732)
		(layer "F.Cu")
		(net "DELTA_L_85_10INCH_TOP_DN")
	)
	(segment
		(start 98.089974 -102.517448)
		(end 97.85096 -102.85857)
		(width 0.14732)
		(layer "F.Cu")
		(net "DELTA_L_85_10INCH_TOP_DN")
	)
	(segment
		(start 92.191078 -114.67338)
		(end 91.831414 -115.187222)
		(width 0.14732)
		(layer "F.Cu")
		(net "DELTA_L_85_10INCH_TOP_DN")
	)
	(segment
		(start 97.570544 -97.757742)
		(end 97.911158 -97.996248)
		(width 0.14732)
		(layer "F.Cu")
		(net "DELTA_L_85_10INCH_TOP_DN")
	)
	(segment
		(start 95.123 -154.051)
		(end 95.000064 -154.173936)
		(width 0.14732)
		(layer "F.Cu")
		(net "DELTA_L_85_10INCH_TOP_DN")
	)
	(segment
		(start 97.823274 -110.074202)
		(end 92.169996 -111.071152)
		(width 0.14732)
		(layer "F.Cu")
		(net "DELTA_L_85_10INCH_TOP_DN")
	)
	(segment
		(start 97.58553 -126.600204)
		(end 97.926144 -126.839218)
		(width 0.14732)
		(layer "F.Cu")
		(net "DELTA_L_85_10INCH_TOP_DN")
	)
	(segment
		(start 91.810078 -111.58474)
		(end 92.008706 -112.710722)
		(width 0.14732)
		(layer "F.Cu")
		(net "DELTA_L_85_10INCH_TOP_DN")
	)
	(segment
		(start 95.123 -146.864578)
		(end 95.123 -154.051)
		(width 0.14732)
		(layer "F.Cu")
		(net "DELTA_L_85_10INCH_TOP_DN")
	)
	(segment
		(start 95.000064 -154.173936)
		(end 95.000064 -154.3685)
		(width 0.14732)
		(layer "F.Cu")
		(net "DELTA_L_85_10INCH_TOP_DN")
	)
	(segment
		(start 97.839784 -117.28323)
		(end 92.14739 -118.287038)
		(width 0.14732)
		(layer "F.Cu")
		(net "DELTA_L_85_10INCH_TOP_DN")
	)
	(segment
		(start 92.011246 -116.20881)
		(end 92.010992 -116.20881)
		(width 0.14732)
		(layer "F.Cu")
		(net "DELTA_L_85_10INCH_TOP_DN")
	)
	(segment
		(start 91.97086 -105.398824)
		(end 91.989148 -105.50271)
		(width 0.14732)
		(layer "F.Cu")
		(net "DELTA_L_85_10INCH_TOP_DN")
	)
	(segment
		(start 92.522294 -113.07064)
		(end 97.565972 -112.180878)
		(width 0.14732)
		(layer "F.Cu")
		(net "DELTA_L_85_10INCH_TOP_DN")
	)
	(segment
		(start 98.089212 -134.968996)
		(end 97.850198 -135.310118)
		(width 0.14732)
		(layer "F.Cu")
		(net "DELTA_L_85_10INCH_TOP_DN")
	)
	(segment
		(start 91.960446 -109.006386)
		(end 91.978988 -109.110272)
		(width 0.14732)
		(layer "F.Cu")
		(net "DELTA_L_85_10INCH_TOP_DN")
	)
	(segment
		(start 97.565972 -112.180878)
		(end 97.907094 -112.419892)
		(width 0.14732)
		(layer "F.Cu")
		(net "DELTA_L_85_10INCH_TOP_DN")
	)
	(segment
		(start 92.140532 -107.470956)
		(end 91.780868 -107.984798)
		(width 0.14732)
		(layer "F.Cu")
		(net "DELTA_L_85_10INCH_TOP_DN")
	)
	(segment
		(start 98.068384 -145.78965)
		(end 97.82937 -146.130772)
		(width 0.14732)
		(layer "F.Cu")
		(net "DELTA_L_85_10INCH_TOP_DN")
	)
	(segment
		(start 91.71813 -89.967308)
		(end 91.91625 -91.092528)
		(width 0.14732)
		(layer "F.Cu")
		(net "DELTA_L_85_10INCH_TOP_DN")
	)
	(segment
		(start 97.593404 -119.387366)
		(end 97.934018 -119.62638)
		(width 0.14732)
		(layer "F.Cu")
		(net "DELTA_L_85_10INCH_TOP_DN")
	)
	(segment
		(start 92.170504 -121.888504)
		(end 91.81084 -122.402346)
		(width 0.14732)
		(layer "F.Cu")
		(net "DELTA_L_85_10INCH_TOP_DN")
	)
	(segment
		(start 91.978988 -109.110272)
		(end 92.493084 -109.469936)
		(width 0.14732)
		(layer "F.Cu")
		(net "DELTA_L_85_10INCH_TOP_DN")
	)
	(segment
		(start 92.169996 -111.071152)
		(end 91.810078 -111.58474)
		(width 0.14732)
		(layer "F.Cu")
		(net "DELTA_L_85_10INCH_TOP_DN")
	)
	(segment
		(start 97.926144 -126.839218)
		(end 98.08845 -127.757682)
		(width 0.14732)
		(layer "F.Cu")
		(net "DELTA_L_85_10INCH_TOP_DN")
	)
	(segment
		(start 98.062288 -109.733842)
		(end 97.823274 -110.074202)
		(width 0.14732)
		(layer "F.Cu")
		(net "DELTA_L_85_10INCH_TOP_DN")
	)
	(segment
		(start 97.586546 -133.811264)
		(end 97.926906 -134.050278)
		(width 0.14732)
		(layer "F.Cu")
		(net "DELTA_L_85_10INCH_TOP_DN")
	)
	(segment
		(start 92.500196 -120.285764)
		(end 97.593404 -119.387366)
		(width 0.14732)
		(layer "F.Cu")
		(net "DELTA_L_85_10INCH_TOP_DN")
	)
	(segment
		(start 92.004134 -127.027178)
		(end 92.022676 -127.131064)
		(width 0.14732)
		(layer "F.Cu")
		(net "DELTA_L_85_10INCH_TOP_DN")
	)
	(segment
		(start 97.926906 -141.261846)
		(end 98.088704 -142.179802)
		(width 0.14732)
		(layer "F.Cu")
		(net "DELTA_L_85_10INCH_TOP_DN")
	)
	(segment
		(start 91.784678 -144.04086)
		(end 91.883738 -144.60347)
		(width 0.14732)
		(layer "F.Cu")
		(net "DELTA_L_85_10INCH_TOP_DN")
	)
	(segment
		(start 91.967304 -137.850626)
		(end 91.985846 -137.954512)
		(width 0.14732)
		(layer "F.Cu")
		(net "DELTA_L_85_10INCH_TOP_DN")
	)
	(segment
		(start 97.585784 -141.022832)
		(end 97.926906 -141.261846)
		(width 0.14732)
		(layer "F.Cu")
		(net "DELTA_L_85_10INCH_TOP_DN")
	)
	(segment
		(start 97.907094 -112.419892)
		(end 98.068892 -113.338102)
		(width 0.14732)
		(layer "F.Cu")
		(net "DELTA_L_85_10INCH_TOP_DN")
	)
	(segment
		(start 97.911158 -137.65911)
		(end 98.07321 -138.57732)
		(width 0.14732)
		(layer "F.Cu")
		(net "DELTA_L_85_10INCH_TOP_DN")
	)
	(segment
		(start 92.004388 -127.027178)
		(end 92.004134 -127.027178)
		(width 0.14732)
		(layer "F.Cu")
		(net "DELTA_L_85_10INCH_TOP_DN")
	)
	(segment
		(start 92.146628 -136.31545)
		(end 91.787218 -136.829292)
		(width 0.14732)
		(layer "F.Cu")
		(net "DELTA_L_85_10INCH_TOP_DN")
	)
	(segment
		(start 91.967558 -137.850626)
		(end 91.967304 -137.850626)
		(width 0.14732)
		(layer "F.Cu")
		(net "DELTA_L_85_10INCH_TOP_DN")
	)
	(segment
		(start 91.731338 -97.176336)
		(end 91.929458 -98.301556)
		(width 0.14732)
		(layer "F.Cu")
		(net "DELTA_L_85_10INCH_TOP_DN")
	)
	(segment
		(start 97.82556 -131.708652)
		(end 92.163646 -132.706618)
		(width 0.14732)
		(layer "F.Cu")
		(net "DELTA_L_85_10INCH_TOP_DN")
	)
	(segment
		(start 91.817444 -129.612136)
		(end 92.016072 -130.737356)
		(width 0.14732)
		(layer "F.Cu")
		(net "DELTA_L_85_10INCH_TOP_DN")
	)
	(segment
		(start 91.803982 -133.220968)
		(end 91.983814 -134.242048)
		(width 0.14732)
		(layer "F.Cu")
		(net "DELTA_L_85_10INCH_TOP_DN")
	)
	(segment
		(start 91.989148 -105.50271)
		(end 92.503244 -105.862374)
		(width 0.14732)
		(layer "F.Cu")
		(net "DELTA_L_85_10INCH_TOP_DN")
	)
	(segment
		(start 91.967558 -119.822214)
		(end 91.9861 -119.9261)
		(width 0.14732)
		(layer "F.Cu")
		(net "DELTA_L_85_10INCH_TOP_DN")
	)
	(segment
		(start 91.983814 -134.242048)
		(end 91.98356 -134.242048)
		(width 0.14732)
		(layer "F.Cu")
		(net "DELTA_L_85_10INCH_TOP_DN")
	)
	(segment
		(start 92.010992 -116.20881)
		(end 92.029534 -116.312696)
		(width 0.14732)
		(layer "F.Cu")
		(net "DELTA_L_85_10INCH_TOP_DN")
	)
	(segment
		(start 97.85096 -102.85857)
		(end 92.150946 -103.863394)
		(width 0.14732)
		(layer "F.Cu")
		(net "DELTA_L_85_10INCH_TOP_DN")
	)
	(segment
		(start 91.985846 -137.954512)
		(end 92.499688 -138.314176)
		(width 0.14732)
		(layer "F.Cu")
		(net "DELTA_L_85_10INCH_TOP_DN")
	)
	(segment
		(start 91.982036 -141.561312)
		(end 92.495116 -141.920468)
		(width 0.14732)
		(layer "F.Cu")
		(net "DELTA_L_85_10INCH_TOP_DN")
	)
	(segment
		(start 95.375984 -146.563334)
		(end 95.123 -146.864578)
		(width 0.14732)
		(layer "F.Cu")
		(net "DELTA_L_85_10INCH_TOP_DN")
	)
	(segment
		(start 97.570036 -94.152212)
		(end 97.910904 -94.390718)
		(width 0.14732)
		(layer "F.Cu")
		(net "DELTA_L_85_10INCH_TOP_DN")
	)
	(segment
		(start 98.06432 -131.36753)
		(end 97.82556 -131.708652)
		(width 0.14732)
		(layer "F.Cu")
		(net "DELTA_L_85_10INCH_TOP_DN")
	)
	(segment
		(start 97.561654 -130.210052)
		(end 97.902522 -130.44932)
		(width 0.14732)
		(layer "F.Cu")
		(net "DELTA_L_85_10INCH_TOP_DN")
	)
	(segment
		(start 92.177362 -129.098548)
		(end 91.817444 -129.612136)
		(width 0.14732)
		(layer "F.Cu")
		(net "DELTA_L_85_10INCH_TOP_DN")
	)
	(segment
		(start 97.570036 -137.42035)
		(end 97.911158 -137.65911)
		(width 0.14732)
		(layer "F.Cu")
		(net "DELTA_L_85_10INCH_TOP_DN")
	)
	(segment
		(start 97.84969 -142.521178)
		(end 92.144088 -143.527272)
		(width 0.14732)
		(layer "F.Cu")
		(net "DELTA_L_85_10INCH_TOP_DN")
	)
	(segment
		(start 97.582228 -90.544396)
		(end 97.923096 -90.782902)
		(width 0.14732)
		(layer "F.Cu")
		(net "DELTA_L_85_10INCH_TOP_DN")
	)
	(segment
		(start 91.983052 -145.166334)
		(end 92.496386 -145.526252)
		(width 0.14732)
		(layer "F.Cu")
		(net "DELTA_L_85_10INCH_TOP_DN")
	)
	(segment
		(start 91.98356 -134.242048)
		(end 92.002102 -134.345934)
		(width 0.14732)
		(layer "F.Cu")
		(net "DELTA_L_85_10INCH_TOP_DN")
	)
	(segment
		(start 92.443808 -98.661474)
		(end 97.570544 -97.757742)
		(width 0.14732)
		(layer "F.Cu")
		(net "DELTA_L_85_10INCH_TOP_DN")
	)
	(segment
		(start 91.929458 -98.301556)
		(end 92.443808 -98.661474)
		(width 0.14732)
		(layer "F.Cu")
		(net "DELTA_L_85_10INCH_TOP_DN")
	)
	(segment
		(start 91.81084 -122.402346)
		(end 91.990672 -123.42368)
		(width 0.14732)
		(layer "F.Cu")
		(net "DELTA_L_85_10INCH_TOP_DN")
	)
	(segment
		(start 97.833942 -138.918442)
		(end 92.143072 -139.92225)
		(width 0.14732)
		(layer "F.Cu")
		(net "DELTA_L_85_10INCH_TOP_DN")
	)
	(segment
		(start 92.144088 -143.527272)
		(end 91.784678 -144.04086)
		(width 0.14732)
		(layer "F.Cu")
		(net "DELTA_L_85_10INCH_TOP_DN")
	)
	(segment
		(start 97.850198 -135.310118)
		(end 92.146628 -136.31545)
		(width 0.14732)
		(layer "F.Cu")
		(net "DELTA_L_85_10INCH_TOP_DN")
	)
	(segment
		(start 97.587054 -101.35997)
		(end 97.927668 -101.598984)
		(width 0.14732)
		(layer "F.Cu")
		(net "DELTA_L_85_10INCH_TOP_DN")
	)
	(segment
		(start 91.784678 -93.5609)
		(end 91.982798 -94.686374)
		(width 0.14732)
		(layer "F.Cu")
		(net "DELTA_L_85_10INCH_TOP_DN")
	)
	(segment
		(start 91.990418 -123.42368)
		(end 92.00896 -123.527566)
		(width 0.14732)
		(layer "F.Cu")
		(net "DELTA_L_85_10INCH_TOP_DN")
	)
	(segment
		(start 98.078798 -116.942108)
		(end 97.839784 -117.28323)
		(width 0.14732)
		(layer "F.Cu")
		(net "DELTA_L_85_10INCH_TOP_DN")
	)
	(segment
		(start 92.143072 -139.92225)
		(end 91.783662 -140.435584)
		(width 0.14732)
		(layer "F.Cu")
		(net "DELTA_L_85_10INCH_TOP_DN")
	)
	(segment
		(start 98.064828 -124.155962)
		(end 97.826068 -124.497084)
		(width 0.14732)
		(layer "F.Cu")
		(net "DELTA_L_85_10INCH_TOP_DN")
	)
	(segment
		(start 92.516198 -134.705598)
		(end 97.586546 -133.811264)
		(width 0.14732)
		(layer "F.Cu")
		(net "DELTA_L_85_10INCH_TOP_DN")
	)
	(segment
		(start 91.831414 -115.187222)
		(end 92.011246 -116.20881)
		(width 0.14732)
		(layer "F.Cu")
		(net "DELTA_L_85_10INCH_TOP_DN")
	)
	(segment
		(start 97.830132 -113.679224)
		(end 92.191078 -114.67338)
		(width 0.14732)
		(layer "F.Cu")
		(net "DELTA_L_85_10INCH_TOP_DN")
	)
	(segment
		(start 92.523056 -123.88723)
		(end 97.561908 -122.998738)
		(width 0.14732)
		(layer "F.Cu")
		(net "DELTA_L_85_10INCH_TOP_DN")
	)
	(segment
		(start 97.910904 -94.390718)
		(end 98.07321 -95.308928)
		(width 0.14732)
		(layer "F.Cu")
		(net "DELTA_L_85_10INCH_TOP_DN")
	)
	(segment
		(start 92.091002 -96.662494)
		(end 91.731338 -97.176336)
		(width 0.14732)
		(layer "F.Cu")
		(net "DELTA_L_85_10INCH_TOP_DN")
	)
	(segment
		(start 91.971114 -105.398824)
		(end 91.97086 -105.398824)
		(width 0.14732)
		(layer "F.Cu")
		(net "DELTA_L_85_10INCH_TOP_DN")
	)
	(segment
		(start 92.022676 -127.131064)
		(end 92.536772 -127.490728)
		(width 0.14732)
		(layer "F.Cu")
		(net "DELTA_L_85_10INCH_TOP_DN")
	)
	(segment
		(start 98.068892 -113.338102)
		(end 97.830132 -113.679224)
		(width 0.14732)
		(layer "F.Cu")
		(net "DELTA_L_85_10INCH_TOP_DN")
	)
	(segment
		(start 91.982798 -94.686374)
		(end 92.497402 -95.046292)
		(width 0.14732)
		(layer "F.Cu")
		(net "DELTA_L_85_10INCH_TOP_DN")
	)
	(segment
		(start 92.016072 -130.737356)
		(end 92.529914 -131.098036)
		(width 0.14732)
		(layer "F.Cu")
		(net "DELTA_L_85_10INCH_TOP_DN")
	)
	(segment
		(start 97.927668 -101.598984)
		(end 98.089974 -102.517448)
		(width 0.14732)
		(layer "F.Cu")
		(net "DELTA_L_85_10INCH_TOP_DN")
	)
	(segment
		(start 92.077794 -89.453466)
		(end 91.71813 -89.967308)
		(width 0.14732)
		(layer "F.Cu")
		(net "DELTA_L_85_10INCH_TOP_DN")
	)
	(segment
		(start 92.499688 -138.314176)
		(end 97.570036 -137.42035)
		(width 0.14732)
		(layer "F.Cu")
		(net "DELTA_L_85_10INCH_TOP_DN")
	)
	(segment
		(start 92.18422 -125.491748)
		(end 91.824556 -126.006098)
		(width 0.14732)
		(layer "F.Cu")
		(net "DELTA_L_85_10INCH_TOP_DN")
	)
	(segment
		(start 91.883484 -144.60347)
		(end 91.92387 -144.832324)
		(width 0.14732)
		(layer "F.Cu")
		(net "DELTA_L_85_10INCH_TOP_DN")
	)
	(segment
		(start 98.09607 -120.545098)
		(end 97.85731 -120.885966)
		(width 0.14732)
		(layer "F.Cu")
		(net "DELTA_L_85_10INCH_TOP_DN")
	)
	(segment
		(start 92.495116 -141.920468)
		(end 97.585784 -141.022832)
		(width 0.14732)
		(layer "F.Cu")
		(net "DELTA_L_85_10INCH_TOP_DN")
	)
	(segment
		(start 97.85731 -120.885966)
		(end 92.170504 -121.888504)
		(width 0.14732)
		(layer "F.Cu")
		(net "DELTA_L_85_10INCH_TOP_DN")
	)
	(segment
		(start 97.926906 -134.050278)
		(end 98.089212 -134.968996)
		(width 0.14732)
		(layer "F.Cu")
		(net "DELTA_L_85_10INCH_TOP_DN")
	)
	(segment
		(start 91.9861 -119.9261)
		(end 92.500196 -120.285764)
		(width 0.14732)
		(layer "F.Cu")
		(net "DELTA_L_85_10INCH_TOP_DN")
	)
	(segment
		(start 97.56521 -144.632426)
		(end 97.906586 -144.87144)
		(width 0.14732)
		(layer "F.Cu")
		(net "DELTA_L_85_10INCH_TOP_DN")
	)
	(segment
		(start 97.837498 -106.46664)
		(end 92.140532 -107.470956)
		(width 0.14732)
		(layer "F.Cu")
		(net "DELTA_L_85_10INCH_TOP_DN")
	)
	(segment
		(start 91.92387 -144.832324)
		(end 91.924124 -144.832832)
		(width 0.14732)
		(layer "F.Cu")
		(net "DELTA_L_85_10INCH_TOP_DN")
	)
	(segment
		(start 97.934018 -119.62638)
		(end 98.09607 -120.545098)
		(width 0.14732)
		(layer "F.Cu")
		(net "DELTA_L_85_10INCH_TOP_DN")
	)
	(segment
		(start 92.150946 -103.863394)
		(end 91.791282 -104.377236)
		(width 0.14732)
		(layer "F.Cu")
		(net "DELTA_L_85_10INCH_TOP_DN")
	)
	(segment
		(start 92.144342 -93.047312)
		(end 91.784678 -93.5609)
		(width 0.14732)
		(layer "F.Cu")
		(net "DELTA_L_85_10INCH_TOP_DN")
	)
	(segment
		(start 91.883738 -144.60347)
		(end 91.883484 -144.60347)
		(width 0.14732)
		(layer "F.Cu")
		(net "DELTA_L_85_10INCH_TOP_DN")
	)
	(segment
		(start 98.085402 -91.701112)
		(end 97.846388 -92.041726)
		(width 0.14732)
		(layer "F.Cu")
		(net "DELTA_L_85_10INCH_TOP_DN")
	)
	(segment
		(start 92.536772 -127.490728)
		(end 97.58553 -126.600204)
		(width 0.14732)
		(layer "F.Cu")
		(net "DELTA_L_85_10INCH_TOP_DN")
	)
	(segment
		(start 97.899982 -108.815632)
		(end 98.062288 -109.733842)
		(width 0.14732)
		(layer "F.Cu")
		(net "DELTA_L_85_10INCH_TOP_DN")
	)
	(segment
		(start 97.561908 -122.998738)
		(end 97.90303 -123.237752)
		(width 0.14732)
		(layer "F.Cu")
		(net "DELTA_L_85_10INCH_TOP_DN")
	)
	(segment
		(start 91.780868 -107.984798)
		(end 91.9607 -109.006386)
		(width 0.14732)
		(layer "F.Cu")
		(net "DELTA_L_85_10INCH_TOP_DN")
	)
	(segment
		(start 92.54363 -116.67236)
		(end 97.575878 -115.78463)
		(width 0.14732)
		(layer "F.Cu")
		(net "DELTA_L_85_10INCH_TOP_DN")
	)
	(segment
		(start 92.497402 -95.046292)
		(end 97.570036 -94.152212)
		(width 0.14732)
		(layer "F.Cu")
		(net "DELTA_L_85_10INCH_TOP_DN")
	)
	(segment
		(start 91.787218 -136.829292)
		(end 91.967558 -137.850626)
		(width 0.14732)
		(layer "F.Cu")
		(net "DELTA_L_85_10INCH_TOP_DN")
	)
	(segment
		(start 91.78798 -118.800626)
		(end 91.967812 -119.822214)
		(width 0.14732)
		(layer "F.Cu")
		(net "DELTA_L_85_10INCH_TOP_DN")
	)
	(segment
		(start 95.000064 -84.252308)
		(end 95.123 -84.375244)
		(width 0.14732)
		(layer "F.Cu")
		(net "DELTA_L_85_10INCH_TOP_DN")
	)
	(segment
		(start 97.911158 -97.996248)
		(end 98.07321 -98.914458)
		(width 0.14732)
		(layer "F.Cu")
		(net "DELTA_L_85_10INCH_TOP_DN")
	)
	(segment
		(start 97.575878 -115.78463)
		(end 97.916492 -116.023644)
		(width 0.14732)
		(layer "F.Cu")
		(net "DELTA_L_85_10INCH_TOP_DN")
	)
	(segment
		(start 94.972886 -88.94318)
		(end 92.077794 -89.453466)
		(width 0.14732)
		(layer "F.Cu")
		(net "DELTA_L_85_10INCH_TOP_DN")
	)
	(segment
		(start 91.791282 -104.377236)
		(end 91.971114 -105.398824)
		(width 0.14732)
		(layer "F.Cu")
		(net "DELTA_L_85_10INCH_TOP_DN")
	)
	(segment
		(start 91.91625 -91.092528)
		(end 92.4306 -91.452446)
		(width 0.14732)
		(layer "F.Cu")
		(net "DELTA_L_85_10INCH_TOP_DN")
	)
	(segment
		(start 97.916492 -116.023644)
		(end 98.078798 -116.942108)
		(width 0.14732)
		(layer "F.Cu")
		(net "DELTA_L_85_10INCH_TOP_DN")
	)
	(segment
		(start 95.123 -88.76411)
		(end 94.972886 -88.94318)
		(width 0.14732)
		(layer "F.Cu")
		(net "DELTA_L_85_10INCH_TOP_DN")
	)
	(segment
		(start 98.08845 -127.757682)
		(end 97.849436 -128.098804)
		(width 0.14732)
		(layer "F.Cu")
		(net "DELTA_L_85_10INCH_TOP_DN")
	)
	(segment
		(start 92.503244 -105.862374)
		(end 97.573592 -104.96804)
		(width 0.14732)
		(layer "F.Cu")
		(net "DELTA_L_85_10INCH_TOP_DN")
	)
	(segment
		(start 91.824556 -126.006098)
		(end 92.004388 -127.027178)
		(width 0.14732)
		(layer "F.Cu")
		(net "DELTA_L_85_10INCH_TOP_DN")
	)
	(segment
		(start 91.772994 -100.7745)
		(end 91.971114 -101.899974)
		(width 0.14732)
		(layer "F.Cu")
		(net "DELTA_L_85_10INCH_TOP_DN")
	)
	(segment
		(start 95.000064 -84.057744)
		(end 95.000064 -84.252308)
		(width 0.14732)
		(layer "F.Cu")
		(net "DELTA_L_85_10INCH_TOP_DN")
	)
	(segment
		(start 95.123 -84.375244)
		(end 95.123 -88.76411)
		(width 0.14732)
		(layer "F.Cu")
		(net "DELTA_L_85_10INCH_TOP_DN")
	)
	(segment
		(start 98.07321 -95.308928)
		(end 97.834196 -95.649542)
		(width 0.14732)
		(layer "F.Cu")
		(net "DELTA_L_85_10INCH_TOP_DN")
	)
	(segment
		(start 92.002102 -134.345934)
		(end 92.516198 -134.705598)
		(width 0.14732)
		(layer "F.Cu")
		(net "DELTA_L_85_10INCH_TOP_DN")
	)
	(segment
		(start 97.906586 -144.87144)
		(end 98.068384 -145.78965)
		(width 0.14732)
		(layer "F.Cu")
		(net "DELTA_L_85_10INCH_TOP_DN")
	)
	(segment
		(start 97.82937 -146.130772)
		(end 95.375984 -146.563334)
		(width 0.14732)
		(layer "F.Cu")
		(net "DELTA_L_85_10INCH_TOP_DN")
	)
	(segment
		(start 92.485464 -102.259892)
		(end 97.587054 -101.35997)
		(width 0.14732)
		(layer "F.Cu")
		(net "DELTA_L_85_10INCH_TOP_DN")
	)
	(segment
		(start 91.924124 -144.832832)
		(end 91.983052 -145.166334)
		(width 0.14732)
		(layer "F.Cu")
		(net "DELTA_L_85_10INCH_TOP_DN")
	)
	(segment
		(start 92.496386 -145.526252)
		(end 97.56521 -144.632426)
		(width 0.14732)
		(layer "F.Cu")
		(net "DELTA_L_85_10INCH_TOP_DN")
	)
	(segment
		(start 97.846388 -92.041726)
		(end 92.144342 -93.047312)
		(width 0.14732)
		(layer "F.Cu")
		(net "DELTA_L_85_10INCH_TOP_DN")
	)
	(segment
		(start 98.076258 -106.125518)
		(end 97.837498 -106.46664)
		(width 0.14732)
		(layer "F.Cu")
		(net "DELTA_L_85_10INCH_TOP_DN")
	)
	(segment
		(start 92.4306 -91.452446)
		(end 97.582228 -90.544396)
		(width 0.14732)
		(layer "F.Cu")
		(net "DELTA_L_85_10INCH_TOP_DN")
	)
	(segment
		(start 92.163646 -132.706618)
		(end 91.803982 -133.220968)
		(width 0.14732)
		(layer "F.Cu")
		(net "DELTA_L_85_10INCH_TOP_DN")
	)
	(segment
		(start 97.559114 -108.576872)
		(end 97.899982 -108.815632)
		(width 0.14732)
		(layer "F.Cu")
		(net "DELTA_L_85_10INCH_TOP_DN")
	)
	(segment
		(start 97.834196 -95.649542)
		(end 92.091002 -96.662494)
		(width 0.14732)
		(layer "F.Cu")
		(net "DELTA_L_85_10INCH_TOP_DN")
	)
	(segment
		(start 97.83445 -99.255326)
		(end 92.132404 -100.261166)
		(width 0.14732)
		(layer "F.Cu")
		(net "DELTA_L_85_10INCH_TOP_DN")
	)
	(segment
		(start 92.132404 -100.261166)
		(end 91.772994 -100.7745)
		(width 0.14732)
		(layer "F.Cu")
		(net "DELTA_L_85_10INCH_TOP_DN")
	)
	(segment
		(start 97.90303 -123.237752)
		(end 98.064828 -124.155962)
		(width 0.14732)
		(layer "F.Cu")
		(net "DELTA_L_85_10INCH_TOP_DN")
	)
	(segment
		(start 97.573592 -104.96804)
		(end 97.91446 -105.207308)
		(width 0.14732)
		(layer "F.Cu")
		(net "DELTA_L_85_10INCH_TOP_DN")
	)
	(segment
		(start 91.9607 -109.006386)
		(end 91.960446 -109.006386)
		(width 0.14732)
		(layer "F.Cu")
		(net "DELTA_L_85_10INCH_TOP_DN")
	)
	(segment
		(start 97.923096 -90.782902)
		(end 98.085402 -91.701112)
		(width 0.14732)
		(layer "F.Cu")
		(net "DELTA_L_85_10INCH_TOP_DN")
	)
	(segment
		(start 98.088704 -142.179802)
		(end 97.84969 -142.521178)
		(width 0.14732)
		(layer "F.Cu")
		(net "DELTA_L_85_10INCH_TOP_DN")
	)
	(segment
		(start 92.14739 -118.287038)
		(end 91.78798 -118.800626)
		(width 0.14732)
		(layer "F.Cu")
		(net "DELTA_L_85_10INCH_TOP_DN")
	)
	(segment
		(start 91.971114 -101.899974)
		(end 92.485464 -102.259892)
		(width 0.14732)
		(layer "F.Cu")
		(net "DELTA_L_85_10INCH_TOP_DN")
	)
	(segment
		(start 91.783662 -140.435584)
		(end 91.982036 -141.561312)
		(width 0.14732)
		(layer "F.Cu")
		(net "DELTA_L_85_10INCH_TOP_DN")
	)
	(segment
		(start 97.624646 -144.363948)
		(end 98.138488 -144.723612)
		(width 0.14732)
		(layer "F.Cu")
		(net "DELTA_L_85_10INCH_TOP_DP")
	)
	(segment
		(start 92.338906 -114.905282)
		(end 92.099892 -115.246658)
		(width 0.14732)
		(layer "F.Cu")
		(net "DELTA_L_85_10INCH_TOP_DP")
	)
	(segment
		(start 98.132138 -108.667804)
		(end 98.330766 -109.793532)
		(width 0.14732)
		(layer "F.Cu")
		(net "DELTA_L_85_10INCH_TOP_DP")
	)
	(segment
		(start 98.341942 -98.974148)
		(end 97.982278 -99.487482)
		(width 0.14732)
		(layer "F.Cu")
		(net "DELTA_L_85_10INCH_TOP_DP")
	)
	(segment
		(start 92.07246 -133.280404)
		(end 92.234004 -134.198106)
		(width 0.14732)
		(layer "F.Cu")
		(net "DELTA_L_85_10INCH_TOP_DP")
	)
	(segment
		(start 98.005138 -121.117868)
		(end 92.318332 -122.120406)
		(width 0.14732)
		(layer "F.Cu")
		(net "DELTA_L_85_10INCH_TOP_DP")
	)
	(segment
		(start 97.985326 -106.698542)
		(end 92.28836 -107.702858)
		(width 0.14732)
		(layer "F.Cu")
		(net "DELTA_L_85_10INCH_TOP_DP")
	)
	(segment
		(start 98.142806 -94.24289)
		(end 98.341688 -95.368618)
		(width 0.14732)
		(layer "F.Cu")
		(net "DELTA_L_85_10INCH_TOP_DP")
	)
	(segment
		(start 91.986608 -90.026744)
		(end 92.148152 -90.9447)
		(width 0.14732)
		(layer "F.Cu")
		(net "DELTA_L_85_10INCH_TOP_DP")
	)
	(segment
		(start 97.633282 -104.699562)
		(end 98.146616 -105.05948)
		(width 0.14732)
		(layer "F.Cu")
		(net "DELTA_L_85_10INCH_TOP_DP")
	)
	(segment
		(start 92.099892 -115.246658)
		(end 92.261436 -116.164868)
		(width 0.14732)
		(layer "F.Cu")
		(net "DELTA_L_85_10INCH_TOP_DP")
	)
	(segment
		(start 92.240862 -112.562894)
		(end 92.581984 -112.801908)
		(width 0.14732)
		(layer "F.Cu")
		(net "DELTA_L_85_10INCH_TOP_DP")
	)
	(segment
		(start 91.999816 -97.235772)
		(end 92.16136 -98.153728)
		(width 0.14732)
		(layer "F.Cu")
		(net "DELTA_L_85_10INCH_TOP_DP")
	)
	(segment
		(start 92.582492 -123.618752)
		(end 97.621598 -122.730006)
		(width 0.14732)
		(layer "F.Cu")
		(net "DELTA_L_85_10INCH_TOP_DP")
	)
	(segment
		(start 92.23883 -96.894396)
		(end 91.999816 -97.235772)
		(width 0.14732)
		(layer "F.Cu")
		(net "DELTA_L_85_10INCH_TOP_DP")
	)
	(segment
		(start 97.653094 -119.118888)
		(end 98.166174 -119.478552)
		(width 0.14732)
		(layer "F.Cu")
		(net "DELTA_L_85_10INCH_TOP_DP")
	)
	(segment
		(start 92.490036 -91.183968)
		(end 97.641918 -90.275664)
		(width 0.14732)
		(layer "F.Cu")
		(net "DELTA_L_85_10INCH_TOP_DP")
	)
	(segment
		(start 98.173286 -90.73896)
		(end 98.35388 -91.760802)
		(width 0.14732)
		(layer "F.Cu")
		(net "DELTA_L_85_10INCH_TOP_DP")
	)
	(segment
		(start 92.079318 -122.461782)
		(end 92.240862 -123.379738)
		(width 0.14732)
		(layer "F.Cu")
		(net "DELTA_L_85_10INCH_TOP_DP")
	)
	(segment
		(start 92.221304 -105.354882)
		(end 92.56268 -105.593896)
		(width 0.14732)
		(layer "F.Cu")
		(net "DELTA_L_85_10INCH_TOP_DP")
	)
	(segment
		(start 98.158808 -141.114018)
		(end 98.357182 -142.239238)
		(width 0.14732)
		(layer "F.Cu")
		(net "DELTA_L_85_10INCH_TOP_DP")
	)
	(segment
		(start 92.2147 -94.538546)
		(end 92.556838 -94.777814)
		(width 0.14732)
		(layer "F.Cu")
		(net "DELTA_L_85_10INCH_TOP_DP")
	)
	(segment
		(start 92.556076 -145.25752)
		(end 97.624646 -144.363948)
		(width 0.14732)
		(layer "F.Cu")
		(net "DELTA_L_85_10INCH_TOP_DP")
	)
	(segment
		(start 97.621598 -122.730006)
		(end 98.135186 -123.089924)
		(width 0.14732)
		(layer "F.Cu")
		(net "DELTA_L_85_10INCH_TOP_DP")
	)
	(segment
		(start 92.589604 -130.829558)
		(end 97.621344 -129.941574)
		(width 0.14732)
		(layer "F.Cu")
		(net "DELTA_L_85_10INCH_TOP_DP")
	)
	(segment
		(start 92.295218 -118.51894)
		(end 92.056458 -118.860062)
		(width 0.14732)
		(layer "F.Cu")
		(net "DELTA_L_85_10INCH_TOP_DP")
	)
	(segment
		(start 92.203016 -101.752146)
		(end 92.5449 -101.991414)
		(width 0.14732)
		(layer "F.Cu")
		(net "DELTA_L_85_10INCH_TOP_DP")
	)
	(segment
		(start 98.1583 -126.69139)
		(end 98.357182 -127.817372)
		(width 0.14732)
		(layer "F.Cu")
		(net "DELTA_L_85_10INCH_TOP_DP")
	)
	(segment
		(start 92.055696 -136.888728)
		(end 92.217748 -137.806684)
		(width 0.14732)
		(layer "F.Cu")
		(net "DELTA_L_85_10INCH_TOP_DP")
	)
	(segment
		(start 97.998026 -135.542274)
		(end 92.294456 -136.547352)
		(width 0.14732)
		(layer "F.Cu")
		(net "DELTA_L_85_10INCH_TOP_DP")
	)
	(segment
		(start 95.377 -88.856566)
		(end 95.108014 -89.177368)
		(width 0.14732)
		(layer "F.Cu")
		(net "DELTA_L_85_10INCH_TOP_DP")
	)
	(segment
		(start 92.503244 -98.392996)
		(end 97.62998 -97.489264)
		(width 0.14732)
		(layer "F.Cu")
		(net "DELTA_L_85_10INCH_TOP_DP")
	)
	(segment
		(start 92.311474 -132.93852)
		(end 92.07246 -133.280404)
		(width 0.14732)
		(layer "F.Cu")
		(net "DELTA_L_85_10INCH_TOP_DP")
	)
	(segment
		(start 98.159062 -133.90245)
		(end 98.357944 -135.028432)
		(width 0.14732)
		(layer "F.Cu")
		(net "DELTA_L_85_10INCH_TOP_DP")
	)
	(segment
		(start 98.357182 -127.817372)
		(end 97.997264 -128.33096)
		(width 0.14732)
		(layer "F.Cu")
		(net "DELTA_L_85_10INCH_TOP_DP")
	)
	(segment
		(start 92.280232 -100.493068)
		(end 92.041472 -100.83419)
		(width 0.14732)
		(layer "F.Cu")
		(net "DELTA_L_85_10INCH_TOP_DP")
	)
	(segment
		(start 92.603066 -116.403882)
		(end 97.635568 -115.516152)
		(width 0.14732)
		(layer "F.Cu")
		(net "DELTA_L_85_10INCH_TOP_DP")
	)
	(segment
		(start 95.511112 -146.797522)
		(end 95.377 -146.957288)
		(width 0.14732)
		(layer "F.Cu")
		(net "DELTA_L_85_10INCH_TOP_DP")
	)
	(segment
		(start 92.5449 -101.991414)
		(end 97.646744 -101.091492)
		(width 0.14732)
		(layer "F.Cu")
		(net "DELTA_L_85_10INCH_TOP_DP")
	)
	(segment
		(start 98.138488 -144.723612)
		(end 98.336862 -145.849086)
		(width 0.14732)
		(layer "F.Cu")
		(net "DELTA_L_85_10INCH_TOP_DP")
	)
	(segment
		(start 98.159824 -101.451156)
		(end 98.358706 -102.577138)
		(width 0.14732)
		(layer "F.Cu")
		(net "DELTA_L_85_10INCH_TOP_DP")
	)
	(segment
		(start 98.13925 -112.272064)
		(end 98.33737 -113.397538)
		(width 0.14732)
		(layer "F.Cu")
		(net "DELTA_L_85_10INCH_TOP_DP")
	)
	(segment
		(start 97.618804 -108.30814)
		(end 98.132138 -108.667804)
		(width 0.14732)
		(layer "F.Cu")
		(net "DELTA_L_85_10INCH_TOP_DP")
	)
	(segment
		(start 92.05214 -140.495274)
		(end 92.213938 -141.413484)
		(width 0.14732)
		(layer "F.Cu")
		(net "DELTA_L_85_10INCH_TOP_DP")
	)
	(segment
		(start 98.34753 -117.001798)
		(end 97.987612 -117.515386)
		(width 0.14732)
		(layer "F.Cu")
		(net "DELTA_L_85_10INCH_TOP_DP")
	)
	(segment
		(start 92.085922 -129.671826)
		(end 92.247974 -130.589782)
		(width 0.14732)
		(layer "F.Cu")
		(net "DELTA_L_85_10INCH_TOP_DP")
	)
	(segment
		(start 98.166174 -119.478552)
		(end 98.364548 -120.604534)
		(width 0.14732)
		(layer "F.Cu")
		(net "DELTA_L_85_10INCH_TOP_DP")
	)
	(segment
		(start 92.053156 -144.100296)
		(end 92.214954 -145.018506)
		(width 0.14732)
		(layer "F.Cu")
		(net "DELTA_L_85_10INCH_TOP_DP")
	)
	(segment
		(start 97.997518 -142.75308)
		(end 92.291916 -143.759174)
		(width 0.14732)
		(layer "F.Cu")
		(net "DELTA_L_85_10INCH_TOP_DP")
	)
	(segment
		(start 97.629726 -137.151618)
		(end 98.14306 -137.511282)
		(width 0.14732)
		(layer "F.Cu")
		(net "DELTA_L_85_10INCH_TOP_DP")
	)
	(segment
		(start 92.056458 -118.860062)
		(end 92.218002 -119.778272)
		(width 0.14732)
		(layer "F.Cu")
		(net "DELTA_L_85_10INCH_TOP_DP")
	)
	(segment
		(start 97.973388 -131.940554)
		(end 92.311474 -132.93852)
		(width 0.14732)
		(layer "F.Cu")
		(net "DELTA_L_85_10INCH_TOP_DP")
	)
	(segment
		(start 97.621344 -129.941574)
		(end 98.134678 -130.301492)
		(width 0.14732)
		(layer "F.Cu")
		(net "DELTA_L_85_10INCH_TOP_DP")
	)
	(segment
		(start 97.629726 -93.88348)
		(end 98.142806 -94.24289)
		(width 0.14732)
		(layer "F.Cu")
		(net "DELTA_L_85_10INCH_TOP_DP")
	)
	(segment
		(start 97.994216 -92.273882)
		(end 92.29217 -93.279468)
		(width 0.14732)
		(layer "F.Cu")
		(net "DELTA_L_85_10INCH_TOP_DP")
	)
	(segment
		(start 92.07881 -111.64443)
		(end 92.240862 -112.562894)
		(width 0.14732)
		(layer "F.Cu")
		(net "DELTA_L_85_10INCH_TOP_DP")
	)
	(segment
		(start 92.291916 -143.759174)
		(end 92.053156 -144.100296)
		(width 0.14732)
		(layer "F.Cu")
		(net "DELTA_L_85_10INCH_TOP_DP")
	)
	(segment
		(start 92.55252 -109.201458)
		(end 97.618804 -108.30814)
		(width 0.14732)
		(layer "F.Cu")
		(net "DELTA_L_85_10INCH_TOP_DP")
	)
	(segment
		(start 97.635568 -115.516152)
		(end 98.148648 -115.875816)
		(width 0.14732)
		(layer "F.Cu")
		(net "DELTA_L_85_10INCH_TOP_DP")
	)
	(segment
		(start 97.982278 -99.487482)
		(end 92.280232 -100.493068)
		(width 0.14732)
		(layer "F.Cu")
		(net "DELTA_L_85_10INCH_TOP_DP")
	)
	(segment
		(start 98.357182 -142.239238)
		(end 97.997518 -142.75308)
		(width 0.14732)
		(layer "F.Cu")
		(net "DELTA_L_85_10INCH_TOP_DP")
	)
	(segment
		(start 92.240862 -123.379738)
		(end 92.582492 -123.618752)
		(width 0.14732)
		(layer "F.Cu")
		(net "DELTA_L_85_10INCH_TOP_DP")
	)
	(segment
		(start 97.625662 -111.912146)
		(end 98.13925 -112.272064)
		(width 0.14732)
		(layer "F.Cu")
		(net "DELTA_L_85_10INCH_TOP_DP")
	)
	(segment
		(start 92.294456 -136.547352)
		(end 92.055696 -136.888728)
		(width 0.14732)
		(layer "F.Cu")
		(net "DELTA_L_85_10INCH_TOP_DP")
	)
	(segment
		(start 92.218002 -119.778272)
		(end 92.559632 -120.017286)
		(width 0.14732)
		(layer "F.Cu")
		(net "DELTA_L_85_10INCH_TOP_DP")
	)
	(segment
		(start 98.336862 -145.849086)
		(end 97.977198 -146.362674)
		(width 0.14732)
		(layer "F.Cu")
		(net "DELTA_L_85_10INCH_TOP_DP")
	)
	(segment
		(start 92.213938 -141.413484)
		(end 92.554552 -141.65199)
		(width 0.14732)
		(layer "F.Cu")
		(net "DELTA_L_85_10INCH_TOP_DP")
	)
	(segment
		(start 98.154998 -90.635074)
		(end 98.17354 -90.73896)
		(width 0.14732)
		(layer "F.Cu")
		(net "DELTA_L_85_10INCH_TOP_DP")
	)
	(segment
		(start 92.318332 -122.120406)
		(end 92.079318 -122.461782)
		(width 0.14732)
		(layer "F.Cu")
		(net "DELTA_L_85_10INCH_TOP_DP")
	)
	(segment
		(start 97.970848 -110.306104)
		(end 92.317824 -111.303308)
		(width 0.14732)
		(layer "F.Cu")
		(net "DELTA_L_85_10INCH_TOP_DP")
	)
	(segment
		(start 95.377 -84.375244)
		(end 95.377 -88.856566)
		(width 0.14732)
		(layer "F.Cu")
		(net "DELTA_L_85_10INCH_TOP_DP")
	)
	(segment
		(start 98.14306 -137.511282)
		(end 98.341942 -138.63701)
		(width 0.14732)
		(layer "F.Cu")
		(net "DELTA_L_85_10INCH_TOP_DP")
	)
	(segment
		(start 98.341942 -138.63701)
		(end 97.98177 -139.150598)
		(width 0.14732)
		(layer "F.Cu")
		(net "DELTA_L_85_10INCH_TOP_DP")
	)
	(segment
		(start 92.053156 -93.62059)
		(end 92.2147 -94.538546)
		(width 0.14732)
		(layer "F.Cu")
		(net "DELTA_L_85_10INCH_TOP_DP")
	)
	(segment
		(start 95.499936 -84.252308)
		(end 95.377 -84.375244)
		(width 0.14732)
		(layer "F.Cu")
		(net "DELTA_L_85_10INCH_TOP_DP")
	)
	(segment
		(start 98.35388 -91.760802)
		(end 97.994216 -92.273882)
		(width 0.14732)
		(layer "F.Cu")
		(net "DELTA_L_85_10INCH_TOP_DP")
	)
	(segment
		(start 98.364548 -120.604534)
		(end 98.005138 -121.117868)
		(width 0.14732)
		(layer "F.Cu")
		(net "DELTA_L_85_10INCH_TOP_DP")
	)
	(segment
		(start 92.596208 -127.22225)
		(end 97.64522 -126.331726)
		(width 0.14732)
		(layer "F.Cu")
		(net "DELTA_L_85_10INCH_TOP_DP")
	)
	(segment
		(start 92.317824 -111.303308)
		(end 92.07881 -111.64443)
		(width 0.14732)
		(layer "F.Cu")
		(net "DELTA_L_85_10INCH_TOP_DP")
	)
	(segment
		(start 92.148152 -90.9447)
		(end 92.490036 -91.183968)
		(width 0.14732)
		(layer "F.Cu")
		(net "DELTA_L_85_10INCH_TOP_DP")
	)
	(segment
		(start 95.108014 -89.177368)
		(end 92.225622 -89.685368)
		(width 0.14732)
		(layer "F.Cu")
		(net "DELTA_L_85_10INCH_TOP_DP")
	)
	(segment
		(start 92.56268 -105.593896)
		(end 97.633282 -104.699562)
		(width 0.14732)
		(layer "F.Cu")
		(net "DELTA_L_85_10INCH_TOP_DP")
	)
	(segment
		(start 97.641918 -90.275664)
		(end 98.154998 -90.635074)
		(width 0.14732)
		(layer "F.Cu")
		(net "DELTA_L_85_10INCH_TOP_DP")
	)
	(segment
		(start 92.28836 -107.702858)
		(end 92.049346 -108.044234)
		(width 0.14732)
		(layer "F.Cu")
		(net "DELTA_L_85_10INCH_TOP_DP")
	)
	(segment
		(start 92.298774 -104.095296)
		(end 92.05976 -104.436672)
		(width 0.14732)
		(layer "F.Cu")
		(net "DELTA_L_85_10INCH_TOP_DP")
	)
	(segment
		(start 97.982024 -95.881698)
		(end 92.23883 -96.894396)
		(width 0.14732)
		(layer "F.Cu")
		(net "DELTA_L_85_10INCH_TOP_DP")
	)
	(segment
		(start 97.987612 -117.515386)
		(end 92.295218 -118.51894)
		(width 0.14732)
		(layer "F.Cu")
		(net "DELTA_L_85_10INCH_TOP_DP")
	)
	(segment
		(start 98.357944 -135.028432)
		(end 97.998026 -135.542274)
		(width 0.14732)
		(layer "F.Cu")
		(net "DELTA_L_85_10INCH_TOP_DP")
	)
	(segment
		(start 92.2909 -140.154406)
		(end 92.05214 -140.495274)
		(width 0.14732)
		(layer "F.Cu")
		(net "DELTA_L_85_10INCH_TOP_DP")
	)
	(segment
		(start 98.17354 -90.73896)
		(end 98.173286 -90.73896)
		(width 0.14732)
		(layer "F.Cu")
		(net "DELTA_L_85_10INCH_TOP_DP")
	)
	(segment
		(start 98.344736 -106.184954)
		(end 97.985326 -106.698542)
		(width 0.14732)
		(layer "F.Cu")
		(net "DELTA_L_85_10INCH_TOP_DP")
	)
	(segment
		(start 92.559632 -120.017286)
		(end 97.653094 -119.118888)
		(width 0.14732)
		(layer "F.Cu")
		(net "DELTA_L_85_10INCH_TOP_DP")
	)
	(segment
		(start 97.997264 -128.33096)
		(end 92.32519 -129.330704)
		(width 0.14732)
		(layer "F.Cu")
		(net "DELTA_L_85_10INCH_TOP_DP")
	)
	(segment
		(start 98.148648 -115.875816)
		(end 98.34753 -117.001798)
		(width 0.14732)
		(layer "F.Cu")
		(net "DELTA_L_85_10INCH_TOP_DP")
	)
	(segment
		(start 97.998788 -103.090726)
		(end 92.298774 -104.095296)
		(width 0.14732)
		(layer "F.Cu")
		(net "DELTA_L_85_10INCH_TOP_DP")
	)
	(segment
		(start 98.146616 -105.05948)
		(end 98.344736 -106.184954)
		(width 0.14732)
		(layer "F.Cu")
		(net "DELTA_L_85_10INCH_TOP_DP")
	)
	(segment
		(start 98.134678 -130.301492)
		(end 98.332798 -131.426966)
		(width 0.14732)
		(layer "F.Cu")
		(net "DELTA_L_85_10INCH_TOP_DP")
	)
	(segment
		(start 97.977198 -146.362674)
		(end 95.511112 -146.797522)
		(width 0.14732)
		(layer "F.Cu")
		(net "DELTA_L_85_10INCH_TOP_DP")
	)
	(segment
		(start 95.377 -146.957288)
		(end 95.377 -154.051)
		(width 0.14732)
		(layer "F.Cu")
		(net "DELTA_L_85_10INCH_TOP_DP")
	)
	(segment
		(start 92.247974 -130.589782)
		(end 92.589604 -130.829558)
		(width 0.14732)
		(layer "F.Cu")
		(net "DELTA_L_85_10INCH_TOP_DP")
	)
	(segment
		(start 92.225622 -89.685368)
		(end 91.986608 -90.026744)
		(width 0.14732)
		(layer "F.Cu")
		(net "DELTA_L_85_10INCH_TOP_DP")
	)
	(segment
		(start 92.234004 -134.198106)
		(end 92.575634 -134.43712)
		(width 0.14732)
		(layer "F.Cu")
		(net "DELTA_L_85_10INCH_TOP_DP")
	)
	(segment
		(start 95.377 -154.051)
		(end 95.499936 -154.173936)
		(width 0.14732)
		(layer "F.Cu")
		(net "DELTA_L_85_10INCH_TOP_DP")
	)
	(segment
		(start 98.14306 -97.84842)
		(end 98.341942 -98.974148)
		(width 0.14732)
		(layer "F.Cu")
		(net "DELTA_L_85_10INCH_TOP_DP")
	)
	(segment
		(start 98.330766 -109.793532)
		(end 97.970848 -110.306104)
		(width 0.14732)
		(layer "F.Cu")
		(net "DELTA_L_85_10INCH_TOP_DP")
	)
	(segment
		(start 97.62998 -97.489264)
		(end 98.14306 -97.84842)
		(width 0.14732)
		(layer "F.Cu")
		(net "DELTA_L_85_10INCH_TOP_DP")
	)
	(segment
		(start 97.97796 -113.911126)
		(end 92.338906 -114.905282)
		(width 0.14732)
		(layer "F.Cu")
		(net "DELTA_L_85_10INCH_TOP_DP")
	)
	(segment
		(start 92.214954 -145.018506)
		(end 92.556076 -145.25752)
		(width 0.14732)
		(layer "F.Cu")
		(net "DELTA_L_85_10INCH_TOP_DP")
	)
	(segment
		(start 92.05976 -104.436672)
		(end 92.221304 -105.354882)
		(width 0.14732)
		(layer "F.Cu")
		(net "DELTA_L_85_10INCH_TOP_DP")
	)
	(segment
		(start 97.646236 -133.542786)
		(end 98.159062 -133.90245)
		(width 0.14732)
		(layer "F.Cu")
		(net "DELTA_L_85_10INCH_TOP_DP")
	)
	(segment
		(start 92.041472 -100.83419)
		(end 92.203016 -101.752146)
		(width 0.14732)
		(layer "F.Cu")
		(net "DELTA_L_85_10INCH_TOP_DP")
	)
	(segment
		(start 92.16136 -98.153728)
		(end 92.503244 -98.392996)
		(width 0.14732)
		(layer "F.Cu")
		(net "DELTA_L_85_10INCH_TOP_DP")
	)
	(segment
		(start 92.217748 -137.806684)
		(end 92.559124 -138.045698)
		(width 0.14732)
		(layer "F.Cu")
		(net "DELTA_L_85_10INCH_TOP_DP")
	)
	(segment
		(start 98.332798 -131.426966)
		(end 97.973388 -131.940554)
		(width 0.14732)
		(layer "F.Cu")
		(net "DELTA_L_85_10INCH_TOP_DP")
	)
	(segment
		(start 92.559124 -138.045698)
		(end 97.629726 -137.151618)
		(width 0.14732)
		(layer "F.Cu")
		(net "DELTA_L_85_10INCH_TOP_DP")
	)
	(segment
		(start 92.581984 -112.801908)
		(end 97.625662 -111.912146)
		(width 0.14732)
		(layer "F.Cu")
		(net "DELTA_L_85_10INCH_TOP_DP")
	)
	(segment
		(start 98.135186 -123.089924)
		(end 98.333306 -124.215398)
		(width 0.14732)
		(layer "F.Cu")
		(net "DELTA_L_85_10INCH_TOP_DP")
	)
	(segment
		(start 92.21089 -108.962444)
		(end 92.55252 -109.201458)
		(width 0.14732)
		(layer "F.Cu")
		(net "DELTA_L_85_10INCH_TOP_DP")
	)
	(segment
		(start 98.33737 -113.397538)
		(end 97.97796 -113.911126)
		(width 0.14732)
		(layer "F.Cu")
		(net "DELTA_L_85_10INCH_TOP_DP")
	)
	(segment
		(start 92.29217 -93.279468)
		(end 92.053156 -93.62059)
		(width 0.14732)
		(layer "F.Cu")
		(net "DELTA_L_85_10INCH_TOP_DP")
	)
	(segment
		(start 98.333306 -124.215398)
		(end 97.973896 -124.728986)
		(width 0.14732)
		(layer "F.Cu")
		(net "DELTA_L_85_10INCH_TOP_DP")
	)
	(segment
		(start 92.556838 -94.777814)
		(end 97.629726 -93.88348)
		(width 0.14732)
		(layer "F.Cu")
		(net "DELTA_L_85_10INCH_TOP_DP")
	)
	(segment
		(start 97.98177 -139.150598)
		(end 92.2909 -140.154406)
		(width 0.14732)
		(layer "F.Cu")
		(net "DELTA_L_85_10INCH_TOP_DP")
	)
	(segment
		(start 95.499936 -84.057744)
		(end 95.499936 -84.252308)
		(width 0.14732)
		(layer "F.Cu")
		(net "DELTA_L_85_10INCH_TOP_DP")
	)
	(segment
		(start 92.575634 -134.43712)
		(end 97.646236 -133.542786)
		(width 0.14732)
		(layer "F.Cu")
		(net "DELTA_L_85_10INCH_TOP_DP")
	)
	(segment
		(start 92.554552 -141.65199)
		(end 97.64522 -140.754354)
		(width 0.14732)
		(layer "F.Cu")
		(net "DELTA_L_85_10INCH_TOP_DP")
	)
	(segment
		(start 97.646744 -101.091492)
		(end 98.159824 -101.451156)
		(width 0.14732)
		(layer "F.Cu")
		(net "DELTA_L_85_10INCH_TOP_DP")
	)
	(segment
		(start 92.093034 -126.065534)
		(end 92.254578 -126.983236)
		(width 0.14732)
		(layer "F.Cu")
		(net "DELTA_L_85_10INCH_TOP_DP")
	)
	(segment
		(start 92.32519 -129.330704)
		(end 92.085922 -129.671826)
		(width 0.14732)
		(layer "F.Cu")
		(net "DELTA_L_85_10INCH_TOP_DP")
	)
	(segment
		(start 92.049346 -108.044234)
		(end 92.21089 -108.962444)
		(width 0.14732)
		(layer "F.Cu")
		(net "DELTA_L_85_10INCH_TOP_DP")
	)
	(segment
		(start 97.64522 -140.754354)
		(end 98.158808 -141.114018)
		(width 0.14732)
		(layer "F.Cu")
		(net "DELTA_L_85_10INCH_TOP_DP")
	)
	(segment
		(start 98.358706 -102.577138)
		(end 97.998788 -103.090726)
		(width 0.14732)
		(layer "F.Cu")
		(net "DELTA_L_85_10INCH_TOP_DP")
	)
	(segment
		(start 92.261436 -116.164868)
		(end 92.603066 -116.403882)
		(width 0.14732)
		(layer "F.Cu")
		(net "DELTA_L_85_10INCH_TOP_DP")
	)
	(segment
		(start 95.499936 -154.173936)
		(end 95.499936 -154.3685)
		(width 0.14732)
		(layer "F.Cu")
		(net "DELTA_L_85_10INCH_TOP_DP")
	)
	(segment
		(start 97.973896 -124.728986)
		(end 92.332048 -125.72365)
		(width 0.14732)
		(layer "F.Cu")
		(net "DELTA_L_85_10INCH_TOP_DP")
	)
	(segment
		(start 92.254578 -126.983236)
		(end 92.596208 -127.22225)
		(width 0.14732)
		(layer "F.Cu")
		(net "DELTA_L_85_10INCH_TOP_DP")
	)
	(segment
		(start 98.341688 -95.368618)
		(end 97.982024 -95.881698)
		(width 0.14732)
		(layer "F.Cu")
		(net "DELTA_L_85_10INCH_TOP_DP")
	)
	(segment
		(start 97.64522 -126.331726)
		(end 98.1583 -126.69139)
		(width 0.14732)
		(layer "F.Cu")
		(net "DELTA_L_85_10INCH_TOP_DP")
	)
	(segment
		(start 92.332048 -125.72365)
		(end 92.093034 -126.065534)
		(width 0.14732)
		(layer "F.Cu")
		(net "DELTA_L_85_10INCH_TOP_DP")
	)
	(segment
		(start 84.822284 -146.32686)
		(end 89.863676 -145.438114)
		(width 0.14732)
		(layer "F.Cu")
		(net "DELTA_L_85_5INCH_TOP_DN")
	)
	(segment
		(start 90.106246 -123.462288)
		(end 89.944448 -122.544078)
		(width 0.14732)
		(layer "F.Cu")
		(net "DELTA_L_85_5INCH_TOP_DN")
	)
	(segment
		(start 90.1192 -134.2771)
		(end 89.957402 -133.35889)
		(width 0.14732)
		(layer "F.Cu")
		(net "DELTA_L_85_5INCH_TOP_DN")
	)
	(segment
		(start 84.754974 -142.733522)
		(end 89.897204 -141.826488)
		(width 0.14732)
		(layer "F.Cu")
		(net "DELTA_L_85_5INCH_TOP_DN")
	)
	(segment
		(start 85.12556 -137.517378)
		(end 84.611464 -137.157714)
		(width 0.14732)
		(layer "F.Cu")
		(net "DELTA_L_85_5INCH_TOP_DN")
	)
	(segment
		(start 89.894156 -131.010152)
		(end 90.13317 -130.66903)
		(width 0.14732)
		(layer "F.Cu")
		(net "DELTA_L_85_5INCH_TOP_DN")
	)
	(segment
		(start 90.136472 -141.485366)
		(end 89.974166 -140.567156)
		(width 0.14732)
		(layer "F.Cu")
		(net "DELTA_L_85_5INCH_TOP_DN")
	)
	(segment
		(start 85.030056 -126.717044)
		(end 84.51596 -126.35738)
		(width 0.14732)
		(layer "F.Cu")
		(net "DELTA_L_85_5INCH_TOP_DN")
	)
	(segment
		(start 89.603326 -122.305064)
		(end 85.01634 -123.1138)
		(width 0.14732)
		(layer "F.Cu")
		(net "DELTA_L_85_5INCH_TOP_DN")
	)
	(segment
		(start 89.881202 -127.406654)
		(end 90.119962 -127.065532)
		(width 0.14732)
		(layer "F.Cu")
		(net "DELTA_L_85_5INCH_TOP_DN")
	)
	(segment
		(start 87.507064 -154.173936)
		(end 87.63 -154.051)
		(width 0.14732)
		(layer "F.Cu")
		(net "DELTA_L_85_5INCH_TOP_DN")
	)
	(segment
		(start 84.812886 -139.117324)
		(end 89.898728 -138.220704)
		(width 0.14732)
		(layer "F.Cu")
		(net "DELTA_L_85_5INCH_TOP_DN")
	)
	(segment
		(start 84.69122 -128.321562)
		(end 89.881202 -127.406654)
		(width 0.14732)
		(layer "F.Cu")
		(net "DELTA_L_85_5INCH_TOP_DN")
	)
	(segment
		(start 89.633298 -140.328396)
		(end 85.1662 -141.115796)
		(width 0.14732)
		(layer "F.Cu")
		(net "DELTA_L_85_5INCH_TOP_DN")
	)
	(segment
		(start 89.634822 -136.722104)
		(end 85.12556 -137.517378)
		(width 0.14732)
		(layer "F.Cu")
		(net "DELTA_L_85_5INCH_TOP_DN")
	)
	(segment
		(start 84.453476 -139.630912)
		(end 84.812886 -139.117324)
		(width 0.14732)
		(layer "F.Cu")
		(net "DELTA_L_85_5INCH_TOP_DN")
	)
	(segment
		(start 84.660994 -147.965922)
		(end 84.462874 -146.840448)
		(width 0.14732)
		(layer "F.Cu")
		(net "DELTA_L_85_5INCH_TOP_DN")
	)
	(segment
		(start 89.940638 -144.178782)
		(end 89.59977 -143.939768)
		(width 0.14732)
		(layer "F.Cu")
		(net "DELTA_L_85_5INCH_TOP_DN")
	)
	(segment
		(start 84.51596 -126.35738)
		(end 84.294726 -125.101096)
		(width 0.14732)
		(layer "F.Cu")
		(net "DELTA_L_85_5INCH_TOP_DN")
	)
	(segment
		(start 84.511134 -129.856992)
		(end 84.511388 -129.856992)
		(width 0.14732)
		(layer "F.Cu")
		(net "DELTA_L_85_5INCH_TOP_DN")
	)
	(segment
		(start 84.529676 -129.960878)
		(end 84.511134 -129.856992)
		(width 0.14732)
		(layer "F.Cu")
		(net "DELTA_L_85_5INCH_TOP_DN")
	)
	(segment
		(start 84.511388 -129.856992)
		(end 84.331556 -128.835912)
		(width 0.14732)
		(layer "F.Cu")
		(net "DELTA_L_85_5INCH_TOP_DN")
	)
	(segment
		(start 90.137742 -137.879582)
		(end 89.975436 -136.961118)
		(width 0.14732)
		(layer "F.Cu")
		(net "DELTA_L_85_5INCH_TOP_DN")
	)
	(segment
		(start 84.504784 -133.463538)
		(end 84.324444 -132.44195)
		(width 0.14732)
		(layer "F.Cu")
		(net "DELTA_L_85_5INCH_TOP_DN")
	)
	(segment
		(start 85.107018 -144.73174)
		(end 84.593938 -144.372584)
		(width 0.14732)
		(layer "F.Cu")
		(net "DELTA_L_85_5INCH_TOP_DN")
	)
	(segment
		(start 84.652104 -140.756132)
		(end 84.453476 -139.630912)
		(width 0.14732)
		(layer "F.Cu")
		(net "DELTA_L_85_5INCH_TOP_DN")
	)
	(segment
		(start 89.637108 -147.538948)
		(end 85.174582 -148.32584)
		(width 0.14732)
		(layer "F.Cu")
		(net "DELTA_L_85_5INCH_TOP_DN")
	)
	(segment
		(start 85.174582 -148.32584)
		(end 84.660994 -147.965922)
		(width 0.14732)
		(layer "F.Cu")
		(net "DELTA_L_85_5INCH_TOP_DN")
	)
	(segment
		(start 84.502244 -122.754136)
		(end 84.296504 -121.585482)
		(width 0.14732)
		(layer "F.Cu")
		(net "DELTA_L_85_5INCH_TOP_DN")
	)
	(segment
		(start 84.395564 -143.24711)
		(end 84.754974 -142.733522)
		(width 0.14732)
		(layer "F.Cu")
		(net "DELTA_L_85_5INCH_TOP_DN")
	)
	(segment
		(start 87.507064 -110.621064)
		(end 87.507064 -110.4265)
		(width 0.14732)
		(layer "F.Cu")
		(net "DELTA_L_85_5INCH_TOP_DN")
	)
	(segment
		(start 84.677504 -124.718318)
		(end 89.867486 -123.80341)
		(width 0.14732)
		(layer "F.Cu")
		(net "DELTA_L_85_5INCH_TOP_DN")
	)
	(segment
		(start 89.863676 -145.438114)
		(end 90.10269 -145.096738)
		(width 0.14732)
		(layer "F.Cu")
		(net "DELTA_L_85_5INCH_TOP_DN")
	)
	(segment
		(start 85.01634 -123.1138)
		(end 84.502244 -122.754136)
		(width 0.14732)
		(layer "F.Cu")
		(net "DELTA_L_85_5INCH_TOP_DN")
	)
	(segment
		(start 89.944448 -122.544078)
		(end 89.603326 -122.305064)
		(width 0.14732)
		(layer "F.Cu")
		(net "DELTA_L_85_5INCH_TOP_DN")
	)
	(segment
		(start 90.13317 -130.66903)
		(end 89.970864 -129.750566)
		(width 0.14732)
		(layer "F.Cu")
		(net "DELTA_L_85_5INCH_TOP_DN")
	)
	(segment
		(start 88.00719 -149.371304)
		(end 89.901268 -149.037294)
		(width 0.14732)
		(layer "F.Cu")
		(net "DELTA_L_85_5INCH_TOP_DN")
	)
	(segment
		(start 84.593938 -144.372584)
		(end 84.395564 -143.24711)
		(width 0.14732)
		(layer "F.Cu")
		(net "DELTA_L_85_5INCH_TOP_DN")
	)
	(segment
		(start 90.140282 -148.696172)
		(end 89.978484 -147.777962)
		(width 0.14732)
		(layer "F.Cu")
		(net "DELTA_L_85_5INCH_TOP_DN")
	)
	(segment
		(start 84.50453 -133.463538)
		(end 84.504784 -133.463538)
		(width 0.14732)
		(layer "F.Cu")
		(net "DELTA_L_85_5INCH_TOP_DN")
	)
	(segment
		(start 89.897204 -141.826488)
		(end 90.136472 -141.485366)
		(width 0.14732)
		(layer "F.Cu")
		(net "DELTA_L_85_5INCH_TOP_DN")
	)
	(segment
		(start 85.043772 -130.320542)
		(end 84.529676 -129.960878)
		(width 0.14732)
		(layer "F.Cu")
		(net "DELTA_L_85_5INCH_TOP_DN")
	)
	(segment
		(start 89.901268 -149.037294)
		(end 90.140282 -148.696172)
		(width 0.14732)
		(layer "F.Cu")
		(net "DELTA_L_85_5INCH_TOP_DN")
	)
	(segment
		(start 89.616534 -133.119622)
		(end 85.036914 -133.92785)
		(width 0.14732)
		(layer "F.Cu")
		(net "DELTA_L_85_5INCH_TOP_DN")
	)
	(segment
		(start 89.898728 -138.220704)
		(end 90.137742 -137.879582)
		(width 0.14732)
		(layer "F.Cu")
		(net "DELTA_L_85_5INCH_TOP_DN")
	)
	(segment
		(start 87.63 -154.051)
		(end 87.63 -149.74824)
		(width 0.14732)
		(layer "F.Cu")
		(net "DELTA_L_85_5INCH_TOP_DN")
	)
	(segment
		(start 90.119962 -127.065532)
		(end 89.958164 -126.147322)
		(width 0.14732)
		(layer "F.Cu")
		(net "DELTA_L_85_5INCH_TOP_DN")
	)
	(segment
		(start 84.294726 -125.101096)
		(end 84.677504 -124.718318)
		(width 0.14732)
		(layer "F.Cu")
		(net "DELTA_L_85_5INCH_TOP_DN")
	)
	(segment
		(start 85.1662 -141.115796)
		(end 84.652104 -140.756132)
		(width 0.14732)
		(layer "F.Cu")
		(net "DELTA_L_85_5INCH_TOP_DN")
	)
	(segment
		(start 89.867486 -123.80341)
		(end 90.106246 -123.462288)
		(width 0.14732)
		(layer "F.Cu")
		(net "DELTA_L_85_5INCH_TOP_DN")
	)
	(segment
		(start 85.036914 -133.92785)
		(end 84.523072 -133.56717)
		(width 0.14732)
		(layer "F.Cu")
		(net "DELTA_L_85_5INCH_TOP_DN")
	)
	(segment
		(start 89.59977 -143.939768)
		(end 85.107018 -144.73174)
		(width 0.14732)
		(layer "F.Cu")
		(net "DELTA_L_85_5INCH_TOP_DN")
	)
	(segment
		(start 84.642706 -121.11863)
		(end 87.479632 -120.618758)
		(width 0.14732)
		(layer "F.Cu")
		(net "DELTA_L_85_5INCH_TOP_DN")
	)
	(segment
		(start 89.957402 -133.35889)
		(end 89.616534 -133.119622)
		(width 0.14732)
		(layer "F.Cu")
		(net "DELTA_L_85_5INCH_TOP_DN")
	)
	(segment
		(start 87.63 -149.74824)
		(end 88.00719 -149.371304)
		(width 0.14732)
		(layer "F.Cu")
		(net "DELTA_L_85_5INCH_TOP_DN")
	)
	(segment
		(start 89.978484 -147.777962)
		(end 89.637108 -147.538948)
		(width 0.14732)
		(layer "F.Cu")
		(net "DELTA_L_85_5INCH_TOP_DN")
	)
	(segment
		(start 89.970864 -129.750566)
		(end 89.63025 -129.511552)
		(width 0.14732)
		(layer "F.Cu")
		(net "DELTA_L_85_5INCH_TOP_DN")
	)
	(segment
		(start 89.63025 -129.511552)
		(end 85.043772 -130.320542)
		(width 0.14732)
		(layer "F.Cu")
		(net "DELTA_L_85_5INCH_TOP_DN")
	)
	(segment
		(start 84.472018 -121.348754)
		(end 84.642706 -121.11863)
		(width 0.14732)
		(layer "F.Cu")
		(net "DELTA_L_85_5INCH_TOP_DN")
	)
	(segment
		(start 87.63 -110.744)
		(end 87.507064 -110.621064)
		(width 0.14732)
		(layer "F.Cu")
		(net "DELTA_L_85_5INCH_TOP_DN")
	)
	(segment
		(start 89.88044 -134.618222)
		(end 90.1192 -134.2771)
		(width 0.14732)
		(layer "F.Cu")
		(net "DELTA_L_85_5INCH_TOP_DN")
	)
	(segment
		(start 84.331556 -128.835912)
		(end 84.69122 -128.321562)
		(width 0.14732)
		(layer "F.Cu")
		(net "DELTA_L_85_5INCH_TOP_DN")
	)
	(segment
		(start 84.324444 -132.44195)
		(end 84.684362 -131.928362)
		(width 0.14732)
		(layer "F.Cu")
		(net "DELTA_L_85_5INCH_TOP_DN")
	)
	(segment
		(start 84.523072 -133.56717)
		(end 84.50453 -133.463538)
		(width 0.14732)
		(layer "F.Cu")
		(net "DELTA_L_85_5INCH_TOP_DN")
	)
	(segment
		(start 89.617042 -125.908308)
		(end 85.030056 -126.717044)
		(width 0.14732)
		(layer "F.Cu")
		(net "DELTA_L_85_5INCH_TOP_DN")
	)
	(segment
		(start 84.462874 -146.840448)
		(end 84.822284 -146.32686)
		(width 0.14732)
		(layer "F.Cu")
		(net "DELTA_L_85_5INCH_TOP_DN")
	)
	(segment
		(start 90.10269 -145.096738)
		(end 89.940638 -144.178782)
		(width 0.14732)
		(layer "F.Cu")
		(net "DELTA_L_85_5INCH_TOP_DN")
	)
	(segment
		(start 87.479632 -120.618758)
		(end 87.63 -120.439434)
		(width 0.14732)
		(layer "F.Cu")
		(net "DELTA_L_85_5INCH_TOP_DN")
	)
	(segment
		(start 87.63 -120.439434)
		(end 87.63 -110.744)
		(width 0.14732)
		(layer "F.Cu")
		(net "DELTA_L_85_5INCH_TOP_DN")
	)
	(segment
		(start 84.773008 -135.518398)
		(end 89.88044 -134.618222)
		(width 0.14732)
		(layer "F.Cu")
		(net "DELTA_L_85_5INCH_TOP_DN")
	)
	(segment
		(start 84.684362 -131.928362)
		(end 89.894156 -131.010152)
		(width 0.14732)
		(layer "F.Cu")
		(net "DELTA_L_85_5INCH_TOP_DN")
	)
	(segment
		(start 84.471764 -121.349008)
		(end 84.472018 -121.348754)
		(width 0.14732)
		(layer "F.Cu")
		(net "DELTA_L_85_5INCH_TOP_DN")
	)
	(segment
		(start 84.611464 -137.157714)
		(end 84.413344 -136.032748)
		(width 0.14732)
		(layer "F.Cu")
		(net "DELTA_L_85_5INCH_TOP_DN")
	)
	(segment
		(start 89.975436 -136.961118)
		(end 89.634822 -136.722104)
		(width 0.14732)
		(layer "F.Cu")
		(net "DELTA_L_85_5INCH_TOP_DN")
	)
	(segment
		(start 84.296504 -121.585482)
		(end 84.471764 -121.349008)
		(width 0.14732)
		(layer "F.Cu")
		(net "DELTA_L_85_5INCH_TOP_DN")
	)
	(segment
		(start 89.958164 -126.147322)
		(end 89.617042 -125.908308)
		(width 0.14732)
		(layer "F.Cu")
		(net "DELTA_L_85_5INCH_TOP_DN")
	)
	(segment
		(start 84.413344 -136.032748)
		(end 84.773008 -135.518398)
		(width 0.14732)
		(layer "F.Cu")
		(net "DELTA_L_85_5INCH_TOP_DN")
	)
	(segment
		(start 87.507064 -154.3685)
		(end 87.507064 -154.173936)
		(width 0.14732)
		(layer "F.Cu")
		(net "DELTA_L_85_5INCH_TOP_DN")
	)
	(segment
		(start 89.974166 -140.567156)
		(end 89.633298 -140.328396)
		(width 0.14732)
		(layer "F.Cu")
		(net "DELTA_L_85_5INCH_TOP_DN")
	)
	(segment
		(start 87.884 -110.744)
		(end 88.006936 -110.621064)
		(width 0.14732)
		(layer "F.Cu")
		(net "DELTA_L_85_5INCH_TOP_DP")
	)
	(segment
		(start 90.371168 -145.156174)
		(end 90.172794 -144.030954)
		(width 0.14732)
		(layer "F.Cu")
		(net "DELTA_L_85_5INCH_TOP_DP")
	)
	(segment
		(start 90.045032 -142.058644)
		(end 90.405204 -141.545056)
		(width 0.14732)
		(layer "F.Cu")
		(net "DELTA_L_85_5INCH_TOP_DP")
	)
	(segment
		(start 84.843366 -137.009886)
		(end 84.681822 -136.092184)
		(width 0.14732)
		(layer "F.Cu")
		(net "DELTA_L_85_5INCH_TOP_DP")
	)
	(segment
		(start 90.041984 -131.242308)
		(end 90.401902 -130.72872)
		(width 0.14732)
		(layer "F.Cu")
		(net "DELTA_L_85_5INCH_TOP_DP")
	)
	(segment
		(start 84.734146 -122.606308)
		(end 84.565744 -121.648982)
		(width 0.14732)
		(layer "F.Cu")
		(net "DELTA_L_85_5INCH_TOP_DP")
	)
	(segment
		(start 90.405204 -141.545056)
		(end 90.206322 -140.419328)
		(width 0.14732)
		(layer "F.Cu")
		(net "DELTA_L_85_5INCH_TOP_DP")
	)
	(segment
		(start 85.089492 -126.448566)
		(end 84.747862 -126.209552)
		(width 0.14732)
		(layer "F.Cu")
		(net "DELTA_L_85_5INCH_TOP_DP")
	)
	(segment
		(start 85.096604 -133.659372)
		(end 84.754974 -133.419596)
		(width 0.14732)
		(layer "F.Cu")
		(net "DELTA_L_85_5INCH_TOP_DP")
	)
	(segment
		(start 88.006936 -110.621064)
		(end 88.006936 -110.4265)
		(width 0.14732)
		(layer "F.Cu")
		(net "DELTA_L_85_5INCH_TOP_DP")
	)
	(segment
		(start 84.83219 -132.160518)
		(end 90.041984 -131.242308)
		(width 0.14732)
		(layer "F.Cu")
		(net "DELTA_L_85_5INCH_TOP_DP")
	)
	(segment
		(start 90.19032 -125.999494)
		(end 89.676732 -125.639576)
		(width 0.14732)
		(layer "F.Cu")
		(net "DELTA_L_85_5INCH_TOP_DP")
	)
	(segment
		(start 87.884 -154.051)
		(end 87.884 -149.85365)
		(width 0.14732)
		(layer "F.Cu")
		(net "DELTA_L_85_5INCH_TOP_DP")
	)
	(segment
		(start 84.884006 -140.608304)
		(end 84.721954 -139.690348)
		(width 0.14732)
		(layer "F.Cu")
		(net "DELTA_L_85_5INCH_TOP_DP")
	)
	(segment
		(start 85.234272 -148.057108)
		(end 84.89315 -147.818094)
		(width 0.14732)
		(layer "F.Cu")
		(net "DELTA_L_85_5INCH_TOP_DP")
	)
	(segment
		(start 90.176604 -122.39625)
		(end 89.663016 -122.036332)
		(width 0.14732)
		(layer "F.Cu")
		(net "DELTA_L_85_5INCH_TOP_DP")
	)
	(segment
		(start 90.387678 -134.336536)
		(end 90.189558 -133.211062)
		(width 0.14732)
		(layer "F.Cu")
		(net "DELTA_L_85_5INCH_TOP_DP")
	)
	(segment
		(start 84.721954 -139.690348)
		(end 84.960714 -139.349226)
		(width 0.14732)
		(layer "F.Cu")
		(net "DELTA_L_85_5INCH_TOP_DP")
	)
	(segment
		(start 90.21064 -147.630134)
		(end 89.696544 -147.27047)
		(width 0.14732)
		(layer "F.Cu")
		(net "DELTA_L_85_5INCH_TOP_DP")
	)
	(segment
		(start 89.911428 -124.0536)
		(end 89.911428 -124.053854)
		(width 0.14732)
		(layer "F.Cu")
		(net "DELTA_L_85_5INCH_TOP_DP")
	)
	(segment
		(start 90.172794 -144.030954)
		(end 89.65946 -143.67129)
		(width 0.14732)
		(layer "F.Cu")
		(net "DELTA_L_85_5INCH_TOP_DP")
	)
	(segment
		(start 90.20302 -129.602738)
		(end 89.68994 -129.243074)
		(width 0.14732)
		(layer "F.Cu")
		(net "DELTA_L_85_5INCH_TOP_DP")
	)
	(segment
		(start 88.006936 -154.3685)
		(end 88.006936 -154.173936)
		(width 0.14732)
		(layer "F.Cu")
		(net "DELTA_L_85_5INCH_TOP_DP")
	)
	(segment
		(start 84.902802 -142.965424)
		(end 90.045032 -142.058644)
		(width 0.14732)
		(layer "F.Cu")
		(net "DELTA_L_85_5INCH_TOP_DP")
	)
	(segment
		(start 84.681822 -136.092184)
		(end 84.920836 -135.7503)
		(width 0.14732)
		(layer "F.Cu")
		(net "DELTA_L_85_5INCH_TOP_DP")
	)
	(segment
		(start 90.406474 -137.939272)
		(end 90.207592 -136.81329)
		(width 0.14732)
		(layer "F.Cu")
		(net "DELTA_L_85_5INCH_TOP_DP")
	)
	(segment
		(start 89.692988 -140.059664)
		(end 85.225636 -140.847318)
		(width 0.14732)
		(layer "F.Cu")
		(net "DELTA_L_85_5INCH_TOP_DP")
	)
	(segment
		(start 85.184996 -137.2489)
		(end 84.843366 -137.009886)
		(width 0.14732)
		(layer "F.Cu")
		(net "DELTA_L_85_5INCH_TOP_DP")
	)
	(segment
		(start 87.884 -149.85365)
		(end 88.130126 -149.607778)
		(width 0.14732)
		(layer "F.Cu")
		(net "DELTA_L_85_5INCH_TOP_DP")
	)
	(segment
		(start 84.565744 -121.648982)
		(end 84.78647 -121.351294)
		(width 0.14732)
		(layer "F.Cu")
		(net "DELTA_L_85_5INCH_TOP_DP")
	)
	(segment
		(start 90.207592 -136.81329)
		(end 89.694512 -136.453626)
		(width 0.14732)
		(layer "F.Cu")
		(net "DELTA_L_85_5INCH_TOP_DP")
	)
	(segment
		(start 90.374724 -123.521724)
		(end 90.176604 -122.39625)
		(width 0.14732)
		(layer "F.Cu")
		(net "DELTA_L_85_5INCH_TOP_DP")
	)
	(segment
		(start 90.028268 -134.850124)
		(end 90.387678 -134.336536)
		(width 0.14732)
		(layer "F.Cu")
		(net "DELTA_L_85_5INCH_TOP_DP")
	)
	(segment
		(start 84.747862 -126.209552)
		(end 84.56803 -125.187202)
		(width 0.14732)
		(layer "F.Cu")
		(net "DELTA_L_85_5INCH_TOP_DP")
	)
	(segment
		(start 90.02903 -127.638556)
		(end 90.38844 -127.124968)
		(width 0.14732)
		(layer "F.Cu")
		(net "DELTA_L_85_5INCH_TOP_DP")
	)
	(segment
		(start 89.676224 -132.851144)
		(end 85.096604 -133.659372)
		(width 0.14732)
		(layer "F.Cu")
		(net "DELTA_L_85_5INCH_TOP_DP")
	)
	(segment
		(start 90.049096 -149.26945)
		(end 90.409014 -148.755862)
		(width 0.14732)
		(layer "F.Cu")
		(net "DELTA_L_85_5INCH_TOP_DP")
	)
	(segment
		(start 84.731352 -146.899884)
		(end 84.970112 -146.558762)
		(width 0.14732)
		(layer "F.Cu")
		(net "DELTA_L_85_5INCH_TOP_DP")
	)
	(segment
		(start 90.401902 -130.72872)
		(end 90.20302 -129.602738)
		(width 0.14732)
		(layer "F.Cu")
		(net "DELTA_L_85_5INCH_TOP_DP")
	)
	(segment
		(start 87.61476 -120.852946)
		(end 87.884 -120.532144)
		(width 0.14732)
		(layer "F.Cu")
		(net "DELTA_L_85_5INCH_TOP_DP")
	)
	(segment
		(start 85.166454 -144.463262)
		(end 84.82584 -144.224756)
		(width 0.14732)
		(layer "F.Cu")
		(net "DELTA_L_85_5INCH_TOP_DP")
	)
	(segment
		(start 85.103208 -130.052064)
		(end 84.761578 -129.81305)
		(width 0.14732)
		(layer "F.Cu")
		(net "DELTA_L_85_5INCH_TOP_DP")
	)
	(segment
		(start 90.189558 -133.211062)
		(end 89.676224 -132.851144)
		(width 0.14732)
		(layer "F.Cu")
		(net "DELTA_L_85_5INCH_TOP_DP")
	)
	(segment
		(start 90.206322 -140.419328)
		(end 89.692988 -140.059664)
		(width 0.14732)
		(layer "F.Cu")
		(net "DELTA_L_85_5INCH_TOP_DP")
	)
	(segment
		(start 90.046556 -138.45286)
		(end 90.406474 -137.939272)
		(width 0.14732)
		(layer "F.Cu")
		(net "DELTA_L_85_5INCH_TOP_DP")
	)
	(segment
		(start 84.600034 -128.895348)
		(end 84.839048 -128.553464)
		(width 0.14732)
		(layer "F.Cu")
		(net "DELTA_L_85_5INCH_TOP_DP")
	)
	(segment
		(start 84.56803 -125.187202)
		(end 84.800694 -124.954792)
		(width 0.14732)
		(layer "F.Cu")
		(net "DELTA_L_85_5INCH_TOP_DP")
	)
	(segment
		(start 89.68994 -129.243074)
		(end 85.103208 -130.052064)
		(width 0.14732)
		(layer "F.Cu")
		(net "DELTA_L_85_5INCH_TOP_DP")
	)
	(segment
		(start 84.960714 -139.349226)
		(end 90.046556 -138.45286)
		(width 0.14732)
		(layer "F.Cu")
		(net "DELTA_L_85_5INCH_TOP_DP")
	)
	(segment
		(start 84.754974 -133.419596)
		(end 84.592922 -132.50164)
		(width 0.14732)
		(layer "F.Cu")
		(net "DELTA_L_85_5INCH_TOP_DP")
	)
	(segment
		(start 90.015314 -124.035312)
		(end 90.374724 -123.521724)
		(width 0.14732)
		(layer "F.Cu")
		(net "DELTA_L_85_5INCH_TOP_DP")
	)
	(segment
		(start 87.884 -120.532144)
		(end 87.884 -110.744)
		(width 0.14732)
		(layer "F.Cu")
		(net "DELTA_L_85_5INCH_TOP_DP")
	)
	(segment
		(start 90.38844 -127.124968)
		(end 90.19032 -125.999494)
		(width 0.14732)
		(layer "F.Cu")
		(net "DELTA_L_85_5INCH_TOP_DP")
	)
	(segment
		(start 84.592922 -132.50164)
		(end 84.83219 -132.160518)
		(width 0.14732)
		(layer "F.Cu")
		(net "DELTA_L_85_5INCH_TOP_DP")
	)
	(segment
		(start 84.839048 -128.553464)
		(end 90.02903 -127.638556)
		(width 0.14732)
		(layer "F.Cu")
		(net "DELTA_L_85_5INCH_TOP_DP")
	)
	(segment
		(start 89.676732 -125.639576)
		(end 85.089492 -126.448566)
		(width 0.14732)
		(layer "F.Cu")
		(net "DELTA_L_85_5INCH_TOP_DP")
	)
	(segment
		(start 89.694512 -136.453626)
		(end 85.184996 -137.2489)
		(width 0.14732)
		(layer "F.Cu")
		(net "DELTA_L_85_5INCH_TOP_DP")
	)
	(segment
		(start 88.130126 -149.607778)
		(end 90.049096 -149.26945)
		(width 0.14732)
		(layer "F.Cu")
		(net "DELTA_L_85_5INCH_TOP_DP")
	)
	(segment
		(start 84.800694 -124.954792)
		(end 89.911428 -124.0536)
		(width 0.14732)
		(layer "F.Cu")
		(net "DELTA_L_85_5INCH_TOP_DP")
	)
	(segment
		(start 89.65946 -143.67129)
		(end 85.166454 -144.463262)
		(width 0.14732)
		(layer "F.Cu")
		(net "DELTA_L_85_5INCH_TOP_DP")
	)
	(segment
		(start 84.82584 -144.224756)
		(end 84.664042 -143.306546)
		(width 0.14732)
		(layer "F.Cu")
		(net "DELTA_L_85_5INCH_TOP_DP")
	)
	(segment
		(start 84.89315 -147.818094)
		(end 84.731352 -146.899884)
		(width 0.14732)
		(layer "F.Cu")
		(net "DELTA_L_85_5INCH_TOP_DP")
	)
	(segment
		(start 89.911428 -124.053854)
		(end 90.015314 -124.035312)
		(width 0.14732)
		(layer "F.Cu")
		(net "DELTA_L_85_5INCH_TOP_DP")
	)
	(segment
		(start 85.075776 -122.845322)
		(end 84.734146 -122.606308)
		(width 0.14732)
		(layer "F.Cu")
		(net "DELTA_L_85_5INCH_TOP_DP")
	)
	(segment
		(start 84.920836 -135.7503)
		(end 90.028268 -134.850124)
		(width 0.14732)
		(layer "F.Cu")
		(net "DELTA_L_85_5INCH_TOP_DP")
	)
	(segment
		(start 89.663016 -122.036332)
		(end 85.075776 -122.845322)
		(width 0.14732)
		(layer "F.Cu")
		(net "DELTA_L_85_5INCH_TOP_DP")
	)
	(segment
		(start 89.696544 -147.27047)
		(end 85.234272 -148.057108)
		(width 0.14732)
		(layer "F.Cu")
		(net "DELTA_L_85_5INCH_TOP_DP")
	)
	(segment
		(start 84.761578 -129.81305)
		(end 84.600034 -128.895348)
		(width 0.14732)
		(layer "F.Cu")
		(net "DELTA_L_85_5INCH_TOP_DP")
	)
	(segment
		(start 90.011504 -145.67027)
		(end 90.371168 -145.156174)
		(width 0.14732)
		(layer "F.Cu")
		(net "DELTA_L_85_5INCH_TOP_DP")
	)
	(segment
		(start 85.225636 -140.847318)
		(end 84.884006 -140.608304)
		(width 0.14732)
		(layer "F.Cu")
		(net "DELTA_L_85_5INCH_TOP_DP")
	)
	(segment
		(start 88.006936 -154.173936)
		(end 87.884 -154.051)
		(width 0.14732)
		(layer "F.Cu")
		(net "DELTA_L_85_5INCH_TOP_DP")
	)
	(segment
		(start 90.409014 -148.755862)
		(end 90.21064 -147.630134)
		(width 0.14732)
		(layer "F.Cu")
		(net "DELTA_L_85_5INCH_TOP_DP")
	)
	(segment
		(start 84.78647 -121.351294)
		(end 87.61476 -120.852946)
		(width 0.14732)
		(layer "F.Cu")
		(net "DELTA_L_85_5INCH_TOP_DP")
	)
	(segment
		(start 84.664042 -143.306546)
		(end 84.902802 -142.965424)
		(width 0.14732)
		(layer "F.Cu")
		(net "DELTA_L_85_5INCH_TOP_DP")
	)
	(segment
		(start 84.970112 -146.558762)
		(end 90.011504 -145.67027)
		(width 0.14732)
		(layer "F.Cu")
		(net "DELTA_L_85_5INCH_TOP_DP")
	)
	(via
		(at 94.27718 -82.446114)
		(size 0.508)
		(drill 0.254)
		(layers "F.Cu" "B.Cu")
		(net "GND1")
	)
	(via
		(at 94.975426 -82.446114)
		(size 0.508)
		(drill 0.254)
		(layers "F.Cu" "B.Cu")
		(net "GND1")
	)
	(via
		(at 94.280736 -83.283806)
		(size 0.508)
		(drill 0.254)
		(layers "F.Cu" "B.Cu")
		(net "GND1")
	)
	(via
		(at 93.85554 -154.381708)
		(size 0.508)
		(drill 0.254)
		(layers "F.Cu" "B.Cu")
		(net "GND1")
	)
	(via
		(at 87.392764 -155.97632)
		(size 0.508)
		(drill 0.254)
		(layers "F.Cu" "B.Cu")
		(net "GND1")
	)
	(via
		(at 86.787736 -109.652562)
		(size 0.508)
		(drill 0.254)
		(layers "F.Cu" "B.Cu")
		(net "GND1")
	)
	(via
		(at 96.951546 -82.453734)
		(size 0.508)
		(drill 0.254)
		(layers "F.Cu" "B.Cu")
		(net "GND1")
	)
	(via
		(at 93.548454 -155.97251)
		(size 0.508)
		(drill 0.254)
		(layers "F.Cu" "B.Cu")
		(net "GND1")
	)
	(via
		(at 96.316292 -83.279996)
		(size 0.508)
		(drill 0.254)
		(layers "F.Cu" "B.Cu")
		(net "GND1")
	)
	(via
		(at 96.529906 -154.381708)
		(size 0.508)
		(drill 0.254)
		(layers "F.Cu" "B.Cu")
		(net "GND1")
	)
	(via
		(at 93.641926 -83.279996)
		(size 0.508)
		(drill 0.254)
		(layers "F.Cu" "B.Cu")
		(net "GND1")
	)
	(via
		(at 94.183708 -155.146248)
		(size 0.508)
		(drill 0.254)
		(layers "F.Cu" "B.Cu")
		(net "GND1")
	)
	(via
		(at 86.055454 -155.97251)
		(size 0.508)
		(drill 0.254)
		(layers "F.Cu" "B.Cu")
		(net "GND1")
	)
	(via
		(at 96.219264 -155.142438)
		(size 0.508)
		(drill 0.254)
		(layers "F.Cu" "B.Cu")
		(net "GND1")
	)
	(via
		(at 89.462102 -109.652562)
		(size 0.508)
		(drill 0.254)
		(layers "F.Cu" "B.Cu")
		(net "GND1")
	)
	(via
		(at 94.187264 -155.97632)
		(size 0.508)
		(drill 0.254)
		(layers "F.Cu" "B.Cu")
		(net "GND1")
	)
	(via
		(at 88.121236 -108.81868)
		(size 0.508)
		(drill 0.254)
		(layers "F.Cu" "B.Cu")
		(net "GND1")
	)
	(via
		(at 96.955102 -83.283806)
		(size 0.508)
		(drill 0.254)
		(layers "F.Cu" "B.Cu")
		(net "GND1")
	)
	(via
		(at 89.15146 -110.413292)
		(size 0.508)
		(drill 0.254)
		(layers "F.Cu" "B.Cu")
		(net "GND1")
	)
	(via
		(at 88.031574 -155.98013)
		(size 0.508)
		(drill 0.254)
		(layers "F.Cu" "B.Cu")
		(net "GND1")
	)
	(via
		(at 96.858074 -155.146248)
		(size 0.508)
		(drill 0.254)
		(layers "F.Cu" "B.Cu")
		(net "GND1")
	)
	(via
		(at 86.14537 -108.81868)
		(size 0.508)
		(drill 0.254)
		(layers "F.Cu" "B.Cu")
		(net "GND1")
	)
	(via
		(at 86.690708 -155.146248)
		(size 0.508)
		(drill 0.254)
		(layers "F.Cu" "B.Cu")
		(net "GND1")
	)
	(via
		(at 88.823292 -109.648752)
		(size 0.508)
		(drill 0.254)
		(layers "F.Cu" "B.Cu")
		(net "GND1")
	)
	(via
		(at 89.36863 -155.97632)
		(size 0.508)
		(drill 0.254)
		(layers "F.Cu" "B.Cu")
		(net "GND1")
	)
	(via
		(at 87.482426 -108.81487)
		(size 0.508)
		(drill 0.254)
		(layers "F.Cu" "B.Cu")
		(net "GND1")
	)
	(via
		(at 86.694264 -155.97632)
		(size 0.508)
		(drill 0.254)
		(layers "F.Cu" "B.Cu")
		(net "GND1")
	)
	(via
		(at 88.72982 -155.98013)
		(size 0.508)
		(drill 0.254)
		(layers "F.Cu" "B.Cu")
		(net "GND1")
	)
	(via
		(at 95.614236 -82.449924)
		(size 0.508)
		(drill 0.254)
		(layers "F.Cu" "B.Cu")
		(net "GND1")
	)
	(via
		(at 96.64446 -84.044536)
		(size 0.508)
		(drill 0.254)
		(layers "F.Cu" "B.Cu")
		(net "GND1")
	)
	(via
		(at 89.458546 -108.82249)
		(size 0.508)
		(drill 0.254)
		(layers "F.Cu" "B.Cu")
		(net "GND1")
	)
	(via
		(at 94.885764 -155.97632)
		(size 0.508)
		(drill 0.254)
		(layers "F.Cu" "B.Cu")
		(net "GND1")
	)
	(via
		(at 86.36254 -154.381708)
		(size 0.508)
		(drill 0.254)
		(layers "F.Cu" "B.Cu")
		(net "GND1")
	)
	(via
		(at 86.051898 -155.142438)
		(size 0.508)
		(drill 0.254)
		(layers "F.Cu" "B.Cu")
		(net "GND1")
	)
	(via
		(at 95.524574 -155.98013)
		(size 0.508)
		(drill 0.254)
		(layers "F.Cu" "B.Cu")
		(net "GND1")
	)
	(via
		(at 86.148926 -109.648752)
		(size 0.508)
		(drill 0.254)
		(layers "F.Cu" "B.Cu")
		(net "GND1")
	)
	(via
		(at 86.477094 -110.413292)
		(size 0.508)
		(drill 0.254)
		(layers "F.Cu" "B.Cu")
		(net "GND1")
	)
	(via
		(at 96.312736 -82.449924)
		(size 0.508)
		(drill 0.254)
		(layers "F.Cu" "B.Cu")
		(net "GND1")
	)
	(via
		(at 86.78418 -108.81487)
		(size 0.508)
		(drill 0.254)
		(layers "F.Cu" "B.Cu")
		(net "GND1")
	)
	(via
		(at 93.63837 -82.449924)
		(size 0.508)
		(drill 0.254)
		(layers "F.Cu" "B.Cu")
		(net "GND1")
	)
	(via
		(at 93.544898 -155.142438)
		(size 0.508)
		(drill 0.254)
		(layers "F.Cu" "B.Cu")
		(net "GND1")
	)
	(via
		(at 96.22282 -155.98013)
		(size 0.508)
		(drill 0.254)
		(layers "F.Cu" "B.Cu")
		(net "GND1")
	)
	(via
		(at 88.726264 -155.142438)
		(size 0.508)
		(drill 0.254)
		(layers "F.Cu" "B.Cu")
		(net "GND1")
	)
	(via
		(at 93.970094 -84.044536)
		(size 0.508)
		(drill 0.254)
		(layers "F.Cu" "B.Cu")
		(net "GND1")
	)
	(via
		(at 96.86163 -155.97632)
		(size 0.508)
		(drill 0.254)
		(layers "F.Cu" "B.Cu")
		(net "GND1")
	)
	(via
		(at 89.036906 -154.381708)
		(size 0.508)
		(drill 0.254)
		(layers "F.Cu" "B.Cu")
		(net "GND1")
	)
	(via
		(at 88.819736 -108.81868)
		(size 0.508)
		(drill 0.254)
		(layers "F.Cu" "B.Cu")
		(net "GND1")
	)
	(via
		(at 89.365074 -155.146248)
		(size 0.508)
		(drill 0.254)
		(layers "F.Cu" "B.Cu")
		(net "GND1")
	)
	(segment
		(start 21.717 -67.330574)
		(end 21.717 -66.226182)
		(width 0.18796)
		(layer "F.Cu")
		(net "SMB_SWB_SDA")
	)
	(segment
		(start 21.226272 -65.041272)
		(end 20.701 -63.77305)
		(width 0.18796)
		(layer "F.Cu")
		(net "SMB_SWB_SDA")
	)
	(segment
		(start 21.717 -66.226182)
		(end 21.226272 -65.041272)
		(width 0.18796)
		(layer "F.Cu")
		(net "SMB_SWB_SDA")
	)
	(segment
		(start 20.6502 -69.799962)
		(end 20.6502 -68.397374)
		(width 0.18796)
		(layer "F.Cu")
		(net "SMB_SWB_SDA")
	)
	(segment
		(start 20.6502 -68.397374)
		(end 21.717 -67.330574)
		(width 0.18796)
		(layer "F.Cu")
		(net "SMB_SWB_SDA")
	)
	(via
		(at 21.226272 -65.041272)
		(size 0.762)
		(drill 0.381)
		(layers "F.Cu" "B.Cu")
		(net "SMB_SWB_SDA")
	)
	(segment
		(start 22.479 -67.409314)
		(end 22.479 -66.548)
		(width 0.18796)
		(layer "F.Cu")
		(net "SMB_SWB_SCL")
	)
	(segment
		(start 21.717 -63.77305)
		(end 21.717 -64.538606)
		(width 0.18796)
		(layer "F.Cu")
		(net "SMB_SWB_SCL")
	)
	(segment
		(start 21.250148 -68.638166)
		(end 22.479 -67.409314)
		(width 0.18796)
		(layer "F.Cu")
		(net "SMB_SWB_SCL")
	)
	(segment
		(start 22.479 -66.37782)
		(end 22.479 -66.548)
		(width 0.18796)
		(layer "F.Cu")
		(net "SMB_SWB_SCL")
	)
	(segment
		(start 21.250148 -69.799962)
		(end 21.250148 -68.638166)
		(width 0.18796)
		(layer "F.Cu")
		(net "SMB_SWB_SCL")
	)
	(segment
		(start 21.717 -64.538606)
		(end 22.479 -66.37782)
		(width 0.18796)
		(layer "F.Cu")
		(net "SMB_SWB_SCL")
	)
	(via
		(at 22.479 -66.548)
		(size 0.762)
		(drill 0.381)
		(layers "F.Cu" "B.Cu")
		(net "SMB_SWB_SCL")
	)
	(segment
		(start 23.09495 -30.48)
		(end 23.09495 -29.6799)
		(width 0.18796)
		(layer "F.Cu")
		(net "UART_DEBUG_R_RX")
	)
	(segment
		(start 23.933658 -26.512774)
		(end 23.933658 -28.086304)
		(width 0.18796)
		(layer "F.Cu")
		(net "UART_DEBUG_R_RX")
	)
	(segment
		(start 25.900126 -21.329904)
		(end 25.900126 -24.546306)
		(width 0.18796)
		(layer "F.Cu")
		(net "UART_DEBUG_R_RX")
	)
	(segment
		(start 23.933658 -28.086304)
		(end 23.003002 -29.01696)
		(width 0.18796)
		(layer "F.Cu")
		(net "UART_DEBUG_R_RX")
	)
	(segment
		(start 23.09495 -29.6799)
		(end 23.003002 -29.587952)
		(width 0.18796)
		(layer "F.Cu")
		(net "UART_DEBUG_R_RX")
	)
	(segment
		(start 23.003002 -29.587952)
		(end 23.003002 -29.01696)
		(width 0.18796)
		(layer "F.Cu")
		(net "UART_DEBUG_R_RX")
	)
	(segment
		(start 25.900126 -24.546306)
		(end 23.933658 -26.512774)
		(width 0.18796)
		(layer "F.Cu")
		(net "UART_DEBUG_R_RX")
	)
	(segment
		(start 24.765 -30.734)
		(end 24.765 -29.254958)
		(width 0.18796)
		(layer "F.Cu")
		(net "UART_DEBUG_R_TX")
	)
	(segment
		(start 25.900126 -19.329908)
		(end 25.900126 -20.12442)
		(width 0.18796)
		(layer "F.Cu")
		(net "UART_DEBUG_R_TX")
	)
	(segment
		(start 14.03096 -53.584348)
		(end 13.716 -53.899308)
		(width 0.18796)
		(layer "F.Cu")
		(net "UART_DEBUG_R_TX")
	)
	(segment
		(start 24.426418 -28.44038)
		(end 25.002998 -29.01696)
		(width 0.18796)
		(layer "F.Cu")
		(net "UART_DEBUG_R_TX")
	)
	(segment
		(start 23.495 -32.004)
		(end 24.765 -30.734)
		(width 0.18796)
		(layer "F.Cu")
		(net "UART_DEBUG_R_TX")
	)
	(segment
		(start 26.694638 -24.44877)
		(end 24.426418 -26.71699)
		(width 0.18796)
		(layer "F.Cu")
		(net "UART_DEBUG_R_TX")
	)
	(segment
		(start 25.900126 -20.12442)
		(end 26.694638 -20.918932)
		(width 0.18796)
		(layer "F.Cu")
		(net "UART_DEBUG_R_TX")
	)
	(segment
		(start 13.716 -61.976)
		(end 15.24 -63.5)
		(width 0.18796)
		(layer "F.Cu")
		(net "UART_DEBUG_R_TX")
	)
	(segment
		(start 24.765 -29.254958)
		(end 25.002998 -29.01696)
		(width 0.18796)
		(layer "F.Cu")
		(net "UART_DEBUG_R_TX")
	)
	(segment
		(start 24.426418 -26.71699)
		(end 24.426418 -28.44038)
		(width 0.18796)
		(layer "F.Cu")
		(net "UART_DEBUG_R_TX")
	)
	(segment
		(start 18.94205 -62.97295)
		(end 18.415 -63.5)
		(width 0.18796)
		(layer "F.Cu")
		(net "UART_DEBUG_R_TX")
	)
	(segment
		(start 20.39874 -35.23869)
		(end 20.39874 -48.624236)
		(width 0.18796)
		(layer "F.Cu")
		(net "UART_DEBUG_R_TX")
	)
	(segment
		(start 13.716 -53.899308)
		(end 13.716 -61.976)
		(width 0.18796)
		(layer "F.Cu")
		(net "UART_DEBUG_R_TX")
	)
	(segment
		(start 15.438628 -53.584348)
		(end 14.03096 -53.584348)
		(width 0.18796)
		(layer "F.Cu")
		(net "UART_DEBUG_R_TX")
	)
	(segment
		(start 20.39874 -48.624236)
		(end 15.438628 -53.584348)
		(width 0.18796)
		(layer "F.Cu")
		(net "UART_DEBUG_R_TX")
	)
	(segment
		(start 15.24 -63.5)
		(end 18.415 -63.5)
		(width 0.18796)
		(layer "F.Cu")
		(net "UART_DEBUG_R_TX")
	)
	(segment
		(start 19.685 -62.97295)
		(end 18.94205 -62.97295)
		(width 0.18796)
		(layer "F.Cu")
		(net "UART_DEBUG_R_TX")
	)
	(segment
		(start 26.694638 -20.918932)
		(end 26.694638 -24.44877)
		(width 0.18796)
		(layer "F.Cu")
		(net "UART_DEBUG_R_TX")
	)
	(via
		(at 20.39874 -35.23869)
		(size 0.508)
		(drill 0.254)
		(layers "F.Cu" "B.Cu")
		(net "UART_DEBUG_R_TX")
	)
	(via
		(at 23.495 -32.004)
		(size 0.508)
		(drill 0.254)
		(layers "F.Cu" "B.Cu")
		(net "UART_DEBUG_R_TX")
	)
	(via
		(at 18.415 -63.5)
		(size 0.762)
		(drill 0.381)
		(layers "F.Cu" "B.Cu")
		(net "UART_DEBUG_R_TX")
	)
	(segment
		(start 23.495 -33.3248)
		(end 21.58111 -35.23869)
		(width 0.18796)
		(layer "B.Cu")
		(net "UART_DEBUG_R_TX")
	)
	(segment
		(start 23.495 -32.004)
		(end 23.495 -33.3248)
		(width 0.18796)
		(layer "B.Cu")
		(net "UART_DEBUG_R_TX")
	)
	(segment
		(start 21.58111 -35.23869)
		(end 20.39874 -35.23869)
		(width 0.18796)
		(layer "B.Cu")
		(net "UART_DEBUG_R_TX")
	)
	(segment
		(start 22.479 -31.369)
		(end 23.240746 -31.369)
		(width 0.18796)
		(layer "F.Cu")
		(net "UART_DEBUG_RX")
	)
	(segment
		(start 13.826744 -53.091588)
		(end 13.22324 -53.695092)
		(width 0.18796)
		(layer "F.Cu")
		(net "UART_DEBUG_RX")
	)
	(segment
		(start 18.850102 -68.54063)
		(end 18.850102 -69.799962)
		(width 0.18796)
		(layer "F.Cu")
		(net "UART_DEBUG_RX")
	)
	(segment
		(start 13.22324 -53.695092)
		(end 13.22324 -62.180216)
		(width 0.18796)
		(layer "F.Cu")
		(net "UART_DEBUG_RX")
	)
	(segment
		(start 20.2184 -65.636902)
		(end 20.2184 -67.172332)
		(width 0.18796)
		(layer "F.Cu")
		(net "UART_DEBUG_RX")
	)
	(segment
		(start 19.89836 -48.42764)
		(end 15.234412 -53.091588)
		(width 0.18796)
		(layer "F.Cu")
		(net "UART_DEBUG_RX")
	)
	(segment
		(start 15.234412 -53.091588)
		(end 13.826744 -53.091588)
		(width 0.18796)
		(layer "F.Cu")
		(net "UART_DEBUG_RX")
	)
	(segment
		(start 19.982688 -65.067688)
		(end 20.2184 -65.636902)
		(width 0.18796)
		(layer "F.Cu")
		(net "UART_DEBUG_RX")
	)
	(segment
		(start 15.559024 -64.516)
		(end 19.431 -64.516)
		(width 0.18796)
		(layer "F.Cu")
		(net "UART_DEBUG_RX")
	)
	(segment
		(start 20.2184 -67.172332)
		(end 18.850102 -68.54063)
		(width 0.18796)
		(layer "F.Cu")
		(net "UART_DEBUG_RX")
	)
	(segment
		(start 19.89836 -34.544)
		(end 19.89836 -48.42764)
		(width 0.18796)
		(layer "F.Cu")
		(net "UART_DEBUG_RX")
	)
	(segment
		(start 19.431 -64.516)
		(end 19.982688 -65.067688)
		(width 0.18796)
		(layer "F.Cu")
		(net "UART_DEBUG_RX")
	)
	(segment
		(start 13.22324 -62.180216)
		(end 15.559024 -64.516)
		(width 0.18796)
		(layer "F.Cu")
		(net "UART_DEBUG_RX")
	)
	(segment
		(start 23.89505 -30.714696)
		(end 23.89505 -30.48)
		(width 0.18796)
		(layer "F.Cu")
		(net "UART_DEBUG_RX")
	)
	(segment
		(start 23.240746 -31.369)
		(end 23.89505 -30.714696)
		(width 0.18796)
		(layer "F.Cu")
		(net "UART_DEBUG_RX")
	)
	(via
		(at 19.89836 -34.544)
		(size 0.508)
		(drill 0.254)
		(layers "F.Cu" "B.Cu")
		(net "UART_DEBUG_RX")
	)
	(via
		(at 15.559024 -64.516)
		(size 0.762)
		(drill 0.381)
		(layers "F.Cu" "B.Cu")
		(net "UART_DEBUG_RX")
	)
	(via
		(at 22.479 -31.369)
		(size 0.508)
		(drill 0.254)
		(layers "F.Cu" "B.Cu")
		(net "UART_DEBUG_RX")
	)
	(segment
		(start 22.479 -33.643824)
		(end 21.578824 -34.544)
		(width 0.18796)
		(layer "B.Cu")
		(net "UART_DEBUG_RX")
	)
	(segment
		(start 21.578824 -34.544)
		(end 19.89836 -34.544)
		(width 0.18796)
		(layer "B.Cu")
		(net "UART_DEBUG_RX")
	)
	(segment
		(start 22.479 -31.369)
		(end 22.479 -33.643824)
		(width 0.18796)
		(layer "B.Cu")
		(net "UART_DEBUG_RX")
	)
	(segment
		(start 20.955 -67.132962)
		(end 20.955 -66.548)
		(width 0.18796)
		(layer "F.Cu")
		(net "UART_DEBUG_TX")
	)
	(segment
		(start 19.706082 -63.77305)
		(end 19.685 -63.77305)
		(width 0.18796)
		(layer "F.Cu")
		(net "UART_DEBUG_TX")
	)
	(segment
		(start 19.45005 -69.799962)
		(end 19.45005 -68.637912)
		(width 0.18796)
		(layer "F.Cu")
		(net "UART_DEBUG_TX")
	)
	(segment
		(start 20.955 -66.548)
		(end 20.955 -66.126868)
		(width 0.18796)
		(layer "F.Cu")
		(net "UART_DEBUG_TX")
	)
	(segment
		(start 19.45005 -68.637912)
		(end 20.955 -67.132962)
		(width 0.18796)
		(layer "F.Cu")
		(net "UART_DEBUG_TX")
	)
	(segment
		(start 20.955 -66.126868)
		(end 20.173696 -64.240664)
		(width 0.18796)
		(layer "F.Cu")
		(net "UART_DEBUG_TX")
	)
	(segment
		(start 20.173696 -64.240664)
		(end 19.706082 -63.77305)
		(width 0.18796)
		(layer "F.Cu")
		(net "UART_DEBUG_TX")
	)
	(via
		(at 20.955 -66.548)
		(size 0.762)
		(drill 0.381)
		(layers "F.Cu" "B.Cu")
		(net "UART_DEBUG_TX")
	)
	(segment
		(start 17.272 -20.701)
		(end 17.272 -19.685254)
		(width 0.18796)
		(layer "F.Cu")
		(net "SMB_IO_DEBUG_CARD_SDA")
	)
	(segment
		(start 17.97304 -17.96796)
		(end 17.97304 -18.431002)
		(width 0.18796)
		(layer "F.Cu")
		(net "SMB_IO_DEBUG_CARD_SDA")
	)
	(segment
		(start 22.829774 -14.708124)
		(end 20.646898 -16.891)
		(width 0.18796)
		(layer "F.Cu")
		(net "SMB_IO_DEBUG_CARD_SDA")
	)
	(segment
		(start 17.272 -19.685254)
		(end 17.97304 -18.984214)
		(width 0.18796)
		(layer "F.Cu")
		(net "SMB_IO_DEBUG_CARD_SDA")
	)
	(segment
		(start 16.51 -21.463)
		(end 17.272 -20.701)
		(width 0.18796)
		(layer "F.Cu")
		(net "SMB_IO_DEBUG_CARD_SDA")
	)
	(segment
		(start 17.12595 -24.13)
		(end 17.12595 -25.146)
		(width 0.18796)
		(layer "F.Cu")
		(net "SMB_IO_DEBUG_CARD_SDA")
	)
	(segment
		(start 17.12595 -24.13)
		(end 17.12595 -24.108664)
		(width 0.18796)
		(layer "F.Cu")
		(net "SMB_IO_DEBUG_CARD_SDA")
	)
	(segment
		(start 20.646898 -16.891)
		(end 19.05 -16.891)
		(width 0.18796)
		(layer "F.Cu")
		(net "SMB_IO_DEBUG_CARD_SDA")
	)
	(segment
		(start 25.900126 -15.329916)
		(end 25.278334 -14.708124)
		(width 0.18796)
		(layer "F.Cu")
		(net "SMB_IO_DEBUG_CARD_SDA")
	)
	(segment
		(start 17.97304 -18.984214)
		(end 17.97304 -18.431002)
		(width 0.18796)
		(layer "F.Cu")
		(net "SMB_IO_DEBUG_CARD_SDA")
	)
	(segment
		(start 19.05 -16.891)
		(end 17.97304 -17.96796)
		(width 0.18796)
		(layer "F.Cu")
		(net "SMB_IO_DEBUG_CARD_SDA")
	)
	(segment
		(start 25.278334 -14.708124)
		(end 22.829774 -14.708124)
		(width 0.18796)
		(layer "F.Cu")
		(net "SMB_IO_DEBUG_CARD_SDA")
	)
	(segment
		(start 16.51 -23.492714)
		(end 16.51 -21.463)
		(width 0.18796)
		(layer "F.Cu")
		(net "SMB_IO_DEBUG_CARD_SDA")
	)
	(segment
		(start 17.12595 -24.108664)
		(end 16.51 -23.492714)
		(width 0.18796)
		(layer "F.Cu")
		(net "SMB_IO_DEBUG_CARD_SDA")
	)
	(segment
		(start 17.12595 -22.098)
		(end 17.12595 -21.73605)
		(width 0.18796)
		(layer "F.Cu")
		(net "SMB_IO_DEBUG_CARD_SCL")
	)
	(segment
		(start 17.97304 -20.88896)
		(end 17.97304 -20.430998)
		(width 0.18796)
		(layer "F.Cu")
		(net "SMB_IO_DEBUG_CARD_SCL")
	)
	(segment
		(start 18.669 -19.177)
		(end 17.97304 -19.87296)
		(width 0.18796)
		(layer "F.Cu")
		(net "SMB_IO_DEBUG_CARD_SCL")
	)
	(segment
		(start 19.344894 -17.48536)
		(end 18.669 -18.161254)
		(width 0.18796)
		(layer "F.Cu")
		(net "SMB_IO_DEBUG_CARD_SCL")
	)
	(segment
		(start 26.25217 -16.12773)
		(end 25.595072 -16.12773)
		(width 0.18796)
		(layer "F.Cu")
		(net "SMB_IO_DEBUG_CARD_SCL")
	)
	(segment
		(start 17.12595 -21.73605)
		(end 17.97304 -20.88896)
		(width 0.18796)
		(layer "F.Cu")
		(net "SMB_IO_DEBUG_CARD_SCL")
	)
	(segment
		(start 18.669 -18.161254)
		(end 18.669 -19.177)
		(width 0.18796)
		(layer "F.Cu")
		(net "SMB_IO_DEBUG_CARD_SCL")
	)
	(segment
		(start 26.719022 -14.907768)
		(end 26.719022 -15.660878)
		(width 0.18796)
		(layer "F.Cu")
		(net "SMB_IO_DEBUG_CARD_SCL")
	)
	(segment
		(start 25.900126 -13.32992)
		(end 25.900126 -14.088872)
		(width 0.18796)
		(layer "F.Cu")
		(net "SMB_IO_DEBUG_CARD_SCL")
	)
	(segment
		(start 17.97304 -19.87296)
		(end 17.97304 -20.430998)
		(width 0.18796)
		(layer "F.Cu")
		(net "SMB_IO_DEBUG_CARD_SCL")
	)
	(segment
		(start 23.076154 -15.302484)
		(end 20.893278 -17.48536)
		(width 0.18796)
		(layer "F.Cu")
		(net "SMB_IO_DEBUG_CARD_SCL")
	)
	(segment
		(start 17.12595 -23.114)
		(end 17.12595 -22.098)
		(width 0.18796)
		(layer "F.Cu")
		(net "SMB_IO_DEBUG_CARD_SCL")
	)
	(segment
		(start 25.595072 -16.12773)
		(end 24.769826 -15.302484)
		(width 0.18796)
		(layer "F.Cu")
		(net "SMB_IO_DEBUG_CARD_SCL")
	)
	(segment
		(start 24.769826 -15.302484)
		(end 23.076154 -15.302484)
		(width 0.18796)
		(layer "F.Cu")
		(net "SMB_IO_DEBUG_CARD_SCL")
	)
	(segment
		(start 26.719022 -15.660878)
		(end 26.25217 -16.12773)
		(width 0.18796)
		(layer "F.Cu")
		(net "SMB_IO_DEBUG_CARD_SCL")
	)
	(segment
		(start 20.893278 -17.48536)
		(end 19.344894 -17.48536)
		(width 0.18796)
		(layer "F.Cu")
		(net "SMB_IO_DEBUG_CARD_SCL")
	)
	(segment
		(start 25.900126 -14.088872)
		(end 26.719022 -14.907768)
		(width 0.18796)
		(layer "F.Cu")
		(net "SMB_IO_DEBUG_CARD_SCL")
	)
	(segment
		(start 15.117064 -60.187078)
		(end 16.139922 -60.187078)
		(width 0.18796)
		(layer "F.Cu")
		(net "SMB_EXP_SCL")
	)
	(segment
		(start 16.139922 -60.187078)
		(end 16.764 -59.563)
		(width 0.18796)
		(layer "F.Cu")
		(net "SMB_EXP_SCL")
	)
	(segment
		(start 17.653 -59.817)
		(end 18.01495 -59.817)
		(width 0.18796)
		(layer "F.Cu")
		(net "SMB_EXP_SCL")
	)
	(segment
		(start 17.399 -59.563)
		(end 17.653 -59.817)
		(width 0.18796)
		(layer "F.Cu")
		(net "SMB_EXP_SCL")
	)
	(segment
		(start 16.764 -59.563)
		(end 17.399 -59.563)
		(width 0.18796)
		(layer "F.Cu")
		(net "SMB_EXP_SCL")
	)
	(via
		(at 16.764 -59.563)
		(size 0.762)
		(drill 0.381)
		(layers "F.Cu" "B.Cu")
		(net "SMB_EXP_SCL")
	)
	(segment
		(start 18.01495 -60.833)
		(end 16.764 -60.833)
		(width 0.18796)
		(layer "F.Cu")
		(net "SMB_EXP_SDA")
	)
	(segment
		(start 15.117064 -60.837064)
		(end 16.759936 -60.837064)
		(width 0.18796)
		(layer "F.Cu")
		(net "SMB_EXP_SDA")
	)
	(segment
		(start 16.759936 -60.837064)
		(end 16.764 -60.833)
		(width 0.18796)
		(layer "F.Cu")
		(net "SMB_EXP_SDA")
	)
	(via
		(at 16.764 -60.833)
		(size 0.762)
		(drill 0.381)
		(layers "F.Cu" "B.Cu")
		(net "SMB_EXP_SDA")
	)
	(segment
		(start 9.12495 -25.92705)
		(end 9.2964 -25.7556)
		(width 0.18796)
		(layer "F.Cu")
		(net "SYSTEM_FAULT_ID_LED_R1_N")
	)
	(segment
		(start 8.509 -26.289)
		(end 9.12495 -26.289)
		(width 0.18796)
		(layer "F.Cu")
		(net "SYSTEM_FAULT_ID_LED_R1_N")
	)
	(segment
		(start 7.874 -25.654)
		(end 8.509 -26.289)
		(width 0.18796)
		(layer "F.Cu")
		(net "SYSTEM_FAULT_ID_LED_R1_N")
	)
	(segment
		(start 9.12495 -26.289)
		(end 9.12495 -25.92705)
		(width 0.18796)
		(layer "F.Cu")
		(net "SYSTEM_FAULT_ID_LED_R1_N")
	)
	(segment
		(start 7.874 -25.654)
		(end 6.5151 -25.654)
		(width 0.18796)
		(layer "F.Cu")
		(net "SYSTEM_FAULT_ID_LED_R1_N")
	)
	(segment
		(start 9.2964 -25.7556)
		(end 9.2964 -25.019)
		(width 0.18796)
		(layer "F.Cu")
		(net "SYSTEM_FAULT_ID_LED_R1_N")
	)
	(via
		(at 7.874 -25.654)
		(size 0.762)
		(drill 0.381)
		(layers "F.Cu" "B.Cu")
		(net "SYSTEM_FAULT_ID_LED_R1_N")
	)
	(segment
		(start 33.128966 -28.64104)
		(end 33.128966 -28.067)
		(width 0.18796)
		(layer "F.Cu")
		(net "NCP380_FLT_N")
	)
	(segment
		(start 33.128966 -28.067)
		(end 34.017966 -27.178)
		(width 0.18796)
		(layer "F.Cu")
		(net "NCP380_FLT_N")
	)
	(segment
		(start 35.687 -27.432)
		(end 36.30295 -27.432)
		(width 0.18796)
		(layer "F.Cu")
		(net "NCP380_FLT_N")
	)
	(segment
		(start 34.017966 -27.178)
		(end 34.925 -27.178)
		(width 0.18796)
		(layer "F.Cu")
		(net "NCP380_FLT_N")
	)
	(segment
		(start 35.433 -27.178)
		(end 35.687 -27.432)
		(width 0.18796)
		(layer "F.Cu")
		(net "NCP380_FLT_N")
	)
	(segment
		(start 34.925 -27.178)
		(end 35.433 -27.178)
		(width 0.18796)
		(layer "F.Cu")
		(net "NCP380_FLT_N")
	)
	(via
		(at 34.925 -27.178)
		(size 0.762)
		(drill 0.381)
		(layers "F.Cu" "B.Cu")
		(net "NCP380_FLT_N")
	)
	(segment
		(start 33.782 -26.416)
		(end 32.258 -27.94)
		(width 0.18796)
		(layer "F.Cu")
		(net "NCP380_ILIM")
	)
	(segment
		(start 32.258 -29.40304)
		(end 32.44596 -29.591)
		(width 0.18796)
		(layer "F.Cu")
		(net "NCP380_ILIM")
	)
	(segment
		(start 32.258 -27.94)
		(end 32.258 -29.40304)
		(width 0.18796)
		(layer "F.Cu")
		(net "NCP380_ILIM")
	)
	(segment
		(start 36.30295 -26.416)
		(end 33.782 -26.416)
		(width 0.18796)
		(layer "F.Cu")
		(net "NCP380_ILIM")
	)
	(segment
		(start 32.44596 -29.591)
		(end 33.128966 -29.591)
		(width 0.18796)
		(layer "F.Cu")
		(net "NCP380_ILIM")
	)
	(via
		(at 33.782 -26.416)
		(size 0.762)
		(drill 0.381)
		(layers "F.Cu" "B.Cu")
		(net "NCP380_ILIM")
	)
	(segment
		(start 31.86684 -27.314906)
		(end 33.781746 -25.4)
		(width 0.18796)
		(layer "F.Cu")
		(net "NCO380_EN")
	)
	(segment
		(start 33.781746 -25.4)
		(end 34.925 -25.4)
		(width 0.18796)
		(layer "F.Cu")
		(net "NCO380_EN")
	)
	(segment
		(start 31.86684 -28.45308)
		(end 31.86684 -27.314906)
		(width 0.18796)
		(layer "F.Cu")
		(net "NCO380_EN")
	)
	(segment
		(start 30.879034 -28.64104)
		(end 31.67888 -28.64104)
		(width 0.18796)
		(layer "F.Cu")
		(net "NCO380_EN")
	)
	(segment
		(start 31.67888 -28.64104)
		(end 31.86684 -28.45308)
		(width 0.18796)
		(layer "F.Cu")
		(net "NCO380_EN")
	)
	(segment
		(start 34.925 -25.4)
		(end 36.30295 -25.4)
		(width 0.18796)
		(layer "F.Cu")
		(net "NCO380_EN")
	)
	(via
		(at 34.925 -25.4)
		(size 0.762)
		(drill 0.381)
		(layers "F.Cu" "B.Cu")
		(net "NCO380_EN")
	)
	(segment
		(start 9.12495 -28.59405)
		(end 9.2964 -28.4226)
		(width 0.18796)
		(layer "F.Cu")
		(net "PWR_LED_R1_N")
	)
	(segment
		(start 9.2964 -28.4226)
		(end 9.2964 -27.813)
		(width 0.18796)
		(layer "F.Cu")
		(net "PWR_LED_R1_N")
	)
	(segment
		(start 9.12495 -29.083)
		(end 8.509 -29.083)
		(width 0.18796)
		(layer "F.Cu")
		(net "PWR_LED_R1_N")
	)
	(segment
		(start 8.509 -29.083)
		(end 7.874 -28.448)
		(width 0.18796)
		(layer "F.Cu")
		(net "PWR_LED_R1_N")
	)
	(segment
		(start 9.12495 -29.083)
		(end 9.12495 -28.59405)
		(width 0.18796)
		(layer "F.Cu")
		(net "PWR_LED_R1_N")
	)
	(segment
		(start 6.5151 -28.448)
		(end 7.874 -28.448)
		(width 0.18796)
		(layer "F.Cu")
		(net "PWR_LED_R1_N")
	)
	(via
		(at 7.874 -28.448)
		(size 0.762)
		(drill 0.381)
		(layers "F.Cu" "B.Cu")
		(net "PWR_LED_R1_N")
	)
	(segment
		(start 11.159998 -5.100066)
		(end 14.194028 -8.134096)
		(width 0.18796)
		(layer "F.Cu")
		(net "PWR_LED_R2_N")
	)
	(segment
		(start 14.194028 -16.805402)
		(end 13.0937 -19.461988)
		(width 0.18796)
		(layer "F.Cu")
		(net "PWR_LED_R2_N")
	)
	(segment
		(start 13.0937 -19.461988)
		(end 11.557 -20.998688)
		(width 0.18796)
		(layer "F.Cu")
		(net "PWR_LED_R2_N")
	)
	(segment
		(start 11.303 -25.781)
		(end 11.303 -26.416)
		(width 0.18796)
		(layer "F.Cu")
		(net "PWR_LED_R2_N")
	)
	(segment
		(start 11.557 -25.527)
		(end 11.303 -25.781)
		(width 0.18796)
		(layer "F.Cu")
		(net "PWR_LED_R2_N")
	)
	(segment
		(start 14.194028 -8.134096)
		(end 14.194028 -16.805402)
		(width 0.18796)
		(layer "F.Cu")
		(net "PWR_LED_R2_N")
	)
	(segment
		(start 10.7696 -26.9494)
		(end 10.7696 -27.813)
		(width 0.18796)
		(layer "F.Cu")
		(net "PWR_LED_R2_N")
	)
	(segment
		(start 11.557 -20.998688)
		(end 11.557 -25.527)
		(width 0.18796)
		(layer "F.Cu")
		(net "PWR_LED_R2_N")
	)
	(segment
		(start 11.303 -26.416)
		(end 10.7696 -26.9494)
		(width 0.18796)
		(layer "F.Cu")
		(net "PWR_LED_R2_N")
	)
	(via
		(at 11.303 -26.416)
		(size 0.762)
		(drill 0.381)
		(layers "F.Cu" "B.Cu")
		(net "PWR_LED_R2_N")
	)
	(segment
		(start 31.237682 -4.245864)
		(end 27.892248 -4.245864)
		(width 0.18796)
		(layer "F.Cu")
		(net "SMB_TMP75_SCL")
	)
	(segment
		(start 19.95805 -22.098)
		(end 19.95805 -23.114)
		(width 0.18796)
		(layer "F.Cu")
		(net "SMB_TMP75_SCL")
	)
	(segment
		(start 19.95805 -23.114)
		(end 20.574 -23.114)
		(width 0.18796)
		(layer "F.Cu")
		(net "SMB_TMP75_SCL")
	)
	(via
		(at 20.574 -23.114)
		(size 0.508)
		(drill 0.254)
		(layers "F.Cu" "B.Cu")
		(net "SMB_TMP75_SCL")
	)
	(via
		(at 27.892248 -4.245864)
		(size 0.508)
		(drill 0.254)
		(layers "F.Cu" "B.Cu")
		(net "SMB_TMP75_SCL")
	)
	(segment
		(start 20.574 -21.336)
		(end 22.217888 -19.692112)
		(width 0.18796)
		(layer "B.Cu")
		(net "SMB_TMP75_SCL")
	)
	(segment
		(start 21.287232 -15.577312)
		(end 21.287232 -9.924796)
		(width 0.18796)
		(layer "B.Cu")
		(net "SMB_TMP75_SCL")
	)
	(segment
		(start 22.217888 -19.692112)
		(end 22.217888 -16.507968)
		(width 0.18796)
		(layer "B.Cu")
		(net "SMB_TMP75_SCL")
	)
	(segment
		(start 21.287232 -9.924796)
		(end 26.966164 -4.245864)
		(width 0.18796)
		(layer "B.Cu")
		(net "SMB_TMP75_SCL")
	)
	(segment
		(start 22.217888 -16.507968)
		(end 21.287232 -15.577312)
		(width 0.18796)
		(layer "B.Cu")
		(net "SMB_TMP75_SCL")
	)
	(segment
		(start 20.574 -23.114)
		(end 20.574 -21.336)
		(width 0.18796)
		(layer "B.Cu")
		(net "SMB_TMP75_SCL")
	)
	(segment
		(start 26.966164 -4.245864)
		(end 27.892248 -4.245864)
		(width 0.18796)
		(layer "B.Cu")
		(net "SMB_TMP75_SCL")
	)
	(segment
		(start 96.884998 -45.377608)
		(end 96.737678 -45.230288)
		(width 0.14732)
		(layer "F.Cu")
		(net "TDR_DIFF_85_TOP_DP")
	)
	(segment
		(start 93.460062 -48.978058)
		(end 93.460062 -48.304958)
		(width 0.14732)
		(layer "F.Cu")
		(net "TDR_DIFF_85_TOP_DP")
	)
	(segment
		(start 93.755972 -57.361328)
		(end 93.460062 -57.065418)
		(width 0.14732)
		(layer "F.Cu")
		(net "TDR_DIFF_85_TOP_DP")
	)
	(segment
		(start 93.460062 -60.435998)
		(end 93.755972 -60.140088)
		(width 0.14732)
		(layer "F.Cu")
		(net "TDR_DIFF_85_TOP_DP")
	)
	(segment
		(start 95.17253 -61.552328)
		(end 95.02521 -61.405008)
		(width 0.14732)
		(layer "F.Cu")
		(net "TDR_DIFF_85_TOP_DP")
	)
	(segment
		(start 93.755972 -58.118248)
		(end 96.737678 -58.118248)
		(width 0.14732)
		(layer "F.Cu")
		(net "TDR_DIFF_85_TOP_DP")
	)
	(segment
		(start 96.737678 -31.834328)
		(end 96.884998 -31.687008)
		(width 0.14732)
		(layer "F.Cu")
		(net "TDR_DIFF_85_TOP_DP")
	)
	(segment
		(start 96.884998 -45.839888)
		(end 96.884998 -45.377608)
		(width 0.14732)
		(layer "F.Cu")
		(net "TDR_DIFF_85_TOP_DP")
	)
	(segment
		(start 96.884998 -57.508648)
		(end 96.737678 -57.361328)
		(width 0.14732)
		(layer "F.Cu")
		(net "TDR_DIFF_85_TOP_DP")
	)
	(segment
		(start 96.737678 -41.186608)
		(end 93.755972 -41.186608)
		(width 0.14732)
		(layer "F.Cu")
		(net "TDR_DIFF_85_TOP_DP")
	)
	(segment
		(start 96.737678 -43.208448)
		(end 93.755972 -43.208448)
		(width 0.14732)
		(layer "F.Cu")
		(net "TDR_DIFF_85_TOP_DP")
	)
	(segment
		(start 93.755972 -56.096408)
		(end 96.737678 -56.096408)
		(width 0.14732)
		(layer "F.Cu")
		(net "TDR_DIFF_85_TOP_DP")
	)
	(segment
		(start 96.884998 -51.443128)
		(end 96.737678 -51.295808)
		(width 0.14732)
		(layer "F.Cu")
		(net "TDR_DIFF_85_TOP_DP")
	)
	(segment
		(start 96.884998 -41.796208)
		(end 96.884998 -41.333928)
		(width 0.14732)
		(layer "F.Cu")
		(net "TDR_DIFF_85_TOP_DP")
	)
	(segment
		(start 96.884998 -55.949088)
		(end 96.884998 -55.486808)
		(width 0.14732)
		(layer "F.Cu")
		(net "TDR_DIFF_85_TOP_DP")
	)
	(segment
		(start 96.884998 -53.927248)
		(end 96.884998 -53.464968)
		(width 0.14732)
		(layer "F.Cu")
		(net "TDR_DIFF_85_TOP_DP")
	)
	(segment
		(start 96.737678 -55.339488)
		(end 93.755972 -55.339488)
		(width 0.14732)
		(layer "F.Cu")
		(net "TDR_DIFF_85_TOP_DP")
	)
	(segment
		(start 96.737678 -37.142928)
		(end 93.755972 -37.142928)
		(width 0.14732)
		(layer "F.Cu")
		(net "TDR_DIFF_85_TOP_DP")
	)
	(segment
		(start 96.737678 -54.074568)
		(end 96.884998 -53.927248)
		(width 0.14732)
		(layer "F.Cu")
		(net "TDR_DIFF_85_TOP_DP")
	)
	(segment
		(start 96.737678 -50.030888)
		(end 96.884998 -49.883568)
		(width 0.14732)
		(layer "F.Cu")
		(net "TDR_DIFF_85_TOP_DP")
	)
	(segment
		(start 96.737678 -33.856168)
		(end 96.884998 -33.708848)
		(width 0.14732)
		(layer "F.Cu")
		(net "TDR_DIFF_85_TOP_DP")
	)
	(segment
		(start 96.884998 -49.421288)
		(end 96.737678 -49.273968)
		(width 0.14732)
		(layer "F.Cu")
		(net "TDR_DIFF_85_TOP_DP")
	)
	(segment
		(start 96.737678 -31.077408)
		(end 93.755972 -31.077408)
		(width 0.14732)
		(layer "F.Cu")
		(net "TDR_DIFF_85_TOP_DP")
	)
	(segment
		(start 93.460062 -55.043578)
		(end 93.460062 -54.370478)
		(width 0.14732)
		(layer "F.Cu")
		(net "TDR_DIFF_85_TOP_DP")
	)
	(segment
		(start 96.737678 -29.055568)
		(end 93.65488 -29.055568)
		(width 0.14732)
		(layer "F.Cu")
		(net "TDR_DIFF_85_TOP_DP")
	)
	(segment
		(start 93.755972 -51.295808)
		(end 93.460062 -50.999898)
		(width 0.14732)
		(layer "F.Cu")
		(net "TDR_DIFF_85_TOP_DP")
	)
	(segment
		(start 96.884998 -43.818048)
		(end 96.884998 -43.355768)
		(width 0.14732)
		(layer "F.Cu")
		(net "TDR_DIFF_85_TOP_DP")
	)
	(segment
		(start 93.460062 -36.847018)
		(end 93.460062 -36.173918)
		(width 0.14732)
		(layer "F.Cu")
		(net "TDR_DIFF_85_TOP_DP")
	)
	(segment
		(start 93.755972 -37.899848)
		(end 96.737678 -37.899848)
		(width 0.14732)
		(layer "F.Cu")
		(net "TDR_DIFF_85_TOP_DP")
	)
	(segment
		(start 93.460062 -48.304958)
		(end 93.755972 -48.009048)
		(width 0.14732)
		(layer "F.Cu")
		(net "TDR_DIFF_85_TOP_DP")
	)
	(segment
		(start 93.460062 -34.152078)
		(end 93.755972 -33.856168)
		(width 0.14732)
		(layer "F.Cu")
		(net "TDR_DIFF_85_TOP_DP")
	)
	(segment
		(start 96.737678 -53.317648)
		(end 93.755972 -53.317648)
		(width 0.14732)
		(layer "F.Cu")
		(net "TDR_DIFF_85_TOP_DP")
	)
	(segment
		(start 96.737678 -45.987208)
		(end 96.884998 -45.839888)
		(width 0.14732)
		(layer "F.Cu")
		(net "TDR_DIFF_85_TOP_DP")
	)
	(segment
		(start 93.705426 -33.099248)
		(end 93.409516 -32.803338)
		(width 0.14732)
		(layer "F.Cu")
		(net "TDR_DIFF_85_TOP_DP")
	)
	(segment
		(start 96.884998 -37.290248)
		(end 96.737678 -37.142928)
		(width 0.14732)
		(layer "F.Cu")
		(net "TDR_DIFF_85_TOP_DP")
	)
	(segment
		(start 96.737678 -51.295808)
		(end 93.755972 -51.295808)
		(width 0.14732)
		(layer "F.Cu")
		(net "TDR_DIFF_85_TOP_DP")
	)
	(segment
		(start 93.460062 -52.348638)
		(end 93.755972 -52.052728)
		(width 0.14732)
		(layer "F.Cu")
		(net "TDR_DIFF_85_TOP_DP")
	)
	(segment
		(start 93.460062 -38.195758)
		(end 93.755972 -37.899848)
		(width 0.14732)
		(layer "F.Cu")
		(net "TDR_DIFF_85_TOP_DP")
	)
	(segment
		(start 93.755972 -39.921688)
		(end 96.737678 -39.921688)
		(width 0.14732)
		(layer "F.Cu")
		(net "TDR_DIFF_85_TOP_DP")
	)
	(segment
		(start 96.737678 -56.096408)
		(end 96.884998 -55.949088)
		(width 0.14732)
		(layer "F.Cu")
		(net "TDR_DIFF_85_TOP_DP")
	)
	(segment
		(start 93.638116 -25.768808)
		(end 95.02521 -25.768808)
		(width 0.14732)
		(layer "F.Cu")
		(net "TDR_DIFF_85_TOP_DP")
	)
	(segment
		(start 96.737678 -29.812488)
		(end 96.884998 -29.665168)
		(width 0.14732)
		(layer "F.Cu")
		(net "TDR_DIFF_85_TOP_DP")
	)
	(segment
		(start 95.02521 -25.768808)
		(end 95.17253 -25.621488)
		(width 0.14732)
		(layer "F.Cu")
		(net "TDR_DIFF_85_TOP_DP")
	)
	(segment
		(start 96.884998 -35.730688)
		(end 96.884998 -35.268408)
		(width 0.14732)
		(layer "F.Cu")
		(net "TDR_DIFF_85_TOP_DP")
	)
	(segment
		(start 93.460062 -34.825178)
		(end 93.460062 -34.152078)
		(width 0.14732)
		(layer "F.Cu")
		(net "TDR_DIFF_85_TOP_DP")
	)
	(segment
		(start 93.755972 -45.987208)
		(end 96.737678 -45.987208)
		(width 0.14732)
		(layer "F.Cu")
		(net "TDR_DIFF_85_TOP_DP")
	)
	(segment
		(start 96.737678 -37.899848)
		(end 96.884998 -37.752528)
		(width 0.14732)
		(layer "F.Cu")
		(net "TDR_DIFF_85_TOP_DP")
	)
	(segment
		(start 93.460062 -42.239438)
		(end 93.755972 -41.943528)
		(width 0.14732)
		(layer "F.Cu")
		(net "TDR_DIFF_85_TOP_DP")
	)
	(segment
		(start 93.460062 -50.999898)
		(end 93.460062 -50.326798)
		(width 0.14732)
		(layer "F.Cu")
		(net "TDR_DIFF_85_TOP_DP")
	)
	(segment
		(start 96.737678 -45.230288)
		(end 93.755972 -45.230288)
		(width 0.14732)
		(layer "F.Cu")
		(net "TDR_DIFF_85_TOP_DP")
	)
	(segment
		(start 93.460062 -30.108398)
		(end 93.755972 -29.812488)
		(width 0.14732)
		(layer "F.Cu")
		(net "TDR_DIFF_85_TOP_DP")
	)
	(segment
		(start 93.460062 -36.173918)
		(end 93.755972 -35.878008)
		(width 0.14732)
		(layer "F.Cu")
		(net "TDR_DIFF_85_TOP_DP")
	)
	(segment
		(start 93.460062 -44.261278)
		(end 93.755972 -43.965368)
		(width 0.14732)
		(layer "F.Cu")
		(net "TDR_DIFF_85_TOP_DP")
	)
	(segment
		(start 96.884998 -39.312088)
		(end 96.737678 -39.164768)
		(width 0.14732)
		(layer "F.Cu")
		(net "TDR_DIFF_85_TOP_DP")
	)
	(segment
		(start 96.737678 -49.273968)
		(end 93.755972 -49.273968)
		(width 0.14732)
		(layer "F.Cu")
		(net "TDR_DIFF_85_TOP_DP")
	)
	(segment
		(start 96.884998 -31.224728)
		(end 96.737678 -31.077408)
		(width 0.14732)
		(layer "F.Cu")
		(net "TDR_DIFF_85_TOP_DP")
	)
	(segment
		(start 93.460062 -59.087258)
		(end 93.460062 -58.414158)
		(width 0.14732)
		(layer "F.Cu")
		(net "TDR_DIFF_85_TOP_DP")
	)
	(segment
		(start 95.02521 -23.622)
		(end 94.02953 -23.622)
		(width 0.14732)
		(layer "F.Cu")
		(net "TDR_DIFF_85_TOP_DP")
	)
	(segment
		(start 94.02953 -62.894972)
		(end 95.02521 -62.894972)
		(width 0.14732)
		(layer "F.Cu")
		(net "TDR_DIFF_85_TOP_DP")
	)
	(segment
		(start 93.460062 -50.326798)
		(end 93.755972 -50.030888)
		(width 0.14732)
		(layer "F.Cu")
		(net "TDR_DIFF_85_TOP_DP")
	)
	(segment
		(start 93.460062 -53.021738)
		(end 93.460062 -52.348638)
		(width 0.14732)
		(layer "F.Cu")
		(net "TDR_DIFF_85_TOP_DP")
	)
	(segment
		(start 96.737678 -52.052728)
		(end 96.884998 -51.905408)
		(width 0.14732)
		(layer "F.Cu")
		(net "TDR_DIFF_85_TOP_DP")
	)
	(segment
		(start 93.460062 -40.890698)
		(end 93.460062 -40.217598)
		(width 0.14732)
		(layer "F.Cu")
		(net "TDR_DIFF_85_TOP_DP")
	)
	(segment
		(start 93.460062 -42.912538)
		(end 93.460062 -42.239438)
		(width 0.14732)
		(layer "F.Cu")
		(net "TDR_DIFF_85_TOP_DP")
	)
	(segment
		(start 96.884998 -27.643328)
		(end 96.884998 -27.181048)
		(width 0.14732)
		(layer "F.Cu")
		(net "TDR_DIFF_85_TOP_DP")
	)
	(segment
		(start 96.737678 -58.118248)
		(end 96.884998 -57.970928)
		(width 0.14732)
		(layer "F.Cu")
		(net "TDR_DIFF_85_TOP_DP")
	)
	(segment
		(start 93.755972 -29.812488)
		(end 96.737678 -29.812488)
		(width 0.14732)
		(layer "F.Cu")
		(net "TDR_DIFF_85_TOP_DP")
	)
	(segment
		(start 95.17253 -23.76932)
		(end 95.02521 -23.622)
		(width 0.14732)
		(layer "F.Cu")
		(net "TDR_DIFF_85_TOP_DP")
	)
	(segment
		(start 96.884998 -29.202888)
		(end 96.737678 -29.055568)
		(width 0.14732)
		(layer "F.Cu")
		(net "TDR_DIFF_85_TOP_DP")
	)
	(segment
		(start 96.737678 -43.965368)
		(end 96.884998 -43.818048)
		(width 0.14732)
		(layer "F.Cu")
		(net "TDR_DIFF_85_TOP_DP")
	)
	(segment
		(start 96.737678 -39.164768)
		(end 93.755972 -39.164768)
		(width 0.14732)
		(layer "F.Cu")
		(net "TDR_DIFF_85_TOP_DP")
	)
	(segment
		(start 96.884998 -53.464968)
		(end 96.737678 -53.317648)
		(width 0.14732)
		(layer "F.Cu")
		(net "TDR_DIFF_85_TOP_DP")
	)
	(segment
		(start 96.884998 -49.883568)
		(end 96.884998 -49.421288)
		(width 0.14732)
		(layer "F.Cu")
		(net "TDR_DIFF_85_TOP_DP")
	)
	(segment
		(start 93.460062 -54.370478)
		(end 93.755972 -54.074568)
		(width 0.14732)
		(layer "F.Cu")
		(net "TDR_DIFF_85_TOP_DP")
	)
	(segment
		(start 93.65488 -29.055568)
		(end 93.35897 -28.759658)
		(width 0.14732)
		(layer "F.Cu")
		(net "TDR_DIFF_85_TOP_DP")
	)
	(segment
		(start 96.884998 -39.774368)
		(end 96.884998 -39.312088)
		(width 0.14732)
		(layer "F.Cu")
		(net "TDR_DIFF_85_TOP_DP")
	)
	(segment
		(start 96.884998 -35.268408)
		(end 96.737678 -35.121088)
		(width 0.14732)
		(layer "F.Cu")
		(net "TDR_DIFF_85_TOP_DP")
	)
	(segment
		(start 93.755972 -54.074568)
		(end 96.737678 -54.074568)
		(width 0.14732)
		(layer "F.Cu")
		(net "TDR_DIFF_85_TOP_DP")
	)
	(segment
		(start 93.755972 -49.273968)
		(end 93.460062 -48.978058)
		(width 0.14732)
		(layer "F.Cu")
		(net "TDR_DIFF_85_TOP_DP")
	)
	(segment
		(start 93.755972 -50.030888)
		(end 96.737678 -50.030888)
		(width 0.14732)
		(layer "F.Cu")
		(net "TDR_DIFF_85_TOP_DP")
	)
	(segment
		(start 93.460062 -46.956218)
		(end 93.460062 -46.283118)
		(width 0.14732)
		(layer "F.Cu")
		(net "TDR_DIFF_85_TOP_DP")
	)
	(segment
		(start 96.737678 -33.099248)
		(end 93.705426 -33.099248)
		(width 0.14732)
		(layer "F.Cu")
		(net "TDR_DIFF_85_TOP_DP")
	)
	(segment
		(start 93.65488 -27.790648)
		(end 96.737678 -27.790648)
		(width 0.14732)
		(layer "F.Cu")
		(net "TDR_DIFF_85_TOP_DP")
	)
	(segment
		(start 93.638116 -27.033728)
		(end 93.342206 -26.737818)
		(width 0.14732)
		(layer "F.Cu")
		(net "TDR_DIFF_85_TOP_DP")
	)
	(segment
		(start 93.460062 -30.781498)
		(end 93.460062 -30.108398)
		(width 0.14732)
		(layer "F.Cu")
		(net "TDR_DIFF_85_TOP_DP")
	)
	(segment
		(start 93.460062 -46.283118)
		(end 93.755972 -45.987208)
		(width 0.14732)
		(layer "F.Cu")
		(net "TDR_DIFF_85_TOP_DP")
	)
	(segment
		(start 96.884998 -41.333928)
		(end 96.737678 -41.186608)
		(width 0.14732)
		(layer "F.Cu")
		(net "TDR_DIFF_85_TOP_DP")
	)
	(segment
		(start 96.884998 -59.530488)
		(end 96.737678 -59.383168)
		(width 0.14732)
		(layer "F.Cu")
		(net "TDR_DIFF_85_TOP_DP")
	)
	(segment
		(start 93.755972 -37.142928)
		(end 93.460062 -36.847018)
		(width 0.14732)
		(layer "F.Cu")
		(net "TDR_DIFF_85_TOP_DP")
	)
	(segment
		(start 93.755972 -48.009048)
		(end 96.737678 -48.009048)
		(width 0.14732)
		(layer "F.Cu")
		(net "TDR_DIFF_85_TOP_DP")
	)
	(segment
		(start 96.884998 -51.905408)
		(end 96.884998 -51.443128)
		(width 0.14732)
		(layer "F.Cu")
		(net "TDR_DIFF_85_TOP_DP")
	)
	(segment
		(start 93.755972 -33.856168)
		(end 96.737678 -33.856168)
		(width 0.14732)
		(layer "F.Cu")
		(net "TDR_DIFF_85_TOP_DP")
	)
	(segment
		(start 96.884998 -29.665168)
		(end 96.884998 -29.202888)
		(width 0.14732)
		(layer "F.Cu")
		(net "TDR_DIFF_85_TOP_DP")
	)
	(segment
		(start 96.737678 -35.121088)
		(end 93.755972 -35.121088)
		(width 0.14732)
		(layer "F.Cu")
		(net "TDR_DIFF_85_TOP_DP")
	)
	(segment
		(start 96.884998 -55.486808)
		(end 96.737678 -55.339488)
		(width 0.14732)
		(layer "F.Cu")
		(net "TDR_DIFF_85_TOP_DP")
	)
	(segment
		(start 93.460062 -58.414158)
		(end 93.755972 -58.118248)
		(width 0.14732)
		(layer "F.Cu")
		(net "TDR_DIFF_85_TOP_DP")
	)
	(segment
		(start 93.755972 -31.077408)
		(end 93.460062 -30.781498)
		(width 0.14732)
		(layer "F.Cu")
		(net "TDR_DIFF_85_TOP_DP")
	)
	(segment
		(start 93.460062 -56.392318)
		(end 93.755972 -56.096408)
		(width 0.14732)
		(layer "F.Cu")
		(net "TDR_DIFF_85_TOP_DP")
	)
	(segment
		(start 96.884998 -27.181048)
		(end 96.737678 -27.033728)
		(width 0.14732)
		(layer "F.Cu")
		(net "TDR_DIFF_85_TOP_DP")
	)
	(segment
		(start 96.884998 -37.752528)
		(end 96.884998 -37.290248)
		(width 0.14732)
		(layer "F.Cu")
		(net "TDR_DIFF_85_TOP_DP")
	)
	(segment
		(start 93.409516 -32.130238)
		(end 93.705426 -31.834328)
		(width 0.14732)
		(layer "F.Cu")
		(net "TDR_DIFF_85_TOP_DP")
	)
	(segment
		(start 93.35897 -28.086558)
		(end 93.65488 -27.790648)
		(width 0.14732)
		(layer "F.Cu")
		(net "TDR_DIFF_85_TOP_DP")
	)
	(segment
		(start 96.884998 -57.970928)
		(end 96.884998 -57.508648)
		(width 0.14732)
		(layer "F.Cu")
		(net "TDR_DIFF_85_TOP_DP")
	)
	(segment
		(start 95.02521 -61.405008)
		(end 93.755972 -61.405008)
		(width 0.14732)
		(layer "F.Cu")
		(net "TDR_DIFF_85_TOP_DP")
	)
	(segment
		(start 95.02521 -62.894972)
		(end 95.17253 -62.747652)
		(width 0.14732)
		(layer "F.Cu")
		(net "TDR_DIFF_85_TOP_DP")
	)
	(segment
		(start 93.755972 -60.140088)
		(end 96.737678 -60.140088)
		(width 0.14732)
		(layer "F.Cu")
		(net "TDR_DIFF_85_TOP_DP")
	)
	(segment
		(start 96.884998 -47.399448)
		(end 96.737678 -47.252128)
		(width 0.14732)
		(layer "F.Cu")
		(net "TDR_DIFF_85_TOP_DP")
	)
	(segment
		(start 93.460062 -40.217598)
		(end 93.755972 -39.921688)
		(width 0.14732)
		(layer "F.Cu")
		(net "TDR_DIFF_85_TOP_DP")
	)
	(segment
		(start 95.17253 -25.621488)
		(end 95.17253 -23.76932)
		(width 0.14732)
		(layer "F.Cu")
		(net "TDR_DIFF_85_TOP_DP")
	)
	(segment
		(start 93.755972 -35.121088)
		(end 93.460062 -34.825178)
		(width 0.14732)
		(layer "F.Cu")
		(net "TDR_DIFF_85_TOP_DP")
	)
	(segment
		(start 93.460062 -44.934378)
		(end 93.460062 -44.261278)
		(width 0.14732)
		(layer "F.Cu")
		(net "TDR_DIFF_85_TOP_DP")
	)
	(segment
		(start 96.737678 -47.252128)
		(end 93.755972 -47.252128)
		(width 0.14732)
		(layer "F.Cu")
		(net "TDR_DIFF_85_TOP_DP")
	)
	(segment
		(start 93.755972 -47.252128)
		(end 93.460062 -46.956218)
		(width 0.14732)
		(layer "F.Cu")
		(net "TDR_DIFF_85_TOP_DP")
	)
	(segment
		(start 96.737678 -27.033728)
		(end 93.638116 -27.033728)
		(width 0.14732)
		(layer "F.Cu")
		(net "TDR_DIFF_85_TOP_DP")
	)
	(segment
		(start 93.755972 -35.878008)
		(end 96.737678 -35.878008)
		(width 0.14732)
		(layer "F.Cu")
		(net "TDR_DIFF_85_TOP_DP")
	)
	(segment
		(start 96.737678 -27.790648)
		(end 96.884998 -27.643328)
		(width 0.14732)
		(layer "F.Cu")
		(net "TDR_DIFF_85_TOP_DP")
	)
	(segment
		(start 93.755972 -45.230288)
		(end 93.460062 -44.934378)
		(width 0.14732)
		(layer "F.Cu")
		(net "TDR_DIFF_85_TOP_DP")
	)
	(segment
		(start 93.705426 -31.834328)
		(end 96.737678 -31.834328)
		(width 0.14732)
		(layer "F.Cu")
		(net "TDR_DIFF_85_TOP_DP")
	)
	(segment
		(start 93.755972 -52.052728)
		(end 96.737678 -52.052728)
		(width 0.14732)
		(layer "F.Cu")
		(net "TDR_DIFF_85_TOP_DP")
	)
	(segment
		(start 93.755972 -41.186608)
		(end 93.460062 -40.890698)
		(width 0.14732)
		(layer "F.Cu")
		(net "TDR_DIFF_85_TOP_DP")
	)
	(segment
		(start 96.737678 -39.921688)
		(end 96.884998 -39.774368)
		(width 0.14732)
		(layer "F.Cu")
		(net "TDR_DIFF_85_TOP_DP")
	)
	(segment
		(start 95.17253 -62.747652)
		(end 95.17253 -61.552328)
		(width 0.14732)
		(layer "F.Cu")
		(net "TDR_DIFF_85_TOP_DP")
	)
	(segment
		(start 93.460062 -61.109098)
		(end 93.460062 -60.435998)
		(width 0.14732)
		(layer "F.Cu")
		(net "TDR_DIFF_85_TOP_DP")
	)
	(segment
		(start 96.884998 -33.246568)
		(end 96.737678 -33.099248)
		(width 0.14732)
		(layer "F.Cu")
		(net "TDR_DIFF_85_TOP_DP")
	)
	(segment
		(start 93.755972 -55.339488)
		(end 93.460062 -55.043578)
		(width 0.14732)
		(layer "F.Cu")
		(net "TDR_DIFF_85_TOP_DP")
	)
	(segment
		(start 96.884998 -43.355768)
		(end 96.737678 -43.208448)
		(width 0.14732)
		(layer "F.Cu")
		(net "TDR_DIFF_85_TOP_DP")
	)
	(segment
		(start 93.755972 -43.965368)
		(end 96.737678 -43.965368)
		(width 0.14732)
		(layer "F.Cu")
		(net "TDR_DIFF_85_TOP_DP")
	)
	(segment
		(start 96.737678 -59.383168)
		(end 93.755972 -59.383168)
		(width 0.14732)
		(layer "F.Cu")
		(net "TDR_DIFF_85_TOP_DP")
	)
	(segment
		(start 96.737678 -48.009048)
		(end 96.884998 -47.861728)
		(width 0.14732)
		(layer "F.Cu")
		(net "TDR_DIFF_85_TOP_DP")
	)
	(segment
		(start 93.755972 -39.164768)
		(end 93.460062 -38.868858)
		(width 0.14732)
		(layer "F.Cu")
		(net "TDR_DIFF_85_TOP_DP")
	)
	(segment
		(start 96.884998 -33.708848)
		(end 96.884998 -33.246568)
		(width 0.14732)
		(layer "F.Cu")
		(net "TDR_DIFF_85_TOP_DP")
	)
	(segment
		(start 93.342206 -26.737818)
		(end 93.342206 -26.064718)
		(width 0.14732)
		(layer "F.Cu")
		(net "TDR_DIFF_85_TOP_DP")
	)
	(segment
		(start 93.755972 -53.317648)
		(end 93.460062 -53.021738)
		(width 0.14732)
		(layer "F.Cu")
		(net "TDR_DIFF_85_TOP_DP")
	)
	(segment
		(start 96.737678 -57.361328)
		(end 93.755972 -57.361328)
		(width 0.14732)
		(layer "F.Cu")
		(net "TDR_DIFF_85_TOP_DP")
	)
	(segment
		(start 96.884998 -47.861728)
		(end 96.884998 -47.399448)
		(width 0.14732)
		(layer "F.Cu")
		(net "TDR_DIFF_85_TOP_DP")
	)
	(segment
		(start 93.342206 -26.064718)
		(end 93.638116 -25.768808)
		(width 0.14732)
		(layer "F.Cu")
		(net "TDR_DIFF_85_TOP_DP")
	)
	(segment
		(start 93.35897 -28.759658)
		(end 93.35897 -28.086558)
		(width 0.14732)
		(layer "F.Cu")
		(net "TDR_DIFF_85_TOP_DP")
	)
	(segment
		(start 93.460062 -57.065418)
		(end 93.460062 -56.392318)
		(width 0.14732)
		(layer "F.Cu")
		(net "TDR_DIFF_85_TOP_DP")
	)
	(segment
		(start 93.409516 -32.803338)
		(end 93.409516 -32.130238)
		(width 0.14732)
		(layer "F.Cu")
		(net "TDR_DIFF_85_TOP_DP")
	)
	(segment
		(start 96.737678 -35.878008)
		(end 96.884998 -35.730688)
		(width 0.14732)
		(layer "F.Cu")
		(net "TDR_DIFF_85_TOP_DP")
	)
	(segment
		(start 93.755972 -61.405008)
		(end 93.460062 -61.109098)
		(width 0.14732)
		(layer "F.Cu")
		(net "TDR_DIFF_85_TOP_DP")
	)
	(segment
		(start 93.755972 -43.208448)
		(end 93.460062 -42.912538)
		(width 0.14732)
		(layer "F.Cu")
		(net "TDR_DIFF_85_TOP_DP")
	)
	(segment
		(start 93.460062 -38.868858)
		(end 93.460062 -38.195758)
		(width 0.14732)
		(layer "F.Cu")
		(net "TDR_DIFF_85_TOP_DP")
	)
	(segment
		(start 93.755972 -41.943528)
		(end 96.737678 -41.943528)
		(width 0.14732)
		(layer "F.Cu")
		(net "TDR_DIFF_85_TOP_DP")
	)
	(segment
		(start 96.737678 -60.140088)
		(end 96.884998 -59.992768)
		(width 0.14732)
		(layer "F.Cu")
		(net "TDR_DIFF_85_TOP_DP")
	)
	(segment
		(start 96.884998 -31.687008)
		(end 96.884998 -31.224728)
		(width 0.14732)
		(layer "F.Cu")
		(net "TDR_DIFF_85_TOP_DP")
	)
	(segment
		(start 96.884998 -59.992768)
		(end 96.884998 -59.530488)
		(width 0.14732)
		(layer "F.Cu")
		(net "TDR_DIFF_85_TOP_DP")
	)
	(segment
		(start 93.755972 -59.383168)
		(end 93.460062 -59.087258)
		(width 0.14732)
		(layer "F.Cu")
		(net "TDR_DIFF_85_TOP_DP")
	)
	(segment
		(start 96.737678 -41.943528)
		(end 96.884998 -41.796208)
		(width 0.14732)
		(layer "F.Cu")
		(net "TDR_DIFF_85_TOP_DP")
	)
	(segment
		(start 16.51 -18.669)
		(end 16.51 -19.28495)
		(width 0.18796)
		(layer "F.Cu")
		(net "THERMAL_OS")
	)
	(segment
		(start 28.43911 -2.975864)
		(end 31.237682 -2.975864)
		(width 0.18796)
		(layer "F.Cu")
		(net "THERMAL_OS")
	)
	(via
		(at 28.43911 -2.975864)
		(size 0.508)
		(drill 0.254)
		(layers "F.Cu" "B.Cu")
		(net "THERMAL_OS")
	)
	(via
		(at 16.51 -18.669)
		(size 0.508)
		(drill 0.254)
		(layers "F.Cu" "B.Cu")
		(net "THERMAL_OS")
	)
	(segment
		(start 15.758922 -17.917922)
		(end 16.51 -18.669)
		(width 0.18796)
		(layer "B.Cu")
		(net "THERMAL_OS")
	)
	(segment
		(start 15.758922 -15.610078)
		(end 15.758922 -17.917922)
		(width 0.18796)
		(layer "B.Cu")
		(net "THERMAL_OS")
	)
	(segment
		(start 20.07108 -13.20292)
		(end 18.969482 -14.304518)
		(width 0.18796)
		(layer "B.Cu")
		(net "THERMAL_OS")
	)
	(segment
		(start 17.064482 -14.304518)
		(end 15.758922 -15.610078)
		(width 0.18796)
		(layer "B.Cu")
		(net "THERMAL_OS")
	)
	(segment
		(start 20.07108 -10.300208)
		(end 20.07108 -13.20292)
		(width 0.18796)
		(layer "B.Cu")
		(net "THERMAL_OS")
	)
	(segment
		(start 28.43911 -2.975864)
		(end 27.395424 -2.975864)
		(width 0.18796)
		(layer "B.Cu")
		(net "THERMAL_OS")
	)
	(segment
		(start 18.969482 -14.304518)
		(end 17.064482 -14.304518)
		(width 0.18796)
		(layer "B.Cu")
		(net "THERMAL_OS")
	)
	(segment
		(start 27.395424 -2.975864)
		(end 20.07108 -10.300208)
		(width 0.18796)
		(layer "B.Cu")
		(net "THERMAL_OS")
	)
	(segment
		(start 19.95805 -24.13)
		(end 19.95805 -25.146)
		(width 0.18796)
		(layer "F.Cu")
		(net "SMB_TMP75_SDA")
	)
	(segment
		(start 27.166316 -5.515864)
		(end 31.237682 -5.515864)
		(width 0.18796)
		(layer "F.Cu")
		(net "SMB_TMP75_SDA")
	)
	(segment
		(start 19.95805 -24.13)
		(end 20.574 -24.13)
		(width 0.18796)
		(layer "F.Cu")
		(net "SMB_TMP75_SDA")
	)
	(via
		(at 20.574 -24.13)
		(size 0.508)
		(drill 0.254)
		(layers "F.Cu" "B.Cu")
		(net "SMB_TMP75_SDA")
	)
	(via
		(at 27.166316 -5.515864)
		(size 0.508)
		(drill 0.254)
		(layers "F.Cu" "B.Cu")
		(net "SMB_TMP75_SDA")
	)
	(segment
		(start 27.166316 -5.569712)
		(end 27.166316 -5.515864)
		(width 0.18796)
		(layer "B.Cu")
		(net "SMB_TMP75_SDA")
	)
	(segment
		(start 21.209 -23.495)
		(end 21.209 -21.54174)
		(width 0.18796)
		(layer "B.Cu")
		(net "SMB_TMP75_SDA")
	)
	(segment
		(start 21.209 -21.54174)
		(end 22.845268 -19.905472)
		(width 0.18796)
		(layer "B.Cu")
		(net "SMB_TMP75_SDA")
	)
	(segment
		(start 23.22195 -9.514078)
		(end 27.166316 -5.569712)
		(width 0.18796)
		(layer "B.Cu")
		(net "SMB_TMP75_SDA")
	)
	(segment
		(start 22.845268 -15.865348)
		(end 23.22195 -15.488666)
		(width 0.18796)
		(layer "B.Cu")
		(net "SMB_TMP75_SDA")
	)
	(segment
		(start 23.22195 -15.488666)
		(end 23.22195 -9.514078)
		(width 0.18796)
		(layer "B.Cu")
		(net "SMB_TMP75_SDA")
	)
	(segment
		(start 20.574 -24.13)
		(end 21.209 -23.495)
		(width 0.18796)
		(layer "B.Cu")
		(net "SMB_TMP75_SDA")
	)
	(segment
		(start 22.845268 -19.905472)
		(end 22.845268 -15.865348)
		(width 0.18796)
		(layer "B.Cu")
		(net "SMB_TMP75_SDA")
	)
	(segment
		(start 88.629744 -33.207198)
		(end 88.441784 -33.395158)
		(width 0.18796)
		(layer "F.Cu")
		(net "TDR_SE_50_OHM_TOP")
	)
	(segment
		(start 85.12302 -49.955958)
		(end 85.31098 -50.143918)
		(width 0.18796)
		(layer "F.Cu")
		(net "TDR_SE_50_OHM_TOP")
	)
	(segment
		(start 88.629744 -49.158398)
		(end 88.441784 -49.346358)
		(width 0.18796)
		(layer "F.Cu")
		(net "TDR_SE_50_OHM_TOP")
	)
	(segment
		(start 88.441784 -40.573198)
		(end 88.629744 -40.761158)
		(width 0.18796)
		(layer "F.Cu")
		(net "TDR_SE_50_OHM_TOP")
	)
	(segment
		(start 88.441784 -47.751238)
		(end 85.31098 -47.751238)
		(width 0.18796)
		(layer "F.Cu")
		(net "TDR_SE_50_OHM_TOP")
	)
	(segment
		(start 88.629744 -41.182798)
		(end 88.441784 -41.370758)
		(width 0.18796)
		(layer "F.Cu")
		(net "TDR_SE_50_OHM_TOP")
	)
	(segment
		(start 85.31098 -47.751238)
		(end 85.12302 -47.939198)
		(width 0.18796)
		(layer "F.Cu")
		(net "TDR_SE_50_OHM_TOP")
	)
	(segment
		(start 88.441784 -41.370758)
		(end 85.31098 -41.370758)
		(width 0.18796)
		(layer "F.Cu")
		(net "TDR_SE_50_OHM_TOP")
	)
	(segment
		(start 88.441784 -50.143918)
		(end 88.629744 -50.331878)
		(width 0.18796)
		(layer "F.Cu")
		(net "TDR_SE_50_OHM_TOP")
	)
	(segment
		(start 87.064342 -32.597598)
		(end 88.441784 -32.597598)
		(width 0.18796)
		(layer "F.Cu")
		(net "TDR_SE_50_OHM_TOP")
	)
	(segment
		(start 88.629744 -52.348638)
		(end 88.441784 -52.536598)
		(width 0.18796)
		(layer "F.Cu")
		(net "TDR_SE_50_OHM_TOP")
	)
	(segment
		(start 85.31098 -42.168318)
		(end 88.441784 -42.168318)
		(width 0.18796)
		(layer "F.Cu")
		(net "TDR_SE_50_OHM_TOP")
	)
	(segment
		(start 88.629744 -47.563278)
		(end 88.441784 -47.751238)
		(width 0.18796)
		(layer "F.Cu")
		(net "TDR_SE_50_OHM_TOP")
	)
	(segment
		(start 88.629744 -43.951398)
		(end 88.629744 -44.373038)
		(width 0.18796)
		(layer "F.Cu")
		(net "TDR_SE_50_OHM_TOP")
	)
	(segment
		(start 85.31098 -35.787838)
		(end 88.441784 -35.787838)
		(width 0.18796)
		(layer "F.Cu")
		(net "TDR_SE_50_OHM_TOP")
	)
	(segment
		(start 85.31098 -50.941478)
		(end 85.12302 -51.129438)
		(width 0.18796)
		(layer "F.Cu")
		(net "TDR_SE_50_OHM_TOP")
	)
	(segment
		(start 85.12302 -46.765718)
		(end 85.31098 -46.953678)
		(width 0.18796)
		(layer "F.Cu")
		(net "TDR_SE_50_OHM_TOP")
	)
	(segment
		(start 85.12302 -36.773358)
		(end 85.12302 -37.194998)
		(width 0.18796)
		(layer "F.Cu")
		(net "TDR_SE_50_OHM_TOP")
	)
	(segment
		(start 88.441784 -46.156118)
		(end 85.31098 -46.156118)
		(width 0.18796)
		(layer "F.Cu")
		(net "TDR_SE_50_OHM_TOP")
	)
	(segment
		(start 85.31098 -41.370758)
		(end 85.12302 -41.558718)
		(width 0.18796)
		(layer "F.Cu")
		(net "TDR_SE_50_OHM_TOP")
	)
	(segment
		(start 88.629744 -50.753518)
		(end 88.441784 -50.941478)
		(width 0.18796)
		(layer "F.Cu")
		(net "TDR_SE_50_OHM_TOP")
	)
	(segment
		(start 88.629744 -34.380678)
		(end 88.629744 -34.802318)
		(width 0.18796)
		(layer "F.Cu")
		(net "TDR_SE_50_OHM_TOP")
	)
	(segment
		(start 85.045042 -33.583118)
		(end 85.045042 -34.004758)
		(width 0.18796)
		(layer "F.Cu")
		(net "TDR_SE_50_OHM_TOP")
	)
	(segment
		(start 85.12302 -46.344078)
		(end 85.12302 -46.765718)
		(width 0.18796)
		(layer "F.Cu")
		(net "TDR_SE_50_OHM_TOP")
	)
	(segment
		(start 88.629744 -40.761158)
		(end 88.629744 -41.182798)
		(width 0.18796)
		(layer "F.Cu")
		(net "TDR_SE_50_OHM_TOP")
	)
	(segment
		(start 85.233002 -33.395158)
		(end 85.045042 -33.583118)
		(width 0.18796)
		(layer "F.Cu")
		(net "TDR_SE_50_OHM_TOP")
	)
	(segment
		(start 85.31098 -43.763438)
		(end 88.441784 -43.763438)
		(width 0.18796)
		(layer "F.Cu")
		(net "TDR_SE_50_OHM_TOP")
	)
	(segment
		(start 88.629744 -39.587678)
		(end 88.441784 -39.775638)
		(width 0.18796)
		(layer "F.Cu")
		(net "TDR_SE_50_OHM_TOP")
	)
	(segment
		(start 88.441784 -49.346358)
		(end 85.31098 -49.346358)
		(width 0.18796)
		(layer "F.Cu")
		(net "TDR_SE_50_OHM_TOP")
	)
	(segment
		(start 88.441784 -42.168318)
		(end 88.629744 -42.356278)
		(width 0.18796)
		(layer "F.Cu")
		(net "TDR_SE_50_OHM_TOP")
	)
	(segment
		(start 85.31098 -39.775638)
		(end 85.12302 -39.963598)
		(width 0.18796)
		(layer "F.Cu")
		(net "TDR_SE_50_OHM_TOP")
	)
	(segment
		(start 88.441784 -36.585398)
		(end 85.31098 -36.585398)
		(width 0.18796)
		(layer "F.Cu")
		(net "TDR_SE_50_OHM_TOP")
	)
	(segment
		(start 88.441784 -34.990278)
		(end 85.31098 -34.990278)
		(width 0.18796)
		(layer "F.Cu")
		(net "TDR_SE_50_OHM_TOP")
	)
	(segment
		(start 85.31098 -44.560998)
		(end 85.12302 -44.748958)
		(width 0.18796)
		(layer "F.Cu")
		(net "TDR_SE_50_OHM_TOP")
	)
	(segment
		(start 85.045042 -54.319678)
		(end 85.045042 -54.741318)
		(width 0.18796)
		(layer "F.Cu")
		(net "TDR_SE_50_OHM_TOP")
	)
	(segment
		(start 85.12302 -43.575478)
		(end 85.31098 -43.763438)
		(width 0.18796)
		(layer "F.Cu")
		(net "TDR_SE_50_OHM_TOP")
	)
	(segment
		(start 88.441784 -35.787838)
		(end 88.629744 -35.975798)
		(width 0.18796)
		(layer "F.Cu")
		(net "TDR_SE_50_OHM_TOP")
	)
	(segment
		(start 86.876382 -55.117238)
		(end 86.876382 -59.56935)
		(width 0.18796)
		(layer "F.Cu")
		(net "TDR_SE_50_OHM_TOP")
	)
	(segment
		(start 89.416382 -30.765242)
		(end 89.228422 -30.577282)
		(width 0.18796)
		(layer "F.Cu")
		(net "TDR_SE_50_OHM_TOP")
	)
	(segment
		(start 88.441784 -52.536598)
		(end 85.31098 -52.536598)
		(width 0.18796)
		(layer "F.Cu")
		(net "TDR_SE_50_OHM_TOP")
	)
	(segment
		(start 85.12302 -45.170598)
		(end 85.31098 -45.358558)
		(width 0.18796)
		(layer "F.Cu")
		(net "TDR_SE_50_OHM_TOP")
	)
	(segment
		(start 85.12302 -38.790118)
		(end 85.31098 -38.978078)
		(width 0.18796)
		(layer "F.Cu")
		(net "TDR_SE_50_OHM_TOP")
	)
	(segment
		(start 88.629744 -45.546518)
		(end 88.629744 -45.968158)
		(width 0.18796)
		(layer "F.Cu")
		(net "TDR_SE_50_OHM_TOP")
	)
	(segment
		(start 88.441784 -44.560998)
		(end 85.31098 -44.560998)
		(width 0.18796)
		(layer "F.Cu")
		(net "TDR_SE_50_OHM_TOP")
	)
	(segment
		(start 85.233002 -34.192718)
		(end 88.441784 -34.192718)
		(width 0.18796)
		(layer "F.Cu")
		(net "TDR_SE_50_OHM_TOP")
	)
	(segment
		(start 85.12302 -51.129438)
		(end 85.12302 -51.551078)
		(width 0.18796)
		(layer "F.Cu")
		(net "TDR_SE_50_OHM_TOP")
	)
	(segment
		(start 88.441784 -39.775638)
		(end 85.31098 -39.775638)
		(width 0.18796)
		(layer "F.Cu")
		(net "TDR_SE_50_OHM_TOP")
	)
	(segment
		(start 88.629744 -53.522118)
		(end 88.629744 -53.943758)
		(width 0.18796)
		(layer "F.Cu")
		(net "TDR_SE_50_OHM_TOP")
	)
	(segment
		(start 85.12302 -47.939198)
		(end 85.12302 -48.360838)
		(width 0.18796)
		(layer "F.Cu")
		(net "TDR_SE_50_OHM_TOP")
	)
	(segment
		(start 88.441784 -45.358558)
		(end 88.629744 -45.546518)
		(width 0.18796)
		(layer "F.Cu")
		(net "TDR_SE_50_OHM_TOP")
	)
	(segment
		(start 88.629744 -45.968158)
		(end 88.441784 -46.156118)
		(width 0.18796)
		(layer "F.Cu")
		(net "TDR_SE_50_OHM_TOP")
	)
	(segment
		(start 85.31098 -34.990278)
		(end 85.12302 -35.178238)
		(width 0.18796)
		(layer "F.Cu")
		(net "TDR_SE_50_OHM_TOP")
	)
	(segment
		(start 88.629744 -53.943758)
		(end 88.441784 -54.131718)
		(width 0.18796)
		(layer "F.Cu")
		(net "TDR_SE_50_OHM_TOP")
	)
	(segment
		(start 88.441784 -43.763438)
		(end 88.629744 -43.951398)
		(width 0.18796)
		(layer "F.Cu")
		(net "TDR_SE_50_OHM_TOP")
	)
	(segment
		(start 85.12302 -41.980358)
		(end 85.31098 -42.168318)
		(width 0.18796)
		(layer "F.Cu")
		(net "TDR_SE_50_OHM_TOP")
	)
	(segment
		(start 85.045042 -34.004758)
		(end 85.233002 -34.192718)
		(width 0.18796)
		(layer "F.Cu")
		(net "TDR_SE_50_OHM_TOP")
	)
	(segment
		(start 85.12302 -49.534318)
		(end 85.12302 -49.955958)
		(width 0.18796)
		(layer "F.Cu")
		(net "TDR_SE_50_OHM_TOP")
	)
	(segment
		(start 85.31098 -48.548798)
		(end 88.441784 -48.548798)
		(width 0.18796)
		(layer "F.Cu")
		(net "TDR_SE_50_OHM_TOP")
	)
	(segment
		(start 88.441784 -38.180518)
		(end 85.31098 -38.180518)
		(width 0.18796)
		(layer "F.Cu")
		(net "TDR_SE_50_OHM_TOP")
	)
	(segment
		(start 85.31098 -52.536598)
		(end 85.12302 -52.724558)
		(width 0.18796)
		(layer "F.Cu")
		(net "TDR_SE_50_OHM_TOP")
	)
	(segment
		(start 87.049864 -30.577282)
		(end 86.876382 -30.750764)
		(width 0.18796)
		(layer "F.Cu")
		(net "TDR_SE_50_OHM_TOP")
	)
	(segment
		(start 88.441784 -50.941478)
		(end 85.31098 -50.941478)
		(width 0.18796)
		(layer "F.Cu")
		(net "TDR_SE_50_OHM_TOP")
	)
	(segment
		(start 85.12302 -39.963598)
		(end 85.12302 -40.385238)
		(width 0.18796)
		(layer "F.Cu")
		(net "TDR_SE_50_OHM_TOP")
	)
	(segment
		(start 86.688422 -54.929278)
		(end 86.876382 -55.117238)
		(width 0.18796)
		(layer "F.Cu")
		(net "TDR_SE_50_OHM_TOP")
	)
	(segment
		(start 88.441784 -37.382958)
		(end 88.629744 -37.570918)
		(width 0.18796)
		(layer "F.Cu")
		(net "TDR_SE_50_OHM_TOP")
	)
	(segment
		(start 88.629744 -37.570918)
		(end 88.629744 -37.992558)
		(width 0.18796)
		(layer "F.Cu")
		(net "TDR_SE_50_OHM_TOP")
	)
	(segment
		(start 85.12302 -52.724558)
		(end 85.12302 -53.146198)
		(width 0.18796)
		(layer "F.Cu")
		(net "TDR_SE_50_OHM_TOP")
	)
	(segment
		(start 85.12302 -51.551078)
		(end 85.31098 -51.739038)
		(width 0.18796)
		(layer "F.Cu")
		(net "TDR_SE_50_OHM_TOP")
	)
	(segment
		(start 89.416382 -59.56935)
		(end 89.416382 -30.765242)
		(width 0.18796)
		(layer "F.Cu")
		(net "TDR_SE_50_OHM_TOP")
	)
	(segment
		(start 88.441784 -46.953678)
		(end 88.629744 -47.141638)
		(width 0.18796)
		(layer "F.Cu")
		(net "TDR_SE_50_OHM_TOP")
	)
	(segment
		(start 86.876382 -30.750764)
		(end 86.876382 -32.409638)
		(width 0.18796)
		(layer "F.Cu")
		(net "TDR_SE_50_OHM_TOP")
	)
	(segment
		(start 88.629744 -39.166038)
		(end 88.629744 -39.587678)
		(width 0.18796)
		(layer "F.Cu")
		(net "TDR_SE_50_OHM_TOP")
	)
	(segment
		(start 88.441784 -54.131718)
		(end 85.233002 -54.131718)
		(width 0.18796)
		(layer "F.Cu")
		(net "TDR_SE_50_OHM_TOP")
	)
	(segment
		(start 85.31098 -46.953678)
		(end 88.441784 -46.953678)
		(width 0.18796)
		(layer "F.Cu")
		(net "TDR_SE_50_OHM_TOP")
	)
	(segment
		(start 85.12302 -35.178238)
		(end 85.12302 -35.599878)
		(width 0.18796)
		(layer "F.Cu")
		(net "TDR_SE_50_OHM_TOP")
	)
	(segment
		(start 85.31098 -46.156118)
		(end 85.12302 -46.344078)
		(width 0.18796)
		(layer "F.Cu")
		(net "TDR_SE_50_OHM_TOP")
	)
	(segment
		(start 85.31098 -40.573198)
		(end 88.441784 -40.573198)
		(width 0.18796)
		(layer "F.Cu")
		(net "TDR_SE_50_OHM_TOP")
	)
	(segment
		(start 88.629744 -42.356278)
		(end 88.629744 -42.777918)
		(width 0.18796)
		(layer "F.Cu")
		(net "TDR_SE_50_OHM_TOP")
	)
	(segment
		(start 85.12302 -43.153838)
		(end 85.12302 -43.575478)
		(width 0.18796)
		(layer "F.Cu")
		(net "TDR_SE_50_OHM_TOP")
	)
	(segment
		(start 88.629744 -42.777918)
		(end 88.441784 -42.965878)
		(width 0.18796)
		(layer "F.Cu")
		(net "TDR_SE_50_OHM_TOP")
	)
	(segment
		(start 85.12302 -44.748958)
		(end 85.12302 -45.170598)
		(width 0.18796)
		(layer "F.Cu")
		(net "TDR_SE_50_OHM_TOP")
	)
	(segment
		(start 88.441784 -51.739038)
		(end 88.629744 -51.926998)
		(width 0.18796)
		(layer "F.Cu")
		(net "TDR_SE_50_OHM_TOP")
	)
	(segment
		(start 88.629744 -44.373038)
		(end 88.441784 -44.560998)
		(width 0.18796)
		(layer "F.Cu")
		(net "TDR_SE_50_OHM_TOP")
	)
	(segment
		(start 85.12302 -37.194998)
		(end 85.31098 -37.382958)
		(width 0.18796)
		(layer "F.Cu")
		(net "TDR_SE_50_OHM_TOP")
	)
	(segment
		(start 85.31098 -50.143918)
		(end 88.441784 -50.143918)
		(width 0.18796)
		(layer "F.Cu")
		(net "TDR_SE_50_OHM_TOP")
	)
	(segment
		(start 88.629744 -51.926998)
		(end 88.629744 -52.348638)
		(width 0.18796)
		(layer "F.Cu")
		(net "TDR_SE_50_OHM_TOP")
	)
	(segment
		(start 85.12302 -38.368478)
		(end 85.12302 -38.790118)
		(width 0.18796)
		(layer "F.Cu")
		(net "TDR_SE_50_OHM_TOP")
	)
	(segment
		(start 88.629744 -36.397438)
		(end 88.441784 -36.585398)
		(width 0.18796)
		(layer "F.Cu")
		(net "TDR_SE_50_OHM_TOP")
	)
	(segment
		(start 88.441784 -42.965878)
		(end 85.31098 -42.965878)
		(width 0.18796)
		(layer "F.Cu")
		(net "TDR_SE_50_OHM_TOP")
	)
	(segment
		(start 88.441784 -38.978078)
		(end 88.629744 -39.166038)
		(width 0.18796)
		(layer "F.Cu")
		(net "TDR_SE_50_OHM_TOP")
	)
	(segment
		(start 88.629744 -48.736758)
		(end 88.629744 -49.158398)
		(width 0.18796)
		(layer "F.Cu")
		(net "TDR_SE_50_OHM_TOP")
	)
	(segment
		(start 86.876382 -32.409638)
		(end 87.064342 -32.597598)
		(width 0.18796)
		(layer "F.Cu")
		(net "TDR_SE_50_OHM_TOP")
	)
	(segment
		(start 88.441784 -48.548798)
		(end 88.629744 -48.736758)
		(width 0.18796)
		(layer "F.Cu")
		(net "TDR_SE_50_OHM_TOP")
	)
	(segment
		(start 85.31098 -38.978078)
		(end 88.441784 -38.978078)
		(width 0.18796)
		(layer "F.Cu")
		(net "TDR_SE_50_OHM_TOP")
	)
	(segment
		(start 85.31098 -51.739038)
		(end 88.441784 -51.739038)
		(width 0.18796)
		(layer "F.Cu")
		(net "TDR_SE_50_OHM_TOP")
	)
	(segment
		(start 85.31098 -38.180518)
		(end 85.12302 -38.368478)
		(width 0.18796)
		(layer "F.Cu")
		(net "TDR_SE_50_OHM_TOP")
	)
	(segment
		(start 85.12302 -41.558718)
		(end 85.12302 -41.980358)
		(width 0.18796)
		(layer "F.Cu")
		(net "TDR_SE_50_OHM_TOP")
	)
	(segment
		(start 85.31098 -53.334158)
		(end 88.441784 -53.334158)
		(width 0.18796)
		(layer "F.Cu")
		(net "TDR_SE_50_OHM_TOP")
	)
	(segment
		(start 88.629744 -47.141638)
		(end 88.629744 -47.563278)
		(width 0.18796)
		(layer "F.Cu")
		(net "TDR_SE_50_OHM_TOP")
	)
	(segment
		(start 85.12302 -40.385238)
		(end 85.31098 -40.573198)
		(width 0.18796)
		(layer "F.Cu")
		(net "TDR_SE_50_OHM_TOP")
	)
	(segment
		(start 85.233002 -54.929278)
		(end 86.688422 -54.929278)
		(width 0.18796)
		(layer "F.Cu")
		(net "TDR_SE_50_OHM_TOP")
	)
	(segment
		(start 85.045042 -54.741318)
		(end 85.233002 -54.929278)
		(width 0.18796)
		(layer "F.Cu")
		(net "TDR_SE_50_OHM_TOP")
	)
	(segment
		(start 88.441784 -32.597598)
		(end 88.629744 -32.785558)
		(width 0.18796)
		(layer "F.Cu")
		(net "TDR_SE_50_OHM_TOP")
	)
	(segment
		(start 88.441784 -33.395158)
		(end 85.233002 -33.395158)
		(width 0.18796)
		(layer "F.Cu")
		(net "TDR_SE_50_OHM_TOP")
	)
	(segment
		(start 85.12302 -48.360838)
		(end 85.31098 -48.548798)
		(width 0.18796)
		(layer "F.Cu")
		(net "TDR_SE_50_OHM_TOP")
	)
	(segment
		(start 85.31098 -42.965878)
		(end 85.12302 -43.153838)
		(width 0.18796)
		(layer "F.Cu")
		(net "TDR_SE_50_OHM_TOP")
	)
	(segment
		(start 88.629744 -37.992558)
		(end 88.441784 -38.180518)
		(width 0.18796)
		(layer "F.Cu")
		(net "TDR_SE_50_OHM_TOP")
	)
	(segment
		(start 88.629744 -50.331878)
		(end 88.629744 -50.753518)
		(width 0.18796)
		(layer "F.Cu")
		(net "TDR_SE_50_OHM_TOP")
	)
	(segment
		(start 85.233002 -54.131718)
		(end 85.045042 -54.319678)
		(width 0.18796)
		(layer "F.Cu")
		(net "TDR_SE_50_OHM_TOP")
	)
	(segment
		(start 85.12302 -53.146198)
		(end 85.31098 -53.334158)
		(width 0.18796)
		(layer "F.Cu")
		(net "TDR_SE_50_OHM_TOP")
	)
	(segment
		(start 89.228422 -30.577282)
		(end 87.049864 -30.577282)
		(width 0.18796)
		(layer "F.Cu")
		(net "TDR_SE_50_OHM_TOP")
	)
	(segment
		(start 88.629744 -35.975798)
		(end 88.629744 -36.397438)
		(width 0.18796)
		(layer "F.Cu")
		(net "TDR_SE_50_OHM_TOP")
	)
	(segment
		(start 85.12302 -35.599878)
		(end 85.31098 -35.787838)
		(width 0.18796)
		(layer "F.Cu")
		(net "TDR_SE_50_OHM_TOP")
	)
	(segment
		(start 85.31098 -49.346358)
		(end 85.12302 -49.534318)
		(width 0.18796)
		(layer "F.Cu")
		(net "TDR_SE_50_OHM_TOP")
	)
	(segment
		(start 88.441784 -34.192718)
		(end 88.629744 -34.380678)
		(width 0.18796)
		(layer "F.Cu")
		(net "TDR_SE_50_OHM_TOP")
	)
	(segment
		(start 85.31098 -36.585398)
		(end 85.12302 -36.773358)
		(width 0.18796)
		(layer "F.Cu")
		(net "TDR_SE_50_OHM_TOP")
	)
	(segment
		(start 88.629744 -34.802318)
		(end 88.441784 -34.990278)
		(width 0.18796)
		(layer "F.Cu")
		(net "TDR_SE_50_OHM_TOP")
	)
	(segment
		(start 85.31098 -45.358558)
		(end 88.441784 -45.358558)
		(width 0.18796)
		(layer "F.Cu")
		(net "TDR_SE_50_OHM_TOP")
	)
	(segment
		(start 85.31098 -37.382958)
		(end 88.441784 -37.382958)
		(width 0.18796)
		(layer "F.Cu")
		(net "TDR_SE_50_OHM_TOP")
	)
	(segment
		(start 88.441784 -53.334158)
		(end 88.629744 -53.522118)
		(width 0.18796)
		(layer "F.Cu")
		(net "TDR_SE_50_OHM_TOP")
	)
	(segment
		(start 88.629744 -32.785558)
		(end 88.629744 -33.207198)
		(width 0.18796)
		(layer "F.Cu")
		(net "TDR_SE_50_OHM_TOP")
	)
	(segment
		(start 32.385 -1.705864)
		(end 36.537646 -1.705864)
		(width 0.18796)
		(layer "F.Cu")
		(net "THERMAL_ADDR_A2")
	)
	(segment
		(start 36.30295 -23.368)
		(end 36.30295 -24.384)
		(width 0.18796)
		(layer "F.Cu")
		(net "THERMAL_ADDR_A2")
	)
	(segment
		(start 36.30295 -23.368)
		(end 34.798 -23.368)
		(width 0.18796)
		(layer "F.Cu")
		(net "THERMAL_ADDR_A2")
	)
	(via
		(at 34.798 -23.368)
		(size 0.508)
		(drill 0.254)
		(layers "F.Cu" "B.Cu")
		(net "THERMAL_ADDR_A2")
	)
	(via
		(at 32.385 -1.705864)
		(size 0.508)
		(drill 0.254)
		(layers "F.Cu" "B.Cu")
		(net "THERMAL_ADDR_A2")
	)
	(segment
		(start 27.347164 -14.190218)
		(end 27.76855 -14.611604)
		(width 0.18796)
		(layer "B.Cu")
		(net "THERMAL_ADDR_A2")
	)
	(segment
		(start 24.937974 -13.702792)
		(end 25.4254 -14.190218)
		(width 0.18796)
		(layer "B.Cu")
		(net "THERMAL_ADDR_A2")
	)
	(segment
		(start 27.76855 -14.611604)
		(end 27.76855 -18.105882)
		(width 0.18796)
		(layer "B.Cu")
		(net "THERMAL_ADDR_A2")
	)
	(segment
		(start 32.385 -1.705864)
		(end 24.937974 -9.15289)
		(width 0.18796)
		(layer "B.Cu")
		(net "THERMAL_ADDR_A2")
	)
	(segment
		(start 25.4254 -14.190218)
		(end 27.347164 -14.190218)
		(width 0.18796)
		(layer "B.Cu")
		(net "THERMAL_ADDR_A2")
	)
	(segment
		(start 24.937974 -9.15289)
		(end 24.937974 -13.702792)
		(width 0.18796)
		(layer "B.Cu")
		(net "THERMAL_ADDR_A2")
	)
	(segment
		(start 27.76855 -18.105882)
		(end 33.030668 -23.368)
		(width 0.18796)
		(layer "B.Cu")
		(net "THERMAL_ADDR_A2")
	)
	(segment
		(start 33.030668 -23.368)
		(end 34.798 -23.368)
		(width 0.18796)
		(layer "B.Cu")
		(net "THERMAL_ADDR_A2")
	)
	(segment
		(start 93.861382 -38.153848)
		(end 96.843088 -38.153848)
		(width 0.14732)
		(layer "F.Cu")
		(net "TDR_DIFF_85_TOP_DN")
	)
	(segment
		(start 96.843088 -30.823408)
		(end 93.861382 -30.823408)
		(width 0.14732)
		(layer "F.Cu")
		(net "TDR_DIFF_85_TOP_DN")
	)
	(segment
		(start 96.843088 -42.197528)
		(end 97.138998 -41.901618)
		(width 0.14732)
		(layer "F.Cu")
		(net "TDR_DIFF_85_TOP_DN")
	)
	(segment
		(start 96.843088 -44.976288)
		(end 93.861382 -44.976288)
		(width 0.14732)
		(layer "F.Cu")
		(net "TDR_DIFF_85_TOP_DN")
	)
	(segment
		(start 96.843088 -36.888928)
		(end 93.861382 -36.888928)
		(width 0.14732)
		(layer "F.Cu")
		(net "TDR_DIFF_85_TOP_DN")
	)
	(segment
		(start 93.61297 -28.654248)
		(end 93.61297 -28.191968)
		(width 0.14732)
		(layer "F.Cu")
		(net "TDR_DIFF_85_TOP_DN")
	)
	(segment
		(start 97.138998 -33.814258)
		(end 97.138998 -33.141158)
		(width 0.14732)
		(layer "F.Cu")
		(net "TDR_DIFF_85_TOP_DN")
	)
	(segment
		(start 93.714062 -38.763448)
		(end 93.714062 -38.301168)
		(width 0.14732)
		(layer "F.Cu")
		(net "TDR_DIFF_85_TOP_DN")
	)
	(segment
		(start 93.714062 -52.916328)
		(end 93.714062 -52.454048)
		(width 0.14732)
		(layer "F.Cu")
		(net "TDR_DIFF_85_TOP_DN")
	)
	(segment
		(start 93.861382 -50.284888)
		(end 96.843088 -50.284888)
		(width 0.14732)
		(layer "F.Cu")
		(net "TDR_DIFF_85_TOP_DN")
	)
	(segment
		(start 96.843088 -34.867088)
		(end 93.861382 -34.867088)
		(width 0.14732)
		(layer "F.Cu")
		(net "TDR_DIFF_85_TOP_DN")
	)
	(segment
		(start 97.138998 -47.294038)
		(end 96.843088 -46.998128)
		(width 0.14732)
		(layer "F.Cu")
		(net "TDR_DIFF_85_TOP_DN")
	)
	(segment
		(start 96.843088 -40.175688)
		(end 97.138998 -39.879778)
		(width 0.14732)
		(layer "F.Cu")
		(net "TDR_DIFF_85_TOP_DN")
	)
	(segment
		(start 97.138998 -29.770578)
		(end 97.138998 -29.097478)
		(width 0.14732)
		(layer "F.Cu")
		(net "TDR_DIFF_85_TOP_DN")
	)
	(segment
		(start 93.861382 -36.888928)
		(end 93.714062 -36.741608)
		(width 0.14732)
		(layer "F.Cu")
		(net "TDR_DIFF_85_TOP_DN")
	)
	(segment
		(start 97.138998 -54.032658)
		(end 97.138998 -53.359558)
		(width 0.14732)
		(layer "F.Cu")
		(net "TDR_DIFF_85_TOP_DN")
	)
	(segment
		(start 93.714062 -48.872648)
		(end 93.714062 -48.410368)
		(width 0.14732)
		(layer "F.Cu")
		(net "TDR_DIFF_85_TOP_DN")
	)
	(segment
		(start 93.76029 -28.044648)
		(end 96.843088 -28.044648)
		(width 0.14732)
		(layer "F.Cu")
		(net "TDR_DIFF_85_TOP_DN")
	)
	(segment
		(start 93.596206 -26.632408)
		(end 93.596206 -26.170128)
		(width 0.14732)
		(layer "F.Cu")
		(net "TDR_DIFF_85_TOP_DN")
	)
	(segment
		(start 93.714062 -56.497728)
		(end 93.861382 -56.350408)
		(width 0.14732)
		(layer "F.Cu")
		(net "TDR_DIFF_85_TOP_DN")
	)
	(segment
		(start 93.861382 -61.151008)
		(end 93.714062 -61.003688)
		(width 0.14732)
		(layer "F.Cu")
		(net "TDR_DIFF_85_TOP_DN")
	)
	(segment
		(start 93.861382 -60.394088)
		(end 96.843088 -60.394088)
		(width 0.14732)
		(layer "F.Cu")
		(net "TDR_DIFF_85_TOP_DN")
	)
	(segment
		(start 96.843088 -60.394088)
		(end 97.138998 -60.098178)
		(width 0.14732)
		(layer "F.Cu")
		(net "TDR_DIFF_85_TOP_DN")
	)
	(segment
		(start 93.714062 -54.475888)
		(end 93.861382 -54.328568)
		(width 0.14732)
		(layer "F.Cu")
		(net "TDR_DIFF_85_TOP_DN")
	)
	(segment
		(start 93.714062 -42.344848)
		(end 93.861382 -42.197528)
		(width 0.14732)
		(layer "F.Cu")
		(net "TDR_DIFF_85_TOP_DN")
	)
	(segment
		(start 93.714062 -34.257488)
		(end 93.861382 -34.110168)
		(width 0.14732)
		(layer "F.Cu")
		(net "TDR_DIFF_85_TOP_DN")
	)
	(segment
		(start 93.714062 -30.676088)
		(end 93.714062 -30.213808)
		(width 0.14732)
		(layer "F.Cu")
		(net "TDR_DIFF_85_TOP_DN")
	)
	(segment
		(start 97.138998 -27.748738)
		(end 97.138998 -27.075638)
		(width 0.14732)
		(layer "F.Cu")
		(net "TDR_DIFF_85_TOP_DN")
	)
	(segment
		(start 93.714062 -58.519568)
		(end 93.861382 -58.372248)
		(width 0.14732)
		(layer "F.Cu")
		(net "TDR_DIFF_85_TOP_DN")
	)
	(segment
		(start 93.714062 -48.410368)
		(end 93.861382 -48.263048)
		(width 0.14732)
		(layer "F.Cu")
		(net "TDR_DIFF_85_TOP_DN")
	)
	(segment
		(start 96.843088 -42.954448)
		(end 93.861382 -42.954448)
		(width 0.14732)
		(layer "F.Cu")
		(net "TDR_DIFF_85_TOP_DN")
	)
	(segment
		(start 93.663516 -32.235648)
		(end 93.810836 -32.088328)
		(width 0.14732)
		(layer "F.Cu")
		(net "TDR_DIFF_85_TOP_DN")
	)
	(segment
		(start 93.714062 -61.003688)
		(end 93.714062 -60.541408)
		(width 0.14732)
		(layer "F.Cu")
		(net "TDR_DIFF_85_TOP_DN")
	)
	(segment
		(start 97.138998 -39.879778)
		(end 97.138998 -39.206678)
		(width 0.14732)
		(layer "F.Cu")
		(net "TDR_DIFF_85_TOP_DN")
	)
	(segment
		(start 96.843088 -26.779728)
		(end 93.743526 -26.779728)
		(width 0.14732)
		(layer "F.Cu")
		(net "TDR_DIFF_85_TOP_DN")
	)
	(segment
		(start 95.57385 -23.622)
		(end 96.56953 -23.622)
		(width 0.14732)
		(layer "F.Cu")
		(net "TDR_DIFF_85_TOP_DN")
	)
	(segment
		(start 96.843088 -32.088328)
		(end 97.138998 -31.792418)
		(width 0.14732)
		(layer "F.Cu")
		(net "TDR_DIFF_85_TOP_DN")
	)
	(segment
		(start 97.138998 -51.337718)
		(end 96.843088 -51.041808)
		(width 0.14732)
		(layer "F.Cu")
		(net "TDR_DIFF_85_TOP_DN")
	)
	(segment
		(start 93.76029 -28.801568)
		(end 93.61297 -28.654248)
		(width 0.14732)
		(layer "F.Cu")
		(net "TDR_DIFF_85_TOP_DN")
	)
	(segment
		(start 96.843088 -44.219368)
		(end 97.138998 -43.923458)
		(width 0.14732)
		(layer "F.Cu")
		(net "TDR_DIFF_85_TOP_DN")
	)
	(segment
		(start 97.138998 -31.119318)
		(end 96.843088 -30.823408)
		(width 0.14732)
		(layer "F.Cu")
		(net "TDR_DIFF_85_TOP_DN")
	)
	(segment
		(start 97.138998 -52.010818)
		(end 97.138998 -51.337718)
		(width 0.14732)
		(layer "F.Cu")
		(net "TDR_DIFF_85_TOP_DN")
	)
	(segment
		(start 93.861382 -46.241208)
		(end 96.843088 -46.241208)
		(width 0.14732)
		(layer "F.Cu")
		(net "TDR_DIFF_85_TOP_DN")
	)
	(segment
		(start 93.861382 -44.976288)
		(end 93.714062 -44.828968)
		(width 0.14732)
		(layer "F.Cu")
		(net "TDR_DIFF_85_TOP_DN")
	)
	(segment
		(start 96.843088 -40.932608)
		(end 93.861382 -40.932608)
		(width 0.14732)
		(layer "F.Cu")
		(net "TDR_DIFF_85_TOP_DN")
	)
	(segment
		(start 96.843088 -32.845248)
		(end 93.810836 -32.845248)
		(width 0.14732)
		(layer "F.Cu")
		(net "TDR_DIFF_85_TOP_DN")
	)
	(segment
		(start 96.843088 -38.153848)
		(end 97.138998 -37.857938)
		(width 0.14732)
		(layer "F.Cu")
		(net "TDR_DIFF_85_TOP_DN")
	)
	(segment
		(start 97.138998 -49.315878)
		(end 96.843088 -49.019968)
		(width 0.14732)
		(layer "F.Cu")
		(net "TDR_DIFF_85_TOP_DN")
	)
	(segment
		(start 96.843088 -56.350408)
		(end 97.138998 -56.054498)
		(width 0.14732)
		(layer "F.Cu")
		(net "TDR_DIFF_85_TOP_DN")
	)
	(segment
		(start 93.861382 -34.867088)
		(end 93.714062 -34.719768)
		(width 0.14732)
		(layer "F.Cu")
		(net "TDR_DIFF_85_TOP_DN")
	)
	(segment
		(start 93.861382 -40.932608)
		(end 93.714062 -40.785288)
		(width 0.14732)
		(layer "F.Cu")
		(net "TDR_DIFF_85_TOP_DN")
	)
	(segment
		(start 93.861382 -53.063648)
		(end 93.714062 -52.916328)
		(width 0.14732)
		(layer "F.Cu")
		(net "TDR_DIFF_85_TOP_DN")
	)
	(segment
		(start 93.861382 -40.175688)
		(end 96.843088 -40.175688)
		(width 0.14732)
		(layer "F.Cu")
		(net "TDR_DIFF_85_TOP_DN")
	)
	(segment
		(start 97.138998 -39.206678)
		(end 96.843088 -38.910768)
		(width 0.14732)
		(layer "F.Cu")
		(net "TDR_DIFF_85_TOP_DN")
	)
	(segment
		(start 93.861382 -36.132008)
		(end 96.843088 -36.132008)
		(width 0.14732)
		(layer "F.Cu")
		(net "TDR_DIFF_85_TOP_DN")
	)
	(segment
		(start 93.714062 -30.213808)
		(end 93.861382 -30.066488)
		(width 0.14732)
		(layer "F.Cu")
		(net "TDR_DIFF_85_TOP_DN")
	)
	(segment
		(start 93.663516 -32.697928)
		(end 93.663516 -32.235648)
		(width 0.14732)
		(layer "F.Cu")
		(net "TDR_DIFF_85_TOP_DN")
	)
	(segment
		(start 96.843088 -51.041808)
		(end 93.861382 -51.041808)
		(width 0.14732)
		(layer "F.Cu")
		(net "TDR_DIFF_85_TOP_DN")
	)
	(segment
		(start 97.138998 -60.098178)
		(end 97.138998 -59.425078)
		(width 0.14732)
		(layer "F.Cu")
		(net "TDR_DIFF_85_TOP_DN")
	)
	(segment
		(start 93.861382 -44.219368)
		(end 96.843088 -44.219368)
		(width 0.14732)
		(layer "F.Cu")
		(net "TDR_DIFF_85_TOP_DN")
	)
	(segment
		(start 95.42653 -62.747652)
		(end 95.42653 -61.446918)
		(width 0.14732)
		(layer "F.Cu")
		(net "TDR_DIFF_85_TOP_DN")
	)
	(segment
		(start 93.861382 -55.085488)
		(end 93.714062 -54.938168)
		(width 0.14732)
		(layer "F.Cu")
		(net "TDR_DIFF_85_TOP_DN")
	)
	(segment
		(start 93.714062 -56.960008)
		(end 93.714062 -56.497728)
		(width 0.14732)
		(layer "F.Cu")
		(net "TDR_DIFF_85_TOP_DN")
	)
	(segment
		(start 96.843088 -58.372248)
		(end 97.138998 -58.076338)
		(width 0.14732)
		(layer "F.Cu")
		(net "TDR_DIFF_85_TOP_DN")
	)
	(segment
		(start 96.843088 -55.085488)
		(end 93.861382 -55.085488)
		(width 0.14732)
		(layer "F.Cu")
		(net "TDR_DIFF_85_TOP_DN")
	)
	(segment
		(start 93.861382 -42.954448)
		(end 93.714062 -42.807128)
		(width 0.14732)
		(layer "F.Cu")
		(net "TDR_DIFF_85_TOP_DN")
	)
	(segment
		(start 93.861382 -30.066488)
		(end 96.843088 -30.066488)
		(width 0.14732)
		(layer "F.Cu")
		(net "TDR_DIFF_85_TOP_DN")
	)
	(segment
		(start 97.138998 -57.403238)
		(end 96.843088 -57.107328)
		(width 0.14732)
		(layer "F.Cu")
		(net "TDR_DIFF_85_TOP_DN")
	)
	(segment
		(start 93.714062 -58.981848)
		(end 93.714062 -58.519568)
		(width 0.14732)
		(layer "F.Cu")
		(net "TDR_DIFF_85_TOP_DN")
	)
	(segment
		(start 96.843088 -28.044648)
		(end 97.138998 -27.748738)
		(width 0.14732)
		(layer "F.Cu")
		(net "TDR_DIFF_85_TOP_DN")
	)
	(segment
		(start 96.843088 -53.063648)
		(end 93.861382 -53.063648)
		(width 0.14732)
		(layer "F.Cu")
		(net "TDR_DIFF_85_TOP_DN")
	)
	(segment
		(start 97.138998 -47.967138)
		(end 97.138998 -47.294038)
		(width 0.14732)
		(layer "F.Cu")
		(net "TDR_DIFF_85_TOP_DN")
	)
	(segment
		(start 97.138998 -45.945298)
		(end 97.138998 -45.272198)
		(width 0.14732)
		(layer "F.Cu")
		(net "TDR_DIFF_85_TOP_DN")
	)
	(segment
		(start 95.42653 -61.446918)
		(end 95.13062 -61.151008)
		(width 0.14732)
		(layer "F.Cu")
		(net "TDR_DIFF_85_TOP_DN")
	)
	(segment
		(start 93.810836 -32.845248)
		(end 93.663516 -32.697928)
		(width 0.14732)
		(layer "F.Cu")
		(net "TDR_DIFF_85_TOP_DN")
	)
	(segment
		(start 93.714062 -50.894488)
		(end 93.714062 -50.432208)
		(width 0.14732)
		(layer "F.Cu")
		(net "TDR_DIFF_85_TOP_DN")
	)
	(segment
		(start 93.861382 -49.019968)
		(end 93.714062 -48.872648)
		(width 0.14732)
		(layer "F.Cu")
		(net "TDR_DIFF_85_TOP_DN")
	)
	(segment
		(start 96.843088 -50.284888)
		(end 97.138998 -49.988978)
		(width 0.14732)
		(layer "F.Cu")
		(net "TDR_DIFF_85_TOP_DN")
	)
	(segment
		(start 93.61297 -28.191968)
		(end 93.76029 -28.044648)
		(width 0.14732)
		(layer "F.Cu")
		(net "TDR_DIFF_85_TOP_DN")
	)
	(segment
		(start 93.861382 -38.910768)
		(end 93.714062 -38.763448)
		(width 0.14732)
		(layer "F.Cu")
		(net "TDR_DIFF_85_TOP_DN")
	)
	(segment
		(start 95.42653 -23.76932)
		(end 95.57385 -23.622)
		(width 0.14732)
		(layer "F.Cu")
		(net "TDR_DIFF_85_TOP_DN")
	)
	(segment
		(start 93.714062 -44.828968)
		(end 93.714062 -44.366688)
		(width 0.14732)
		(layer "F.Cu")
		(net "TDR_DIFF_85_TOP_DN")
	)
	(segment
		(start 96.843088 -46.998128)
		(end 93.861382 -46.998128)
		(width 0.14732)
		(layer "F.Cu")
		(net "TDR_DIFF_85_TOP_DN")
	)
	(segment
		(start 93.861382 -58.372248)
		(end 96.843088 -58.372248)
		(width 0.14732)
		(layer "F.Cu")
		(net "TDR_DIFF_85_TOP_DN")
	)
	(segment
		(start 93.861382 -34.110168)
		(end 96.843088 -34.110168)
		(width 0.14732)
		(layer "F.Cu")
		(net "TDR_DIFF_85_TOP_DN")
	)
	(segment
		(start 93.743526 -26.022808)
		(end 95.13062 -26.022808)
		(width 0.14732)
		(layer "F.Cu")
		(net "TDR_DIFF_85_TOP_DN")
	)
	(segment
		(start 96.843088 -52.306728)
		(end 97.138998 -52.010818)
		(width 0.14732)
		(layer "F.Cu")
		(net "TDR_DIFF_85_TOP_DN")
	)
	(segment
		(start 95.13062 -26.022808)
		(end 95.42653 -25.726898)
		(width 0.14732)
		(layer "F.Cu")
		(net "TDR_DIFF_85_TOP_DN")
	)
	(segment
		(start 93.596206 -26.170128)
		(end 93.743526 -26.022808)
		(width 0.14732)
		(layer "F.Cu")
		(net "TDR_DIFF_85_TOP_DN")
	)
	(segment
		(start 96.843088 -54.328568)
		(end 97.138998 -54.032658)
		(width 0.14732)
		(layer "F.Cu")
		(net "TDR_DIFF_85_TOP_DN")
	)
	(segment
		(start 97.138998 -41.901618)
		(end 97.138998 -41.228518)
		(width 0.14732)
		(layer "F.Cu")
		(net "TDR_DIFF_85_TOP_DN")
	)
	(segment
		(start 97.138998 -27.075638)
		(end 96.843088 -26.779728)
		(width 0.14732)
		(layer "F.Cu")
		(net "TDR_DIFF_85_TOP_DN")
	)
	(segment
		(start 95.42653 -25.726898)
		(end 95.42653 -23.76932)
		(width 0.14732)
		(layer "F.Cu")
		(net "TDR_DIFF_85_TOP_DN")
	)
	(segment
		(start 93.714062 -36.279328)
		(end 93.861382 -36.132008)
		(width 0.14732)
		(layer "F.Cu")
		(net "TDR_DIFF_85_TOP_DN")
	)
	(segment
		(start 93.714062 -52.454048)
		(end 93.861382 -52.306728)
		(width 0.14732)
		(layer "F.Cu")
		(net "TDR_DIFF_85_TOP_DN")
	)
	(segment
		(start 97.138998 -37.857938)
		(end 97.138998 -37.184838)
		(width 0.14732)
		(layer "F.Cu")
		(net "TDR_DIFF_85_TOP_DN")
	)
	(segment
		(start 95.13062 -61.151008)
		(end 93.861382 -61.151008)
		(width 0.14732)
		(layer "F.Cu")
		(net "TDR_DIFF_85_TOP_DN")
	)
	(segment
		(start 93.714062 -46.850808)
		(end 93.714062 -46.388528)
		(width 0.14732)
		(layer "F.Cu")
		(net "TDR_DIFF_85_TOP_DN")
	)
	(segment
		(start 96.843088 -30.066488)
		(end 97.138998 -29.770578)
		(width 0.14732)
		(layer "F.Cu")
		(net "TDR_DIFF_85_TOP_DN")
	)
	(segment
		(start 97.138998 -58.076338)
		(end 97.138998 -57.403238)
		(width 0.14732)
		(layer "F.Cu")
		(net "TDR_DIFF_85_TOP_DN")
	)
	(segment
		(start 93.861382 -56.350408)
		(end 96.843088 -56.350408)
		(width 0.14732)
		(layer "F.Cu")
		(net "TDR_DIFF_85_TOP_DN")
	)
	(segment
		(start 93.714062 -34.719768)
		(end 93.714062 -34.257488)
		(width 0.14732)
		(layer "F.Cu")
		(net "TDR_DIFF_85_TOP_DN")
	)
	(segment
		(start 96.843088 -34.110168)
		(end 97.138998 -33.814258)
		(width 0.14732)
		(layer "F.Cu")
		(net "TDR_DIFF_85_TOP_DN")
	)
	(segment
		(start 93.714062 -44.366688)
		(end 93.861382 -44.219368)
		(width 0.14732)
		(layer "F.Cu")
		(net "TDR_DIFF_85_TOP_DN")
	)
	(segment
		(start 96.843088 -57.107328)
		(end 93.861382 -57.107328)
		(width 0.14732)
		(layer "F.Cu")
		(net "TDR_DIFF_85_TOP_DN")
	)
	(segment
		(start 97.138998 -35.836098)
		(end 97.138998 -35.162998)
		(width 0.14732)
		(layer "F.Cu")
		(net "TDR_DIFF_85_TOP_DN")
	)
	(segment
		(start 96.843088 -48.263048)
		(end 97.138998 -47.967138)
		(width 0.14732)
		(layer "F.Cu")
		(net "TDR_DIFF_85_TOP_DN")
	)
	(segment
		(start 93.861382 -54.328568)
		(end 96.843088 -54.328568)
		(width 0.14732)
		(layer "F.Cu")
		(net "TDR_DIFF_85_TOP_DN")
	)
	(segment
		(start 93.861382 -59.129168)
		(end 93.714062 -58.981848)
		(width 0.14732)
		(layer "F.Cu")
		(net "TDR_DIFF_85_TOP_DN")
	)
	(segment
		(start 93.714062 -36.741608)
		(end 93.714062 -36.279328)
		(width 0.14732)
		(layer "F.Cu")
		(net "TDR_DIFF_85_TOP_DN")
	)
	(segment
		(start 97.138998 -56.054498)
		(end 97.138998 -55.381398)
		(width 0.14732)
		(layer "F.Cu")
		(net "TDR_DIFF_85_TOP_DN")
	)
	(segment
		(start 93.714062 -60.541408)
		(end 93.861382 -60.394088)
		(width 0.14732)
		(layer "F.Cu")
		(net "TDR_DIFF_85_TOP_DN")
	)
	(segment
		(start 97.138998 -43.250358)
		(end 96.843088 -42.954448)
		(width 0.14732)
		(layer "F.Cu")
		(net "TDR_DIFF_85_TOP_DN")
	)
	(segment
		(start 93.861382 -30.823408)
		(end 93.714062 -30.676088)
		(width 0.14732)
		(layer "F.Cu")
		(net "TDR_DIFF_85_TOP_DN")
	)
	(segment
		(start 96.843088 -28.801568)
		(end 93.76029 -28.801568)
		(width 0.14732)
		(layer "F.Cu")
		(net "TDR_DIFF_85_TOP_DN")
	)
	(segment
		(start 97.138998 -55.381398)
		(end 96.843088 -55.085488)
		(width 0.14732)
		(layer "F.Cu")
		(net "TDR_DIFF_85_TOP_DN")
	)
	(segment
		(start 93.810836 -32.088328)
		(end 96.843088 -32.088328)
		(width 0.14732)
		(layer "F.Cu")
		(net "TDR_DIFF_85_TOP_DN")
	)
	(segment
		(start 96.843088 -36.132008)
		(end 97.138998 -35.836098)
		(width 0.14732)
		(layer "F.Cu")
		(net "TDR_DIFF_85_TOP_DN")
	)
	(segment
		(start 93.743526 -26.779728)
		(end 93.596206 -26.632408)
		(width 0.14732)
		(layer "F.Cu")
		(net "TDR_DIFF_85_TOP_DN")
	)
	(segment
		(start 97.138998 -33.141158)
		(end 96.843088 -32.845248)
		(width 0.14732)
		(layer "F.Cu")
		(net "TDR_DIFF_85_TOP_DN")
	)
	(segment
		(start 97.138998 -37.184838)
		(end 96.843088 -36.888928)
		(width 0.14732)
		(layer "F.Cu")
		(net "TDR_DIFF_85_TOP_DN")
	)
	(segment
		(start 97.138998 -43.923458)
		(end 97.138998 -43.250358)
		(width 0.14732)
		(layer "F.Cu")
		(net "TDR_DIFF_85_TOP_DN")
	)
	(segment
		(start 97.138998 -31.792418)
		(end 97.138998 -31.119318)
		(width 0.14732)
		(layer "F.Cu")
		(net "TDR_DIFF_85_TOP_DN")
	)
	(segment
		(start 93.861382 -48.263048)
		(end 96.843088 -48.263048)
		(width 0.14732)
		(layer "F.Cu")
		(net "TDR_DIFF_85_TOP_DN")
	)
	(segment
		(start 97.138998 -53.359558)
		(end 96.843088 -53.063648)
		(width 0.14732)
		(layer "F.Cu")
		(net "TDR_DIFF_85_TOP_DN")
	)
	(segment
		(start 96.843088 -46.241208)
		(end 97.138998 -45.945298)
		(width 0.14732)
		(layer "F.Cu")
		(net "TDR_DIFF_85_TOP_DN")
	)
	(segment
		(start 95.57385 -62.894972)
		(end 95.42653 -62.747652)
		(width 0.14732)
		(layer "F.Cu")
		(net "TDR_DIFF_85_TOP_DN")
	)
	(segment
		(start 97.138998 -29.097478)
		(end 96.843088 -28.801568)
		(width 0.14732)
		(layer "F.Cu")
		(net "TDR_DIFF_85_TOP_DN")
	)
	(segment
		(start 97.138998 -45.272198)
		(end 96.843088 -44.976288)
		(width 0.14732)
		(layer "F.Cu")
		(net "TDR_DIFF_85_TOP_DN")
	)
	(segment
		(start 97.138998 -59.425078)
		(end 96.843088 -59.129168)
		(width 0.14732)
		(layer "F.Cu")
		(net "TDR_DIFF_85_TOP_DN")
	)
	(segment
		(start 96.843088 -49.019968)
		(end 93.861382 -49.019968)
		(width 0.14732)
		(layer "F.Cu")
		(net "TDR_DIFF_85_TOP_DN")
	)
	(segment
		(start 93.714062 -40.785288)
		(end 93.714062 -40.323008)
		(width 0.14732)
		(layer "F.Cu")
		(net "TDR_DIFF_85_TOP_DN")
	)
	(segment
		(start 93.714062 -46.388528)
		(end 93.861382 -46.241208)
		(width 0.14732)
		(layer "F.Cu")
		(net "TDR_DIFF_85_TOP_DN")
	)
	(segment
		(start 96.843088 -59.129168)
		(end 93.861382 -59.129168)
		(width 0.14732)
		(layer "F.Cu")
		(net "TDR_DIFF_85_TOP_DN")
	)
	(segment
		(start 93.714062 -38.301168)
		(end 93.861382 -38.153848)
		(width 0.14732)
		(layer "F.Cu")
		(net "TDR_DIFF_85_TOP_DN")
	)
	(segment
		(start 93.861382 -51.041808)
		(end 93.714062 -50.894488)
		(width 0.14732)
		(layer "F.Cu")
		(net "TDR_DIFF_85_TOP_DN")
	)
	(segment
		(start 96.843088 -38.910768)
		(end 93.861382 -38.910768)
		(width 0.14732)
		(layer "F.Cu")
		(net "TDR_DIFF_85_TOP_DN")
	)
	(segment
		(start 93.861382 -52.306728)
		(end 96.843088 -52.306728)
		(width 0.14732)
		(layer "F.Cu")
		(net "TDR_DIFF_85_TOP_DN")
	)
	(segment
		(start 97.138998 -49.988978)
		(end 97.138998 -49.315878)
		(width 0.14732)
		(layer "F.Cu")
		(net "TDR_DIFF_85_TOP_DN")
	)
	(segment
		(start 93.714062 -40.323008)
		(end 93.861382 -40.175688)
		(width 0.14732)
		(layer "F.Cu")
		(net "TDR_DIFF_85_TOP_DN")
	)
	(segment
		(start 97.138998 -41.228518)
		(end 96.843088 -40.932608)
		(width 0.14732)
		(layer "F.Cu")
		(net "TDR_DIFF_85_TOP_DN")
	)
	(segment
		(start 93.714062 -54.938168)
		(end 93.714062 -54.475888)
		(width 0.14732)
		(layer "F.Cu")
		(net "TDR_DIFF_85_TOP_DN")
	)
	(segment
		(start 93.714062 -42.807128)
		(end 93.714062 -42.344848)
		(width 0.14732)
		(layer "F.Cu")
		(net "TDR_DIFF_85_TOP_DN")
	)
	(segment
		(start 93.861382 -57.107328)
		(end 93.714062 -56.960008)
		(width 0.14732)
		(layer "F.Cu")
		(net "TDR_DIFF_85_TOP_DN")
	)
	(segment
		(start 97.138998 -35.162998)
		(end 96.843088 -34.867088)
		(width 0.14732)
		(layer "F.Cu")
		(net "TDR_DIFF_85_TOP_DN")
	)
	(segment
		(start 93.861382 -42.197528)
		(end 96.843088 -42.197528)
		(width 0.14732)
		(layer "F.Cu")
		(net "TDR_DIFF_85_TOP_DN")
	)
	(segment
		(start 96.56953 -62.894972)
		(end 95.57385 -62.894972)
		(width 0.14732)
		(layer "F.Cu")
		(net "TDR_DIFF_85_TOP_DN")
	)
	(segment
		(start 93.714062 -50.432208)
		(end 93.861382 -50.284888)
		(width 0.14732)
		(layer "F.Cu")
		(net "TDR_DIFF_85_TOP_DN")
	)
	(segment
		(start 93.861382 -46.998128)
		(end 93.714062 -46.850808)
		(width 0.14732)
		(layer "F.Cu")
		(net "TDR_DIFF_85_TOP_DN")
	)
	(segment
		(start 24.100028 -20.830032)
		(end 24.638 -21.368004)
		(width 0.7112)
		(layer "F.Cu")
		(net "P5V_STBY_DEBUG")
	)
	(segment
		(start 30.609794 -18.712942)
		(end 30.609794 -19.213576)
		(width 0.508)
		(layer "F.Cu")
		(net "P5V_STBY_DEBUG")
	)
	(segment
		(start 27.17038 -16.720058)
		(end 28.61691 -16.720058)
		(width 0.508)
		(layer "F.Cu")
		(net "P5V_STBY_DEBUG")
	)
	(segment
		(start 21.700998 -18.431002)
		(end 24.100028 -20.830032)
		(width 0.7112)
		(layer "F.Cu")
		(net "P5V_STBY_DEBUG")
	)
	(segment
		(start 27.17038 -17.355058)
		(end 27.17038 -16.720058)
		(width 0.508)
		(layer "F.Cu")
		(net "P5V_STBY_DEBUG")
	)
	(segment
		(start 24.638 -21.368004)
		(end 24.638 -24.741378)
		(width 0.7112)
		(layer "F.Cu")
		(net "P5V_STBY_DEBUG")
	)
	(segment
		(start 23.003002 -26.376376)
		(end 23.003002 -27.11704)
		(width 0.7112)
		(layer "F.Cu")
		(net "P5V_STBY_DEBUG")
	)
	(segment
		(start 28.61691 -16.720058)
		(end 30.609794 -18.712942)
		(width 0.508)
		(layer "F.Cu")
		(net "P5V_STBY_DEBUG")
	)
	(segment
		(start 19.87296 -18.431002)
		(end 21.700998 -18.431002)
		(width 0.7112)
		(layer "F.Cu")
		(net "P5V_STBY_DEBUG")
	)
	(segment
		(start 24.638 -24.741378)
		(end 23.003002 -26.376376)
		(width 0.7112)
		(layer "F.Cu")
		(net "P5V_STBY_DEBUG")
	)
	(via
		(at 34.163 -30.226)
		(size 0.508)
		(drill 0.254)
		(layers "F.Cu" "B.Cu")
		(net "P5V_STBY_DEBUG")
	)
	(via
		(at 24.892 -25.146)
		(size 0.6604)
		(drill 0.3302)
		(layers "F.Cu" "B.Cu")
		(net "P5V_STBY_DEBUG")
	)
	(via
		(at 34.163 -33.782)
		(size 0.508)
		(drill 0.254)
		(layers "F.Cu" "B.Cu")
		(net "P5V_STBY_DEBUG")
	)
	(via
		(at 34.163 -26.67)
		(size 0.6604)
		(drill 0.3302)
		(layers "F.Cu" "B.Cu")
		(net "P5V_STBY_DEBUG")
	)
	(via
		(at 29.718 -31.115)
		(size 0.6604)
		(drill 0.3302)
		(layers "F.Cu" "B.Cu")
		(net "P5V_STBY_DEBUG")
	)
	(via
		(at 27.17038 -16.720058)
		(size 0.508)
		(drill 0.254)
		(layers "F.Cu" "B.Cu")
		(net "P5V_STBY_DEBUG")
	)
	(via
		(at 34.163 -34.671)
		(size 0.508)
		(drill 0.254)
		(layers "F.Cu" "B.Cu")
		(net "P5V_STBY_DEBUG")
	)
	(via
		(at 34.163 -32.893)
		(size 0.508)
		(drill 0.254)
		(layers "F.Cu" "B.Cu")
		(net "P5V_STBY_DEBUG")
	)
	(via
		(at 34.163 -32.004)
		(size 0.508)
		(drill 0.254)
		(layers "F.Cu" "B.Cu")
		(net "P5V_STBY_DEBUG")
	)
	(via
		(at 34.163 -31.115)
		(size 0.508)
		(drill 0.254)
		(layers "F.Cu" "B.Cu")
		(net "P5V_STBY_DEBUG")
	)
	(via
		(at 27.17038 -17.355058)
		(size 0.508)
		(drill 0.254)
		(layers "F.Cu" "B.Cu")
		(net "P5V_STBY_DEBUG")
	)
	(segment
		(start 90.4494 -44.04868)
		(end 90.63736 -44.23664)
		(width 0.18796)
		(layer "B.Cu")
		(net "TDR_SE_50_OHM_BOT")
	)
	(segment
		(start 90.723974 -31.89732)
		(end 90.536014 -32.08528)
		(width 0.18796)
		(layer "B.Cu")
		(net "TDR_SE_50_OHM_BOT")
	)
	(segment
		(start 90.4494 -40.85844)
		(end 90.63736 -41.0464)
		(width 0.18796)
		(layer "B.Cu")
		(net "TDR_SE_50_OHM_BOT")
	)
	(segment
		(start 87.318596 -44.84624)
		(end 87.130636 -45.0342)
		(width 0.18796)
		(layer "B.Cu")
		(net "TDR_SE_50_OHM_BOT")
	)
	(segment
		(start 90.63736 -47.84852)
		(end 90.4494 -48.03648)
		(width 0.18796)
		(layer "B.Cu")
		(net "TDR_SE_50_OHM_BOT")
	)
	(segment
		(start 90.536014 -32.08528)
		(end 87.318596 -32.08528)
		(width 0.18796)
		(layer "B.Cu")
		(net "TDR_SE_50_OHM_BOT")
	)
	(segment
		(start 90.715338 -52.63388)
		(end 90.527378 -52.82184)
		(width 0.18796)
		(layer "B.Cu")
		(net "TDR_SE_50_OHM_BOT")
	)
	(segment
		(start 90.63736 -42.64152)
		(end 90.63736 -43.06316)
		(width 0.18796)
		(layer "B.Cu")
		(net "TDR_SE_50_OHM_BOT")
	)
	(segment
		(start 90.63736 -36.68268)
		(end 90.4494 -36.87064)
		(width 0.18796)
		(layer "B.Cu")
		(net "TDR_SE_50_OHM_BOT")
	)
	(segment
		(start 90.63736 -35.08756)
		(end 90.4494 -35.27552)
		(width 0.18796)
		(layer "B.Cu")
		(net "TDR_SE_50_OHM_BOT")
	)
	(segment
		(start 87.318596 -32.08528)
		(end 87.130636 -32.27324)
		(width 0.18796)
		(layer "B.Cu")
		(net "TDR_SE_50_OHM_BOT")
	)
	(segment
		(start 87.130636 -32.69488)
		(end 87.318596 -32.88284)
		(width 0.18796)
		(layer "B.Cu")
		(net "TDR_SE_50_OHM_BOT")
	)
	(segment
		(start 87.318596 -38.46576)
		(end 87.130636 -38.65372)
		(width 0.18796)
		(layer "B.Cu")
		(net "TDR_SE_50_OHM_BOT")
	)
	(segment
		(start 90.4494 -51.22672)
		(end 87.318596 -51.22672)
		(width 0.18796)
		(layer "B.Cu")
		(net "TDR_SE_50_OHM_BOT")
	)
	(segment
		(start 87.130636 -48.22444)
		(end 87.130636 -48.64608)
		(width 0.18796)
		(layer "B.Cu")
		(net "TDR_SE_50_OHM_BOT")
	)
	(segment
		(start 86.343998 -55.451756)
		(end 86.343998 -26.647648)
		(width 0.18796)
		(layer "B.Cu")
		(net "TDR_SE_50_OHM_BOT")
	)
	(segment
		(start 87.318596 -43.25112)
		(end 87.130636 -43.43908)
		(width 0.18796)
		(layer "B.Cu")
		(net "TDR_SE_50_OHM_BOT")
	)
	(segment
		(start 90.4494 -43.25112)
		(end 87.318596 -43.25112)
		(width 0.18796)
		(layer "B.Cu")
		(net "TDR_SE_50_OHM_BOT")
	)
	(segment
		(start 90.63736 -38.2778)
		(end 90.4494 -38.46576)
		(width 0.18796)
		(layer "B.Cu")
		(net "TDR_SE_50_OHM_BOT")
	)
	(segment
		(start 90.4494 -34.47796)
		(end 90.63736 -34.66592)
		(width 0.18796)
		(layer "B.Cu")
		(net "TDR_SE_50_OHM_BOT")
	)
	(segment
		(start 90.63736 -45.83176)
		(end 90.63736 -46.2534)
		(width 0.18796)
		(layer "B.Cu")
		(net "TDR_SE_50_OHM_BOT")
	)
	(segment
		(start 88.883998 -55.466234)
		(end 88.710516 -55.639716)
		(width 0.18796)
		(layer "B.Cu")
		(net "TDR_SE_50_OHM_BOT")
	)
	(segment
		(start 87.130636 -53.0098)
		(end 87.130636 -53.43144)
		(width 0.18796)
		(layer "B.Cu")
		(net "TDR_SE_50_OHM_BOT")
	)
	(segment
		(start 90.4494 -33.6804)
		(end 87.318596 -33.6804)
		(width 0.18796)
		(layer "B.Cu")
		(net "TDR_SE_50_OHM_BOT")
	)
	(segment
		(start 87.130636 -40.67048)
		(end 87.318596 -40.85844)
		(width 0.18796)
		(layer "B.Cu")
		(net "TDR_SE_50_OHM_BOT")
	)
	(segment
		(start 90.63736 -49.022)
		(end 90.63736 -49.44364)
		(width 0.18796)
		(layer "B.Cu")
		(net "TDR_SE_50_OHM_BOT")
	)
	(segment
		(start 90.63736 -39.45128)
		(end 90.63736 -39.87292)
		(width 0.18796)
		(layer "B.Cu")
		(net "TDR_SE_50_OHM_BOT")
	)
	(segment
		(start 86.531958 -55.639716)
		(end 86.343998 -55.451756)
		(width 0.18796)
		(layer "B.Cu")
		(net "TDR_SE_50_OHM_BOT")
	)
	(segment
		(start 90.4494 -36.07308)
		(end 90.63736 -36.26104)
		(width 0.18796)
		(layer "B.Cu")
		(net "TDR_SE_50_OHM_BOT")
	)
	(segment
		(start 87.130636 -40.24884)
		(end 87.130636 -40.67048)
		(width 0.18796)
		(layer "B.Cu")
		(net "TDR_SE_50_OHM_BOT")
	)
	(segment
		(start 87.318596 -50.42916)
		(end 90.4494 -50.42916)
		(width 0.18796)
		(layer "B.Cu")
		(net "TDR_SE_50_OHM_BOT")
	)
	(segment
		(start 90.4494 -48.03648)
		(end 87.318596 -48.03648)
		(width 0.18796)
		(layer "B.Cu")
		(net "TDR_SE_50_OHM_BOT")
	)
	(segment
		(start 87.130636 -37.48024)
		(end 87.318596 -37.6682)
		(width 0.18796)
		(layer "B.Cu")
		(net "TDR_SE_50_OHM_BOT")
	)
	(segment
		(start 90.4494 -44.84624)
		(end 87.318596 -44.84624)
		(width 0.18796)
		(layer "B.Cu")
		(net "TDR_SE_50_OHM_BOT")
	)
	(segment
		(start 87.130636 -43.43908)
		(end 87.130636 -43.86072)
		(width 0.18796)
		(layer "B.Cu")
		(net "TDR_SE_50_OHM_BOT")
	)
	(segment
		(start 90.4494 -41.656)
		(end 87.318596 -41.656)
		(width 0.18796)
		(layer "B.Cu")
		(net "TDR_SE_50_OHM_BOT")
	)
	(segment
		(start 87.130636 -35.46348)
		(end 87.130636 -35.88512)
		(width 0.18796)
		(layer "B.Cu")
		(net "TDR_SE_50_OHM_BOT")
	)
	(segment
		(start 90.4494 -42.45356)
		(end 90.63736 -42.64152)
		(width 0.18796)
		(layer "B.Cu")
		(net "TDR_SE_50_OHM_BOT")
	)
	(segment
		(start 89.071958 -31.28772)
		(end 90.536014 -31.28772)
		(width 0.18796)
		(layer "B.Cu")
		(net "TDR_SE_50_OHM_BOT")
	)
	(segment
		(start 90.63736 -49.44364)
		(end 90.4494 -49.6316)
		(width 0.18796)
		(layer "B.Cu")
		(net "TDR_SE_50_OHM_BOT")
	)
	(segment
		(start 87.130636 -46.62932)
		(end 87.130636 -47.05096)
		(width 0.18796)
		(layer "B.Cu")
		(net "TDR_SE_50_OHM_BOT")
	)
	(segment
		(start 88.883998 -53.80736)
		(end 88.883998 -55.466234)
		(width 0.18796)
		(layer "B.Cu")
		(net "TDR_SE_50_OHM_BOT")
	)
	(segment
		(start 87.318596 -48.03648)
		(end 87.130636 -48.22444)
		(width 0.18796)
		(layer "B.Cu")
		(net "TDR_SE_50_OHM_BOT")
	)
	(segment
		(start 87.130636 -49.81956)
		(end 87.130636 -50.2412)
		(width 0.18796)
		(layer "B.Cu")
		(net "TDR_SE_50_OHM_BOT")
	)
	(segment
		(start 87.130636 -42.2656)
		(end 87.318596 -42.45356)
		(width 0.18796)
		(layer "B.Cu")
		(net "TDR_SE_50_OHM_BOT")
	)
	(segment
		(start 87.130636 -50.2412)
		(end 87.318596 -50.42916)
		(width 0.18796)
		(layer "B.Cu")
		(net "TDR_SE_50_OHM_BOT")
	)
	(segment
		(start 87.318596 -32.88284)
		(end 90.4494 -32.88284)
		(width 0.18796)
		(layer "B.Cu")
		(net "TDR_SE_50_OHM_BOT")
	)
	(segment
		(start 90.4494 -37.6682)
		(end 90.63736 -37.85616)
		(width 0.18796)
		(layer "B.Cu")
		(net "TDR_SE_50_OHM_BOT")
	)
	(segment
		(start 87.318596 -44.04868)
		(end 90.4494 -44.04868)
		(width 0.18796)
		(layer "B.Cu")
		(net "TDR_SE_50_OHM_BOT")
	)
	(segment
		(start 90.4494 -47.23892)
		(end 90.63736 -47.42688)
		(width 0.18796)
		(layer "B.Cu")
		(net "TDR_SE_50_OHM_BOT")
	)
	(segment
		(start 90.723974 -31.47568)
		(end 90.723974 -31.89732)
		(width 0.18796)
		(layer "B.Cu")
		(net "TDR_SE_50_OHM_BOT")
	)
	(segment
		(start 90.63736 -47.42688)
		(end 90.63736 -47.84852)
		(width 0.18796)
		(layer "B.Cu")
		(net "TDR_SE_50_OHM_BOT")
	)
	(segment
		(start 87.318596 -48.83404)
		(end 90.4494 -48.83404)
		(width 0.18796)
		(layer "B.Cu")
		(net "TDR_SE_50_OHM_BOT")
	)
	(segment
		(start 88.883998 -31.09976)
		(end 89.071958 -31.28772)
		(width 0.18796)
		(layer "B.Cu")
		(net "TDR_SE_50_OHM_BOT")
	)
	(segment
		(start 90.63736 -39.87292)
		(end 90.4494 -40.06088)
		(width 0.18796)
		(layer "B.Cu")
		(net "TDR_SE_50_OHM_BOT")
	)
	(segment
		(start 87.318596 -52.02428)
		(end 90.527378 -52.02428)
		(width 0.18796)
		(layer "B.Cu")
		(net "TDR_SE_50_OHM_BOT")
	)
	(segment
		(start 90.536014 -31.28772)
		(end 90.723974 -31.47568)
		(width 0.18796)
		(layer "B.Cu")
		(net "TDR_SE_50_OHM_BOT")
	)
	(segment
		(start 87.130636 -51.41468)
		(end 87.130636 -51.83632)
		(width 0.18796)
		(layer "B.Cu")
		(net "TDR_SE_50_OHM_BOT")
	)
	(segment
		(start 90.63736 -36.26104)
		(end 90.63736 -36.68268)
		(width 0.18796)
		(layer "B.Cu")
		(net "TDR_SE_50_OHM_BOT")
	)
	(segment
		(start 87.130636 -45.0342)
		(end 87.130636 -45.45584)
		(width 0.18796)
		(layer "B.Cu")
		(net "TDR_SE_50_OHM_BOT")
	)
	(segment
		(start 87.130636 -53.43144)
		(end 87.318596 -53.6194)
		(width 0.18796)
		(layer "B.Cu")
		(net "TDR_SE_50_OHM_BOT")
	)
	(segment
		(start 90.715338 -52.21224)
		(end 90.715338 -52.63388)
		(width 0.18796)
		(layer "B.Cu")
		(net "TDR_SE_50_OHM_BOT")
	)
	(segment
		(start 87.130636 -43.86072)
		(end 87.318596 -44.04868)
		(width 0.18796)
		(layer "B.Cu")
		(net "TDR_SE_50_OHM_BOT")
	)
	(segment
		(start 87.130636 -48.64608)
		(end 87.318596 -48.83404)
		(width 0.18796)
		(layer "B.Cu")
		(net "TDR_SE_50_OHM_BOT")
	)
	(segment
		(start 87.318596 -51.22672)
		(end 87.130636 -51.41468)
		(width 0.18796)
		(layer "B.Cu")
		(net "TDR_SE_50_OHM_BOT")
	)
	(segment
		(start 87.130636 -33.86836)
		(end 87.130636 -34.29)
		(width 0.18796)
		(layer "B.Cu")
		(net "TDR_SE_50_OHM_BOT")
	)
	(segment
		(start 90.4494 -46.44136)
		(end 87.318596 -46.44136)
		(width 0.18796)
		(layer "B.Cu")
		(net "TDR_SE_50_OHM_BOT")
	)
	(segment
		(start 87.318596 -34.47796)
		(end 90.4494 -34.47796)
		(width 0.18796)
		(layer "B.Cu")
		(net "TDR_SE_50_OHM_BOT")
	)
	(segment
		(start 87.318596 -39.26332)
		(end 90.4494 -39.26332)
		(width 0.18796)
		(layer "B.Cu")
		(net "TDR_SE_50_OHM_BOT")
	)
	(segment
		(start 87.318596 -36.87064)
		(end 87.130636 -37.0586)
		(width 0.18796)
		(layer "B.Cu")
		(net "TDR_SE_50_OHM_BOT")
	)
	(segment
		(start 90.527378 -52.02428)
		(end 90.715338 -52.21224)
		(width 0.18796)
		(layer "B.Cu")
		(net "TDR_SE_50_OHM_BOT")
	)
	(segment
		(start 90.63736 -37.85616)
		(end 90.63736 -38.2778)
		(width 0.18796)
		(layer "B.Cu")
		(net "TDR_SE_50_OHM_BOT")
	)
	(segment
		(start 88.710516 -55.639716)
		(end 86.531958 -55.639716)
		(width 0.18796)
		(layer "B.Cu")
		(net "TDR_SE_50_OHM_BOT")
	)
	(segment
		(start 87.318596 -49.6316)
		(end 87.130636 -49.81956)
		(width 0.18796)
		(layer "B.Cu")
		(net "TDR_SE_50_OHM_BOT")
	)
	(segment
		(start 90.4494 -35.27552)
		(end 87.318596 -35.27552)
		(width 0.18796)
		(layer "B.Cu")
		(net "TDR_SE_50_OHM_BOT")
	)
	(segment
		(start 90.4494 -36.87064)
		(end 87.318596 -36.87064)
		(width 0.18796)
		(layer "B.Cu")
		(net "TDR_SE_50_OHM_BOT")
	)
	(segment
		(start 87.130636 -35.88512)
		(end 87.318596 -36.07308)
		(width 0.18796)
		(layer "B.Cu")
		(net "TDR_SE_50_OHM_BOT")
	)
	(segment
		(start 90.63736 -41.46804)
		(end 90.4494 -41.656)
		(width 0.18796)
		(layer "B.Cu")
		(net "TDR_SE_50_OHM_BOT")
	)
	(segment
		(start 90.63736 -41.0464)
		(end 90.63736 -41.46804)
		(width 0.18796)
		(layer "B.Cu")
		(net "TDR_SE_50_OHM_BOT")
	)
	(segment
		(start 87.130636 -34.29)
		(end 87.318596 -34.47796)
		(width 0.18796)
		(layer "B.Cu")
		(net "TDR_SE_50_OHM_BOT")
	)
	(segment
		(start 87.318596 -45.6438)
		(end 90.4494 -45.6438)
		(width 0.18796)
		(layer "B.Cu")
		(net "TDR_SE_50_OHM_BOT")
	)
	(segment
		(start 90.4494 -48.83404)
		(end 90.63736 -49.022)
		(width 0.18796)
		(layer "B.Cu")
		(net "TDR_SE_50_OHM_BOT")
	)
	(segment
		(start 87.318596 -33.6804)
		(end 87.130636 -33.86836)
		(width 0.18796)
		(layer "B.Cu")
		(net "TDR_SE_50_OHM_BOT")
	)
	(segment
		(start 90.4494 -40.06088)
		(end 87.318596 -40.06088)
		(width 0.18796)
		(layer "B.Cu")
		(net "TDR_SE_50_OHM_BOT")
	)
	(segment
		(start 90.63736 -33.0708)
		(end 90.63736 -33.49244)
		(width 0.18796)
		(layer "B.Cu")
		(net "TDR_SE_50_OHM_BOT")
	)
	(segment
		(start 87.318596 -53.6194)
		(end 88.696038 -53.6194)
		(width 0.18796)
		(layer "B.Cu")
		(net "TDR_SE_50_OHM_BOT")
	)
	(segment
		(start 87.318596 -52.82184)
		(end 87.130636 -53.0098)
		(width 0.18796)
		(layer "B.Cu")
		(net "TDR_SE_50_OHM_BOT")
	)
	(segment
		(start 88.696038 -53.6194)
		(end 88.883998 -53.80736)
		(width 0.18796)
		(layer "B.Cu")
		(net "TDR_SE_50_OHM_BOT")
	)
	(segment
		(start 87.130636 -32.27324)
		(end 87.130636 -32.69488)
		(width 0.18796)
		(layer "B.Cu")
		(net "TDR_SE_50_OHM_BOT")
	)
	(segment
		(start 87.318596 -41.656)
		(end 87.130636 -41.84396)
		(width 0.18796)
		(layer "B.Cu")
		(net "TDR_SE_50_OHM_BOT")
	)
	(segment
		(start 87.130636 -37.0586)
		(end 87.130636 -37.48024)
		(width 0.18796)
		(layer "B.Cu")
		(net "TDR_SE_50_OHM_BOT")
	)
	(segment
		(start 87.318596 -36.07308)
		(end 90.4494 -36.07308)
		(width 0.18796)
		(layer "B.Cu")
		(net "TDR_SE_50_OHM_BOT")
	)
	(segment
		(start 90.4494 -45.6438)
		(end 90.63736 -45.83176)
		(width 0.18796)
		(layer "B.Cu")
		(net "TDR_SE_50_OHM_BOT")
	)
	(segment
		(start 87.130636 -45.45584)
		(end 87.318596 -45.6438)
		(width 0.18796)
		(layer "B.Cu")
		(net "TDR_SE_50_OHM_BOT")
	)
	(segment
		(start 90.63736 -43.06316)
		(end 90.4494 -43.25112)
		(width 0.18796)
		(layer "B.Cu")
		(net "TDR_SE_50_OHM_BOT")
	)
	(segment
		(start 90.63736 -33.49244)
		(end 90.4494 -33.6804)
		(width 0.18796)
		(layer "B.Cu")
		(net "TDR_SE_50_OHM_BOT")
	)
	(segment
		(start 87.130636 -39.07536)
		(end 87.318596 -39.26332)
		(width 0.18796)
		(layer "B.Cu")
		(net "TDR_SE_50_OHM_BOT")
	)
	(segment
		(start 87.130636 -38.65372)
		(end 87.130636 -39.07536)
		(width 0.18796)
		(layer "B.Cu")
		(net "TDR_SE_50_OHM_BOT")
	)
	(segment
		(start 90.63736 -50.61712)
		(end 90.63736 -51.03876)
		(width 0.18796)
		(layer "B.Cu")
		(net "TDR_SE_50_OHM_BOT")
	)
	(segment
		(start 90.527378 -52.82184)
		(end 87.318596 -52.82184)
		(width 0.18796)
		(layer "B.Cu")
		(net "TDR_SE_50_OHM_BOT")
	)
	(segment
		(start 90.4494 -32.88284)
		(end 90.63736 -33.0708)
		(width 0.18796)
		(layer "B.Cu")
		(net "TDR_SE_50_OHM_BOT")
	)
	(segment
		(start 90.4494 -50.42916)
		(end 90.63736 -50.61712)
		(width 0.18796)
		(layer "B.Cu")
		(net "TDR_SE_50_OHM_BOT")
	)
	(segment
		(start 90.63736 -44.65828)
		(end 90.4494 -44.84624)
		(width 0.18796)
		(layer "B.Cu")
		(net "TDR_SE_50_OHM_BOT")
	)
	(segment
		(start 87.318596 -37.6682)
		(end 90.4494 -37.6682)
		(width 0.18796)
		(layer "B.Cu")
		(net "TDR_SE_50_OHM_BOT")
	)
	(segment
		(start 90.4494 -38.46576)
		(end 87.318596 -38.46576)
		(width 0.18796)
		(layer "B.Cu")
		(net "TDR_SE_50_OHM_BOT")
	)
	(segment
		(start 90.63736 -46.2534)
		(end 90.4494 -46.44136)
		(width 0.18796)
		(layer "B.Cu")
		(net "TDR_SE_50_OHM_BOT")
	)
	(segment
		(start 90.4494 -49.6316)
		(end 87.318596 -49.6316)
		(width 0.18796)
		(layer "B.Cu")
		(net "TDR_SE_50_OHM_BOT")
	)
	(segment
		(start 87.130636 -47.05096)
		(end 87.318596 -47.23892)
		(width 0.18796)
		(layer "B.Cu")
		(net "TDR_SE_50_OHM_BOT")
	)
	(segment
		(start 87.318596 -46.44136)
		(end 87.130636 -46.62932)
		(width 0.18796)
		(layer "B.Cu")
		(net "TDR_SE_50_OHM_BOT")
	)
	(segment
		(start 90.4494 -39.26332)
		(end 90.63736 -39.45128)
		(width 0.18796)
		(layer "B.Cu")
		(net "TDR_SE_50_OHM_BOT")
	)
	(segment
		(start 90.63736 -34.66592)
		(end 90.63736 -35.08756)
		(width 0.18796)
		(layer "B.Cu")
		(net "TDR_SE_50_OHM_BOT")
	)
	(segment
		(start 87.318596 -40.85844)
		(end 90.4494 -40.85844)
		(width 0.18796)
		(layer "B.Cu")
		(net "TDR_SE_50_OHM_BOT")
	)
	(segment
		(start 87.318596 -47.23892)
		(end 90.4494 -47.23892)
		(width 0.18796)
		(layer "B.Cu")
		(net "TDR_SE_50_OHM_BOT")
	)
	(segment
		(start 87.318596 -40.06088)
		(end 87.130636 -40.24884)
		(width 0.18796)
		(layer "B.Cu")
		(net "TDR_SE_50_OHM_BOT")
	)
	(segment
		(start 90.63736 -51.03876)
		(end 90.4494 -51.22672)
		(width 0.18796)
		(layer "B.Cu")
		(net "TDR_SE_50_OHM_BOT")
	)
	(segment
		(start 87.130636 -41.84396)
		(end 87.130636 -42.2656)
		(width 0.18796)
		(layer "B.Cu")
		(net "TDR_SE_50_OHM_BOT")
	)
	(segment
		(start 87.130636 -51.83632)
		(end 87.318596 -52.02428)
		(width 0.18796)
		(layer "B.Cu")
		(net "TDR_SE_50_OHM_BOT")
	)
	(segment
		(start 90.63736 -44.23664)
		(end 90.63736 -44.65828)
		(width 0.18796)
		(layer "B.Cu")
		(net "TDR_SE_50_OHM_BOT")
	)
	(segment
		(start 87.318596 -35.27552)
		(end 87.130636 -35.46348)
		(width 0.18796)
		(layer "B.Cu")
		(net "TDR_SE_50_OHM_BOT")
	)
	(segment
		(start 88.883998 -26.647648)
		(end 88.883998 -31.09976)
		(width 0.18796)
		(layer "B.Cu")
		(net "TDR_SE_50_OHM_BOT")
	)
	(segment
		(start 87.318596 -42.45356)
		(end 90.4494 -42.45356)
		(width 0.18796)
		(layer "B.Cu")
		(net "TDR_SE_50_OHM_BOT")
	)
	(segment
		(start 17.309084 -57.747916)
		(end 16.764 -58.293)
		(width 0.18796)
		(layer "F.Cu")
		(net "PWR_LED")
	)
	(segment
		(start 16.330422 -58.472578)
		(end 15.915894 -58.887106)
		(width 0.18796)
		(layer "F.Cu")
		(net "PWR_LED")
	)
	(segment
		(start 18.01495 -56.769)
		(end 17.502378 -57.281572)
		(width 0.18796)
		(layer "F.Cu")
		(net "PWR_LED")
	)
	(segment
		(start 16.764 -58.293)
		(end 16.330422 -58.472578)
		(width 0.18796)
		(layer "F.Cu")
		(net "PWR_LED")
	)
	(segment
		(start 15.915894 -58.887106)
		(end 15.117064 -58.887106)
		(width 0.18796)
		(layer "F.Cu")
		(net "PWR_LED")
	)
	(segment
		(start 17.502378 -57.281572)
		(end 17.309084 -57.747916)
		(width 0.18796)
		(layer "F.Cu")
		(net "PWR_LED")
	)
	(via
		(at 16.764 -58.293)
		(size 0.762)
		(drill 0.381)
		(layers "F.Cu" "B.Cu")
		(net "PWR_LED")
	)
	(segment
		(start 35.433 -2.667)
		(end 35.741864 -2.975864)
		(width 0.18796)
		(layer "F.Cu")
		(net "THERMAL_ADDR_A1")
	)
	(segment
		(start 36.30295 -22.352)
		(end 34.798 -22.352)
		(width 0.18796)
		(layer "F.Cu")
		(net "THERMAL_ADDR_A1")
	)
	(segment
		(start 35.741864 -2.975864)
		(end 36.537646 -2.975864)
		(width 0.18796)
		(layer "F.Cu")
		(net "THERMAL_ADDR_A1")
	)
	(segment
		(start 36.30295 -22.352)
		(end 36.30295 -21.336)
		(width 0.18796)
		(layer "F.Cu")
		(net "THERMAL_ADDR_A1")
	)
	(via
		(at 34.798 -22.352)
		(size 0.508)
		(drill 0.254)
		(layers "F.Cu" "B.Cu")
		(net "THERMAL_ADDR_A1")
	)
	(via
		(at 35.433 -2.667)
		(size 0.508)
		(drill 0.254)
		(layers "F.Cu" "B.Cu")
		(net "THERMAL_ADDR_A1")
	)
	(segment
		(start 28.184348 -17.833848)
		(end 32.7025 -22.352)
		(width 0.18796)
		(layer "B.Cu")
		(net "THERMAL_ADDR_A1")
	)
	(segment
		(start 32.7025 -22.352)
		(end 34.798 -22.352)
		(width 0.18796)
		(layer "B.Cu")
		(net "THERMAL_ADDR_A1")
	)
	(segment
		(start 32.990028 -2.032)
		(end 26.715974 -8.306054)
		(width 0.18796)
		(layer "B.Cu")
		(net "THERMAL_ADDR_A1")
	)
	(segment
		(start 34.798 -2.032)
		(end 32.990028 -2.032)
		(width 0.18796)
		(layer "B.Cu")
		(net "THERMAL_ADDR_A1")
	)
	(segment
		(start 28.184348 -14.412468)
		(end 28.184348 -17.833848)
		(width 0.18796)
		(layer "B.Cu")
		(net "THERMAL_ADDR_A1")
	)
	(segment
		(start 26.715974 -8.306054)
		(end 26.715974 -12.944094)
		(width 0.18796)
		(layer "B.Cu")
		(net "THERMAL_ADDR_A1")
	)
	(segment
		(start 26.715974 -12.944094)
		(end 28.184348 -14.412468)
		(width 0.18796)
		(layer "B.Cu")
		(net "THERMAL_ADDR_A1")
	)
	(segment
		(start 35.433 -2.667)
		(end 34.798 -2.032)
		(width 0.18796)
		(layer "B.Cu")
		(net "THERMAL_ADDR_A1")
	)
	(segment
		(start 36.30295 -20.32)
		(end 35.941 -20.32)
		(width 0.18796)
		(layer "F.Cu")
		(net "THERMAL_ADDR_A0")
	)
	(segment
		(start 36.30295 -20.32)
		(end 36.30295 -19.304)
		(width 0.18796)
		(layer "F.Cu")
		(net "THERMAL_ADDR_A0")
	)
	(segment
		(start 33.528 -2.667)
		(end 34.036 -2.667)
		(width 0.18796)
		(layer "F.Cu")
		(net "THERMAL_ADDR_A0")
	)
	(segment
		(start 35.941 -20.32)
		(end 34.798 -21.463)
		(width 0.18796)
		(layer "F.Cu")
		(net "THERMAL_ADDR_A0")
	)
	(segment
		(start 35.614864 -4.245864)
		(end 36.537646 -4.245864)
		(width 0.18796)
		(layer "F.Cu")
		(net "THERMAL_ADDR_A0")
	)
	(segment
		(start 34.036 -2.667)
		(end 35.614864 -4.245864)
		(width 0.18796)
		(layer "F.Cu")
		(net "THERMAL_ADDR_A0")
	)
	(via
		(at 34.798 -21.463)
		(size 0.508)
		(drill 0.254)
		(layers "F.Cu" "B.Cu")
		(net "THERMAL_ADDR_A0")
	)
	(via
		(at 33.528 -2.667)
		(size 0.508)
		(drill 0.254)
		(layers "F.Cu" "B.Cu")
		(net "THERMAL_ADDR_A0")
	)
	(segment
		(start 28.59151 -10.81151)
		(end 28.59151 -17.687798)
		(width 0.18796)
		(layer "B.Cu")
		(net "THERMAL_ADDR_A0")
	)
	(segment
		(start 28.59151 -17.687798)
		(end 32.366712 -21.463)
		(width 0.18796)
		(layer "B.Cu")
		(net "THERMAL_ADDR_A0")
	)
	(segment
		(start 33.528 -2.667)
		(end 33.117028 -2.667)
		(width 0.18796)
		(layer "B.Cu")
		(net "THERMAL_ADDR_A0")
	)
	(segment
		(start 27.98826 -7.795768)
		(end 27.98826 -10.20826)
		(width 0.18796)
		(layer "B.Cu")
		(net "THERMAL_ADDR_A0")
	)
	(segment
		(start 32.366712 -21.463)
		(end 34.798 -21.463)
		(width 0.18796)
		(layer "B.Cu")
		(net "THERMAL_ADDR_A0")
	)
	(segment
		(start 33.117028 -2.667)
		(end 27.98826 -7.795768)
		(width 0.18796)
		(layer "B.Cu")
		(net "THERMAL_ADDR_A0")
	)
	(segment
		(start 27.98826 -10.20826)
		(end 28.59151 -10.81151)
		(width 0.18796)
		(layer "B.Cu")
		(net "THERMAL_ADDR_A0")
	)
	(segment
		(start 16.129 -58.039)
		(end 15.93088 -58.23712)
		(width 0.18796)
		(layer "F.Cu")
		(net "SYSTEM_FAULT_ID_LED")
	)
	(segment
		(start 16.764 -57.00395)
		(end 18.01495 -55.753)
		(width 0.18796)
		(layer "F.Cu")
		(net "SYSTEM_FAULT_ID_LED")
	)
	(segment
		(start 15.93088 -58.23712)
		(end 15.117064 -58.23712)
		(width 0.18796)
		(layer "F.Cu")
		(net "SYSTEM_FAULT_ID_LED")
	)
	(segment
		(start 16.764 -57.023)
		(end 16.764 -57.00395)
		(width 0.18796)
		(layer "F.Cu")
		(net "SYSTEM_FAULT_ID_LED")
	)
	(segment
		(start 16.764 -57.023)
		(end 16.398494 -57.388506)
		(width 0.18796)
		(layer "F.Cu")
		(net "SYSTEM_FAULT_ID_LED")
	)
	(segment
		(start 16.398494 -57.388506)
		(end 16.129 -58.039)
		(width 0.18796)
		(layer "F.Cu")
		(net "SYSTEM_FAULT_ID_LED")
	)
	(via
		(at 16.764 -57.023)
		(size 0.762)
		(drill 0.381)
		(layers "F.Cu" "B.Cu")
		(net "SYSTEM_FAULT_ID_LED")
	)
	(segment
		(start 10.7696 -21.971)
		(end 10.7696 -23.622)
		(width 0.18796)
		(layer "F.Cu")
		(net "SYSTEM_FAULT_ID_LED_R2_N")
	)
	(segment
		(start 10.7696 -23.622)
		(end 10.7696 -25.019)
		(width 0.18796)
		(layer "F.Cu")
		(net "SYSTEM_FAULT_ID_LED_R2_N")
	)
	(via
		(at 10.7696 -23.622)
		(size 0.762)
		(drill 0.381)
		(layers "F.Cu" "B.Cu")
		(net "SYSTEM_FAULT_ID_LED_R2_N")
	)
	(via
		(at 10.7696 -21.971)
		(size 0.508)
		(drill 0.254)
		(layers "F.Cu" "B.Cu")
		(net "SYSTEM_FAULT_ID_LED_R2_N")
	)
	(segment
		(start 10.47877 -7.30377)
		(end 11.811 -8.636)
		(width 0.18796)
		(layer "B.Cu")
		(net "SYSTEM_FAULT_ID_LED_R2_N")
	)
	(segment
		(start 11.811 -8.636)
		(end 11.811 -20.9296)
		(width 0.18796)
		(layer "B.Cu")
		(net "SYSTEM_FAULT_ID_LED_R2_N")
	)
	(segment
		(start 11.811 -20.9296)
		(end 10.7696 -21.971)
		(width 0.18796)
		(layer "B.Cu")
		(net "SYSTEM_FAULT_ID_LED_R2_N")
	)
	(segment
		(start 5.16001 -5.100066)
		(end 10.47877 -7.30377)
		(width 0.18796)
		(layer "B.Cu")
		(net "SYSTEM_FAULT_ID_LED_R2_N")
	)
	(segment
		(start 14.224 -48.641)
		(end 13.589 -48.641)
		(width 0.18796)
		(layer "F.Cu")
		(net "SMB_FRU_SCL")
	)
	(segment
		(start 14.732 -48.133)
		(end 15.47495 -48.133)
		(width 0.18796)
		(layer "F.Cu")
		(net "SMB_FRU_SCL")
	)
	(segment
		(start 13.589 -48.641)
		(end 13.462 -48.514)
		(width 0.18796)
		(layer "F.Cu")
		(net "SMB_FRU_SCL")
	)
	(segment
		(start 13.462 -48.514)
		(end 12.555982 -48.514)
		(width 0.18796)
		(layer "F.Cu")
		(net "SMB_FRU_SCL")
	)
	(segment
		(start 14.224 -48.641)
		(end 14.732 -48.133)
		(width 0.18796)
		(layer "F.Cu")
		(net "SMB_FRU_SCL")
	)
	(segment
		(start 15.47495 -48.133)
		(end 15.47495 -47.117)
		(width 0.18796)
		(layer "F.Cu")
		(net "SMB_FRU_SCL")
	)
	(via
		(at 14.224 -48.641)
		(size 0.762)
		(drill 0.381)
		(layers "F.Cu" "B.Cu")
		(net "SMB_FRU_SCL")
	)
	(segment
		(start 7.256018 -49.784)
		(end 5.588 -49.784)
		(width 0.18796)
		(layer "F.Cu")
		(net "PD_FRU_A1")
	)
	(segment
		(start 4.33705 -48.768)
		(end 4.33705 -49.784)
		(width 0.18796)
		(layer "F.Cu")
		(net "PD_FRU_A1")
	)
	(segment
		(start 5.588 -49.784)
		(end 4.33705 -49.784)
		(width 0.18796)
		(layer "F.Cu")
		(net "PD_FRU_A1")
	)
	(via
		(at 5.588 -49.784)
		(size 0.762)
		(drill 0.381)
		(layers "F.Cu" "B.Cu")
		(net "PD_FRU_A1")
	)
	(segment
		(start 4.826 -50.8)
		(end 4.33705 -50.8)
		(width 0.18796)
		(layer "F.Cu")
		(net "PD_FRU_A0")
	)
	(segment
		(start 4.33705 -51.816)
		(end 4.33705 -50.8)
		(width 0.18796)
		(layer "F.Cu")
		(net "PD_FRU_A0")
	)
	(segment
		(start 5.08 -51.054)
		(end 4.826 -50.8)
		(width 0.18796)
		(layer "F.Cu")
		(net "PD_FRU_A0")
	)
	(segment
		(start 5.588 -51.054)
		(end 5.08 -51.054)
		(width 0.18796)
		(layer "F.Cu")
		(net "PD_FRU_A0")
	)
	(segment
		(start 7.256018 -51.054)
		(end 5.588 -51.054)
		(width 0.18796)
		(layer "F.Cu")
		(net "PD_FRU_A0")
	)
	(via
		(at 5.588 -51.054)
		(size 0.762)
		(drill 0.381)
		(layers "F.Cu" "B.Cu")
		(net "PD_FRU_A0")
	)
	(segment
		(start 15.47495 -49.149)
		(end 15.47495 -50.165)
		(width 0.18796)
		(layer "F.Cu")
		(net "PD_FRU_WP")
	)
	(segment
		(start 15.47495 -49.149)
		(end 14.986 -49.149)
		(width 0.18796)
		(layer "F.Cu")
		(net "PD_FRU_WP")
	)
	(segment
		(start 13.488162 -49.784)
		(end 12.555982 -49.784)
		(width 0.18796)
		(layer "F.Cu")
		(net "PD_FRU_WP")
	)
	(segment
		(start 14.986 -49.149)
		(end 14.224 -49.911)
		(width 0.18796)
		(layer "F.Cu")
		(net "PD_FRU_WP")
	)
	(segment
		(start 13.615162 -49.911)
		(end 13.488162 -49.784)
		(width 0.18796)
		(layer "F.Cu")
		(net "PD_FRU_WP")
	)
	(segment
		(start 14.224 -49.911)
		(end 13.615162 -49.911)
		(width 0.18796)
		(layer "F.Cu")
		(net "PD_FRU_WP")
	)
	(via
		(at 14.224 -49.911)
		(size 0.762)
		(drill 0.381)
		(layers "F.Cu" "B.Cu")
		(net "PD_FRU_WP")
	)
	(segment
		(start 14.732254 -46.101)
		(end 14.224 -46.609254)
		(width 0.18796)
		(layer "F.Cu")
		(net "SMB_FRU_SDA")
	)
	(segment
		(start 14.224 -47.244)
		(end 12.555982 -47.244)
		(width 0.18796)
		(layer "F.Cu")
		(net "SMB_FRU_SDA")
	)
	(segment
		(start 15.47495 -46.101)
		(end 14.732254 -46.101)
		(width 0.18796)
		(layer "F.Cu")
		(net "SMB_FRU_SDA")
	)
	(segment
		(start 14.224 -46.609254)
		(end 14.224 -47.244)
		(width 0.18796)
		(layer "F.Cu")
		(net "SMB_FRU_SDA")
	)
	(segment
		(start 15.47495 -46.101)
		(end 15.47495 -45.085)
		(width 0.18796)
		(layer "F.Cu")
		(net "SMB_FRU_SDA")
	)
	(via
		(at 14.224 -47.244)
		(size 0.762)
		(drill 0.381)
		(layers "F.Cu" "B.Cu")
		(net "SMB_FRU_SDA")
	)
	(segment
		(start 4.33705 -47.752)
		(end 4.33705 -46.736)
		(width 0.18796)
		(layer "F.Cu")
		(net "PD_FRU_A2")
	)
	(segment
		(start 5.588 -48.26)
		(end 5.08 -47.752)
		(width 0.18796)
		(layer "F.Cu")
		(net "PD_FRU_A2")
	)
	(segment
		(start 5.08 -47.752)
		(end 4.33705 -47.752)
		(width 0.18796)
		(layer "F.Cu")
		(net "PD_FRU_A2")
	)
	(segment
		(start 5.588 -48.26)
		(end 6.096 -48.26)
		(width 0.18796)
		(layer "F.Cu")
		(net "PD_FRU_A2")
	)
	(segment
		(start 6.096 -48.26)
		(end 6.35 -48.514)
		(width 0.18796)
		(layer "F.Cu")
		(net "PD_FRU_A2")
	)
	(segment
		(start 6.35 -48.514)
		(end 7.256018 -48.514)
		(width 0.18796)
		(layer "F.Cu")
		(net "PD_FRU_A2")
	)
	(via
		(at 5.588 -48.26)
		(size 0.762)
		(drill 0.381)
		(layers "F.Cu" "B.Cu")
		(net "PD_FRU_A2")
	)
	(segment
		(start 37.719 -27.432)
		(end 37.10305 -27.432)
		(width 0.381)
		(layer "F.Cu")
		(net "P3V3_STBY")
	)
	(segment
		(start 17.92605 -22.098)
		(end 18.542 -22.098)
		(width 0.381)
		(layer "F.Cu")
		(net "P3V3_STBY")
	)
	(segment
		(start 2.64795 -26.289)
		(end 2.032 -26.289)
		(width 0.4572)
		(layer "F.Cu")
		(net "P3V3_STBY")
	)
	(segment
		(start 31.02102 -7.675118)
		(end 31.473902 -7.222236)
		(width 0.4572)
		(layer "F.Cu")
		(net "P3V3_STBY")
	)
	(segment
		(start 4.953 -59.309)
		(end 5.56895 -59.309)
		(width 0.4572)
		(layer "F.Cu")
		(net "P3V3_STBY")
	)
	(segment
		(start 17.92605 -25.146)
		(end 19.15795 -25.146)
		(width 0.381)
		(layer "F.Cu")
		(net "P3V3_STBY")
	)
	(segment
		(start 36.537646 -5.515864)
		(end 32.869632 -5.515864)
		(width 0.4572)
		(layer "F.Cu")
		(net "P3V3_STBY")
	)
	(segment
		(start 16.129 -24.257)
		(end 15.748 -23.876)
		(width 0.381)
		(layer "F.Cu")
		(net "P3V3_STBY")
	)
	(segment
		(start 5.56895 -61.341)
		(end 4.953 -61.341)
		(width 0.4572)
		(layer "F.Cu")
		(net "P3V3_STBY")
	)
	(segment
		(start 37.10305 -21.336)
		(end 37.719 -21.336)
		(width 0.4572)
		(layer "F.Cu")
		(net "P3V3_STBY")
	)
	(segment
		(start 15.748 -20.84705)
		(end 16.51 -20.08505)
		(width 0.381)
		(layer "F.Cu")
		(net "P3V3_STBY")
	)
	(segment
		(start 37.10305 -23.368)
		(end 37.719 -23.368)
		(width 0.4572)
		(layer "F.Cu")
		(net "P3V3_STBY")
	)
	(segment
		(start 12.555982 -51.054)
		(end 13.462254 -51.054)
		(width 0.4572)
		(layer "F.Cu")
		(net "P3V3_STBY")
	)
	(segment
		(start 16.129 -25.527)
		(end 16.129 -24.257)
		(width 0.381)
		(layer "F.Cu")
		(net "P3V3_STBY")
	)
	(segment
		(start 3.53695 -49.784)
		(end 2.921 -49.784)
		(width 0.4572)
		(layer "F.Cu")
		(net "P3V3_STBY")
	)
	(segment
		(start 5.56895 -55.245)
		(end 4.953 -55.245)
		(width 0.4572)
		(layer "F.Cu")
		(net "P3V3_STBY")
	)
	(segment
		(start 19.15795 -25.908)
		(end 19.15795 -25.146)
		(width 0.381)
		(layer "F.Cu")
		(net "P3V3_STBY")
	)
	(segment
		(start 16.256254 -62.103)
		(end 15.740126 -61.586872)
		(width 0.4572)
		(layer "F.Cu")
		(net "P3V3_STBY")
	)
	(segment
		(start 13.589254 -51.181)
		(end 14.20495 -51.181)
		(width 0.4572)
		(layer "F.Cu")
		(net "P3V3_STBY")
	)
	(segment
		(start 15.740126 -61.586872)
		(end 15.117064 -61.586872)
		(width 0.4572)
		(layer "F.Cu")
		(net "P3V3_STBY")
	)
	(segment
		(start 37.719 -25.4)
		(end 37.10305 -25.4)
		(width 0.381)
		(layer "F.Cu")
		(net "P3V3_STBY")
	)
	(segment
		(start 31.473902 -7.222236)
		(end 31.473902 -6.911594)
		(width 0.4572)
		(layer "F.Cu")
		(net "P3V3_STBY")
	)
	(segment
		(start 4.953 -57.277)
		(end 5.56895 -57.277)
		(width 0.4572)
		(layer "F.Cu")
		(net "P3V3_STBY")
	)
	(segment
		(start 32.869632 -5.515864)
		(end 31.473902 -6.911594)
		(width 0.4572)
		(layer "F.Cu")
		(net "P3V3_STBY")
	)
	(segment
		(start 3.53695 -47.752)
		(end 2.921 -47.752)
		(width 0.4572)
		(layer "F.Cu")
		(net "P3V3_STBY")
	)
	(segment
		(start 18.542 -22.098)
		(end 19.15795 -22.098)
		(width 0.381)
		(layer "F.Cu")
		(net "P3V3_STBY")
	)
	(segment
		(start 16.74495 -62.738)
		(end 16.74495 -62.103)
		(width 0.4572)
		(layer "F.Cu")
		(net "P3V3_STBY")
	)
	(segment
		(start 16.74495 -62.103)
		(end 16.256254 -62.103)
		(width 0.4572)
		(layer "F.Cu")
		(net "P3V3_STBY")
	)
	(segment
		(start 16.27505 -45.085)
		(end 17.018 -45.085)
		(width 0.4572)
		(layer "F.Cu")
		(net "P3V3_STBY")
	)
	(segment
		(start 13.462254 -51.054)
		(end 13.589254 -51.181)
		(width 0.4572)
		(layer "F.Cu")
		(net "P3V3_STBY")
	)
	(segment
		(start 18.81505 -58.801)
		(end 19.431 -58.801)
		(width 0.4572)
		(layer "F.Cu")
		(net "P3V3_STBY")
	)
	(segment
		(start 16.27505 -49.149)
		(end 16.891 -49.149)
		(width 0.4572)
		(layer "F.Cu")
		(net "P3V3_STBY")
	)
	(segment
		(start 3.53695 -51.816)
		(end 2.921 -51.816)
		(width 0.4572)
		(layer "F.Cu")
		(net "P3V3_STBY")
	)
	(segment
		(start 16.27505 -48.133)
		(end 16.891 -48.133)
		(width 0.4572)
		(layer "F.Cu")
		(net "P3V3_STBY")
	)
	(segment
		(start 37.719 -19.304)
		(end 37.10305 -19.304)
		(width 0.4572)
		(layer "F.Cu")
		(net "P3V3_STBY")
	)
	(segment
		(start 15.748 -23.876)
		(end 15.748 -20.84705)
		(width 0.381)
		(layer "F.Cu")
		(net "P3V3_STBY")
	)
	(segment
		(start 14.20495 -51.181)
		(end 14.20495 -51.816)
		(width 0.4572)
		(layer "F.Cu")
		(net "P3V3_STBY")
	)
	(segment
		(start 2.64795 -29.083)
		(end 2.032 -29.083)
		(width 0.4572)
		(layer "F.Cu")
		(net "P3V3_STBY")
	)
	(segment
		(start 5.56895 -53.213)
		(end 4.953 -53.213)
		(width 0.4572)
		(layer "F.Cu")
		(net "P3V3_STBY")
	)
	(via
		(at 18.542 -22.098)
		(size 0.508)
		(drill 0.254)
		(layers "F.Cu" "B.Cu")
		(net "P3V3_STBY")
	)
	(via
		(at 37.719 -25.4)
		(size 0.508)
		(drill 0.254)
		(layers "F.Cu" "B.Cu")
		(net "P3V3_STBY")
	)
	(via
		(at 3.175 -29.718)
		(size 0.6604)
		(drill 0.3302)
		(layers "F.Cu" "B.Cu")
		(net "P3V3_STBY")
	)
	(via
		(at 4.953 -57.277)
		(size 0.508)
		(drill 0.254)
		(layers "F.Cu" "B.Cu")
		(net "P3V3_STBY")
	)
	(via
		(at 2.921 -47.752)
		(size 0.508)
		(drill 0.254)
		(layers "F.Cu" "B.Cu")
		(net "P3V3_STBY")
	)
	(via
		(at 37.719 -21.336)
		(size 0.508)
		(drill 0.254)
		(layers "F.Cu" "B.Cu")
		(net "P3V3_STBY")
	)
	(via
		(at 16.74495 -62.738)
		(size 0.508)
		(drill 0.254)
		(layers "F.Cu" "B.Cu")
		(net "P3V3_STBY")
	)
	(via
		(at 19.431 -58.801)
		(size 0.508)
		(drill 0.254)
		(layers "F.Cu" "B.Cu")
		(net "P3V3_STBY")
	)
	(via
		(at 31.02102 -7.675118)
		(size 0.508)
		(drill 0.254)
		(layers "F.Cu" "B.Cu")
		(net "P3V3_STBY")
	)
	(via
		(at 13.97 -70.104)
		(size 0.6604)
		(drill 0.3302)
		(layers "F.Cu" "B.Cu")
		(net "P3V3_STBY")
	)
	(via
		(at 4.953 -61.341)
		(size 0.508)
		(drill 0.254)
		(layers "F.Cu" "B.Cu")
		(net "P3V3_STBY")
	)
	(via
		(at 16.891 -49.149)
		(size 0.508)
		(drill 0.254)
		(layers "F.Cu" "B.Cu")
		(net "P3V3_STBY")
	)
	(via
		(at 37.719 -27.432)
		(size 0.508)
		(drill 0.254)
		(layers "F.Cu" "B.Cu")
		(net "P3V3_STBY")
	)
	(via
		(at 19.939 -27.94)
		(size 0.508)
		(drill 0.254)
		(layers "F.Cu" "B.Cu")
		(net "P3V3_STBY")
	)
	(via
		(at 2.032 -26.289)
		(size 0.508)
		(drill 0.254)
		(layers "F.Cu" "B.Cu")
		(net "P3V3_STBY")
	)
	(via
		(at 37.719 -23.368)
		(size 0.508)
		(drill 0.254)
		(layers "F.Cu" "B.Cu")
		(net "P3V3_STBY")
	)
	(via
		(at 17.78 -65.532)
		(size 0.508)
		(drill 0.254)
		(layers "F.Cu" "B.Cu")
		(net "P3V3_STBY")
	)
	(via
		(at 18.415 -65.532)
		(size 0.508)
		(drill 0.254)
		(layers "F.Cu" "B.Cu")
		(net "P3V3_STBY")
	)
	(via
		(at 4.953 -59.309)
		(size 0.508)
		(drill 0.254)
		(layers "F.Cu" "B.Cu")
		(net "P3V3_STBY")
	)
	(via
		(at 19.939 -28.575)
		(size 0.508)
		(drill 0.254)
		(layers "F.Cu" "B.Cu")
		(net "P3V3_STBY")
	)
	(via
		(at 2.032 -29.083)
		(size 0.508)
		(drill 0.254)
		(layers "F.Cu" "B.Cu")
		(net "P3V3_STBY")
	)
	(via
		(at 37.719 -19.304)
		(size 0.508)
		(drill 0.254)
		(layers "F.Cu" "B.Cu")
		(net "P3V3_STBY")
	)
	(via
		(at 17.018 -45.085)
		(size 0.508)
		(drill 0.254)
		(layers "F.Cu" "B.Cu")
		(net "P3V3_STBY")
	)
	(via
		(at 2.921 -51.816)
		(size 0.508)
		(drill 0.254)
		(layers "F.Cu" "B.Cu")
		(net "P3V3_STBY")
	)
	(via
		(at 19.15795 -25.908)
		(size 0.508)
		(drill 0.254)
		(layers "F.Cu" "B.Cu")
		(net "P3V3_STBY")
	)
	(via
		(at 2.921 -49.784)
		(size 0.508)
		(drill 0.254)
		(layers "F.Cu" "B.Cu")
		(net "P3V3_STBY")
	)
	(via
		(at 16.891 -48.133)
		(size 0.508)
		(drill 0.254)
		(layers "F.Cu" "B.Cu")
		(net "P3V3_STBY")
	)
	(via
		(at 25.781 -70.485)
		(size 0.6604)
		(drill 0.3302)
		(layers "F.Cu" "B.Cu")
		(net "P3V3_STBY")
	)
	(via
		(at 4.953 -53.213)
		(size 0.508)
		(drill 0.254)
		(layers "F.Cu" "B.Cu")
		(net "P3V3_STBY")
	)
	(via
		(at 14.20495 -51.816)
		(size 0.508)
		(drill 0.254)
		(layers "F.Cu" "B.Cu")
		(net "P3V3_STBY")
	)
	(via
		(at 4.953 -55.245)
		(size 0.508)
		(drill 0.254)
		(layers "F.Cu" "B.Cu")
		(net "P3V3_STBY")
	)
	(segment
		(start 19.304 -32.131)
		(end 19.304 -46.228)
		(width 0.18796)
		(layer "F.Cu")
		(net "SMB_SCL")
	)
	(segment
		(start 20.574 -59.817)
		(end 19.431 -59.817)
		(width 0.18796)
		(layer "F.Cu")
		(net "SMB_SCL")
	)
	(segment
		(start 16.27505 -47.117)
		(end 16.891 -47.117)
		(width 0.18796)
		(layer "F.Cu")
		(net "SMB_SCL")
	)
	(segment
		(start 18.81505 -59.817)
		(end 19.431 -59.817)
		(width 0.18796)
		(layer "F.Cu")
		(net "SMB_SCL")
	)
	(segment
		(start 19.15795 -23.114)
		(end 18.542 -23.114)
		(width 0.18796)
		(layer "F.Cu")
		(net "SMB_SCL")
	)
	(segment
		(start 18.415 -47.117)
		(end 16.891 -47.117)
		(width 0.18796)
		(layer "F.Cu")
		(net "SMB_SCL")
	)
	(segment
		(start 21.717 -62.97295)
		(end 21.717 -60.96)
		(width 0.18796)
		(layer "F.Cu")
		(net "SMB_SCL")
	)
	(segment
		(start 18.542 -23.114)
		(end 17.92605 -23.114)
		(width 0.18796)
		(layer "F.Cu")
		(net "SMB_SCL")
	)
	(segment
		(start 19.304 -46.228)
		(end 18.415 -47.117)
		(width 0.18796)
		(layer "F.Cu")
		(net "SMB_SCL")
	)
	(segment
		(start 21.717 -60.96)
		(end 20.574 -59.817)
		(width 0.18796)
		(layer "F.Cu")
		(net "SMB_SCL")
	)
	(via
		(at 16.891 -47.117)
		(size 0.508)
		(drill 0.254)
		(layers "F.Cu" "B.Cu")
		(net "SMB_SCL")
	)
	(via
		(at 19.431 -59.817)
		(size 0.508)
		(drill 0.254)
		(layers "F.Cu" "B.Cu")
		(net "SMB_SCL")
	)
	(via
		(at 20.574 -59.817)
		(size 0.762)
		(drill 0.381)
		(layers "F.Cu" "B.Cu")
		(net "SMB_SCL")
	)
	(via
		(at 19.304 -32.131)
		(size 0.508)
		(drill 0.254)
		(layers "F.Cu" "B.Cu")
		(net "SMB_SCL")
	)
	(via
		(at 18.542 -23.114)
		(size 0.508)
		(drill 0.254)
		(layers "F.Cu" "B.Cu")
		(net "SMB_SCL")
	)
	(segment
		(start 20.237704 -50.463704)
		(end 20.237704 -59.391296)
		(width 0.18796)
		(layer "B.Cu")
		(net "SMB_SCL")
	)
	(segment
		(start 20.237704 -59.391296)
		(end 19.812 -59.817)
		(width 0.18796)
		(layer "B.Cu")
		(net "SMB_SCL")
	)
	(segment
		(start 18.542 -23.114)
		(end 17.399 -24.257)
		(width 0.18796)
		(layer "B.Cu")
		(net "SMB_SCL")
	)
	(segment
		(start 17.399 -24.257)
		(end 17.399 -30.226)
		(width 0.18796)
		(layer "B.Cu")
		(net "SMB_SCL")
	)
	(segment
		(start 17.399 -30.226)
		(end 19.304 -32.131)
		(width 0.18796)
		(layer "B.Cu")
		(net "SMB_SCL")
	)
	(segment
		(start 16.891 -47.117)
		(end 20.237704 -50.463704)
		(width 0.18796)
		(layer "B.Cu")
		(net "SMB_SCL")
	)
	(segment
		(start 19.812 -59.817)
		(end 19.431 -59.817)
		(width 0.18796)
		(layer "B.Cu")
		(net "SMB_SCL")
	)
	(segment
		(start 18.542 -24.13)
		(end 17.92605 -24.13)
		(width 0.18796)
		(layer "F.Cu")
		(net "SMB_SDA")
	)
	(segment
		(start 19.431 -60.833)
		(end 18.81505 -60.833)
		(width 0.18796)
		(layer "F.Cu")
		(net "SMB_SDA")
	)
	(segment
		(start 18.70964 -45.42536)
		(end 18.70964 -31.83636)
		(width 0.18796)
		(layer "F.Cu")
		(net "SMB_SDA")
	)
	(segment
		(start 16.27505 -46.101)
		(end 16.891 -46.101)
		(width 0.18796)
		(layer "F.Cu")
		(net "SMB_SDA")
	)
	(segment
		(start 16.891 -46.101)
		(end 18.034 -46.101)
		(width 0.18796)
		(layer "F.Cu")
		(net "SMB_SDA")
	)
	(segment
		(start 19.431 -60.833)
		(end 19.811746 -60.833)
		(width 0.18796)
		(layer "F.Cu")
		(net "SMB_SDA")
	)
	(segment
		(start 18.70964 -31.83636)
		(end 19.304 -31.242)
		(width 0.18796)
		(layer "F.Cu")
		(net "SMB_SDA")
	)
	(segment
		(start 19.15795 -24.13)
		(end 18.542 -24.13)
		(width 0.18796)
		(layer "F.Cu")
		(net "SMB_SDA")
	)
	(segment
		(start 19.811746 -60.833)
		(end 20.701 -61.722254)
		(width 0.18796)
		(layer "F.Cu")
		(net "SMB_SDA")
	)
	(segment
		(start 18.034 -46.101)
		(end 18.70964 -45.42536)
		(width 0.18796)
		(layer "F.Cu")
		(net "SMB_SDA")
	)
	(segment
		(start 20.701 -61.722254)
		(end 20.701 -62.97295)
		(width 0.18796)
		(layer "F.Cu")
		(net "SMB_SDA")
	)
	(via
		(at 16.891 -46.101)
		(size 0.508)
		(drill 0.254)
		(layers "F.Cu" "B.Cu")
		(net "SMB_SDA")
	)
	(via
		(at 18.542 -24.13)
		(size 0.508)
		(drill 0.254)
		(layers "F.Cu" "B.Cu")
		(net "SMB_SDA")
	)
	(via
		(at 19.431 -60.833)
		(size 0.508)
		(drill 0.254)
		(layers "F.Cu" "B.Cu")
		(net "SMB_SDA")
	)
	(via
		(at 19.304 -31.242)
		(size 0.508)
		(drill 0.254)
		(layers "F.Cu" "B.Cu")
		(net "SMB_SDA")
	)
	(via
		(at 20.701 -61.722254)
		(size 0.762)
		(drill 0.381)
		(layers "F.Cu" "B.Cu")
		(net "SMB_SDA")
	)
	(segment
		(start 17.99336 -24.67864)
		(end 18.542 -24.13)
		(width 0.18796)
		(layer "B.Cu")
		(net "SMB_SDA")
	)
	(segment
		(start 17.99336 -29.93136)
		(end 17.99336 -24.67864)
		(width 0.18796)
		(layer "B.Cu")
		(net "SMB_SDA")
	)
	(segment
		(start 20.832064 -59.812936)
		(end 19.812 -60.833)
		(width 0.18796)
		(layer "B.Cu")
		(net "SMB_SDA")
	)
	(segment
		(start 16.891 -46.101)
		(end 20.832064 -50.042064)
		(width 0.18796)
		(layer "B.Cu")
		(net "SMB_SDA")
	)
	(segment
		(start 20.832064 -50.042064)
		(end 20.832064 -59.812936)
		(width 0.18796)
		(layer "B.Cu")
		(net "SMB_SDA")
	)
	(segment
		(start 19.812 -60.833)
		(end 19.431 -60.833)
		(width 0.18796)
		(layer "B.Cu")
		(net "SMB_SDA")
	)
	(segment
		(start 19.304 -31.242)
		(end 17.99336 -29.93136)
		(width 0.18796)
		(layer "B.Cu")
		(net "SMB_SDA")
	)
	(segment
		(start 14.84884 -69.73824)
		(end 16.1036 -70.993)
		(width 0.18796)
		(layer "F.Cu")
		(net "RST_SMB_N")
	)
	(segment
		(start 11.57605 -62.738)
		(end 12.319 -62.738)
		(width 0.18796)
		(layer "F.Cu")
		(net "RST_SMB_N")
	)
	(segment
		(start 12.827 -64.857122)
		(end 14.84884 -69.73824)
		(width 0.18796)
		(layer "F.Cu")
		(net "RST_SMB_N")
	)
	(segment
		(start 23.049992 -70.80504)
		(end 23.049992 -69.799962)
		(width 0.18796)
		(layer "F.Cu")
		(net "RST_SMB_N")
	)
	(segment
		(start 12.827 -63.246)
		(end 12.827 -64.857122)
		(width 0.18796)
		(layer "F.Cu")
		(net "RST_SMB_N")
	)
	(segment
		(start 12.319 -62.738)
		(end 12.827 -63.246)
		(width 0.18796)
		(layer "F.Cu")
		(net "RST_SMB_N")
	)
	(segment
		(start 16.1036 -70.993)
		(end 22.862032 -70.993)
		(width 0.18796)
		(layer "F.Cu")
		(net "RST_SMB_N")
	)
	(segment
		(start 22.862032 -70.993)
		(end 23.049992 -70.80504)
		(width 0.18796)
		(layer "F.Cu")
		(net "RST_SMB_N")
	)
	(via
		(at 12.827 -63.246)
		(size 0.762)
		(drill 0.381)
		(layers "F.Cu" "B.Cu")
		(net "RST_SMB_N")
	)
	(segment
		(start 23.10638 -66.339212)
		(end 23.10638 -67.69862)
		(width 0.18796)
		(layer "F.Cu")
		(net "PRSNT_DBV2_SLIMSAS")
	)
	(segment
		(start 15.113 -24.74595)
		(end 15.113 -24.13)
		(width 0.18796)
		(layer "F.Cu")
		(net "PRSNT_DBV2_SLIMSAS")
	)
	(segment
		(start 22.31136 -64.41948)
		(end 23.10638 -66.339212)
		(width 0.18796)
		(layer "F.Cu")
		(net "PRSNT_DBV2_SLIMSAS")
	)
	(segment
		(start 21.209 -32.893)
		(end 22.31136 -33.99536)
		(width 0.18796)
		(layer "F.Cu")
		(net "PRSNT_DBV2_SLIMSAS")
	)
	(segment
		(start 13.93825 -24.13)
		(end 13.730986 -23.922736)
		(width 0.18796)
		(layer "F.Cu")
		(net "PRSNT_DBV2_SLIMSAS")
	)
	(segment
		(start 15.113 -24.13)
		(end 13.93825 -24.13)
		(width 0.18796)
		(layer "F.Cu")
		(net "PRSNT_DBV2_SLIMSAS")
	)
	(segment
		(start 23.10638 -67.69862)
		(end 22.450044 -68.354956)
		(width 0.18796)
		(layer "F.Cu")
		(net "PRSNT_DBV2_SLIMSAS")
	)
	(segment
		(start 22.31136 -33.99536)
		(end 22.31136 -64.41948)
		(width 0.18796)
		(layer "F.Cu")
		(net "PRSNT_DBV2_SLIMSAS")
	)
	(segment
		(start 22.450044 -68.354956)
		(end 22.450044 -69.799962)
		(width 0.18796)
		(layer "F.Cu")
		(net "PRSNT_DBV2_SLIMSAS")
	)
	(segment
		(start 13.730986 -23.922736)
		(end 13.730986 -23.43404)
		(width 0.18796)
		(layer "F.Cu")
		(net "PRSNT_DBV2_SLIMSAS")
	)
	(via
		(at 15.113 -24.13)
		(size 0.508)
		(drill 0.254)
		(layers "F.Cu" "B.Cu")
		(net "PRSNT_DBV2_SLIMSAS")
	)
	(via
		(at 21.209 -32.893)
		(size 0.508)
		(drill 0.254)
		(layers "F.Cu" "B.Cu")
		(net "PRSNT_DBV2_SLIMSAS")
	)
	(segment
		(start 15.113 -29.073348)
		(end 18.932652 -32.893)
		(width 0.18796)
		(layer "B.Cu")
		(net "PRSNT_DBV2_SLIMSAS")
	)
	(segment
		(start 18.932652 -32.893)
		(end 21.209 -32.893)
		(width 0.18796)
		(layer "B.Cu")
		(net "PRSNT_DBV2_SLIMSAS")
	)
	(segment
		(start 15.113 -24.13)
		(end 15.113 -29.073348)
		(width 0.18796)
		(layer "B.Cu")
		(net "PRSNT_DBV2_SLIMSAS")
	)
	(segment
		(start 12.573 -24.638)
		(end 12.431014 -24.779986)
		(width 0.18796)
		(layer "F.Cu")
		(net "PRSNT_DBV2_USB_N")
	)
	(segment
		(start 13.081 -27.27198)
		(end 13.081 -26.67)
		(width 0.18796)
		(layer "F.Cu")
		(net "PRSNT_DBV2_USB_N")
	)
	(segment
		(start 13.081 -25.33396)
		(end 13.081 -26.67)
		(width 0.18796)
		(layer "F.Cu")
		(net "PRSNT_DBV2_USB_N")
	)
	(segment
		(start 13.081 -25.33396)
		(end 13.081 -24.771096)
		(width 0.18796)
		(layer "F.Cu")
		(net "PRSNT_DBV2_USB_N")
	)
	(segment
		(start 12.431014 -24.779986)
		(end 12.431014 -25.33396)
		(width 0.18796)
		(layer "F.Cu")
		(net "PRSNT_DBV2_USB_N")
	)
	(segment
		(start 13.06195 -27.94)
		(end 13.06195 -27.29103)
		(width 0.18796)
		(layer "F.Cu")
		(net "PRSNT_DBV2_USB_N")
	)
	(segment
		(start 13.081 -24.771096)
		(end 12.947904 -24.638)
		(width 0.18796)
		(layer "F.Cu")
		(net "PRSNT_DBV2_USB_N")
	)
	(segment
		(start 12.947904 -24.638)
		(end 12.573 -24.638)
		(width 0.18796)
		(layer "F.Cu")
		(net "PRSNT_DBV2_USB_N")
	)
	(segment
		(start 13.06195 -27.29103)
		(end 13.081 -27.27198)
		(width 0.18796)
		(layer "F.Cu")
		(net "PRSNT_DBV2_USB_N")
	)
	(via
		(at 13.081 -26.67)
		(size 0.762)
		(drill 0.381)
		(layers "F.Cu" "B.Cu")
		(net "PRSNT_DBV2_USB_N")
	)
	(segment
		(start 8.377936 -54.986936)
		(end 9.266936 -54.986936)
		(width 0.18796)
		(layer "F.Cu")
		(net "REV_ID<0>")
	)
	(segment
		(start 6.36905 -54.229)
		(end 7.62 -54.229)
		(width 0.18796)
		(layer "F.Cu")
		(net "REV_ID<0>")
	)
	(segment
		(start 6.36905 -54.229)
		(end 6.36905 -53.213)
		(width 0.18796)
		(layer "F.Cu")
		(net "REV_ID<0>")
	)
	(segment
		(start 7.62 -54.229)
		(end 8.377936 -54.986936)
		(width 0.18796)
		(layer "F.Cu")
		(net "REV_ID<0>")
	)
	(via
		(at 7.62 -54.229)
		(size 0.762)
		(drill 0.381)
		(layers "F.Cu" "B.Cu")
		(net "REV_ID<0>")
	)
	(segment
		(start 8.382 -55.636922)
		(end 9.266936 -55.636922)
		(width 0.18796)
		(layer "F.Cu")
		(net "REV_ID<1>")
	)
	(segment
		(start 7.62 -55.499)
		(end 7.112 -55.499)
		(width 0.18796)
		(layer "F.Cu")
		(net "REV_ID<1>")
	)
	(segment
		(start 6.36905 -55.245)
		(end 6.36905 -56.261)
		(width 0.18796)
		(layer "F.Cu")
		(net "REV_ID<1>")
	)
	(segment
		(start 7.112 -55.499)
		(end 6.858 -55.245)
		(width 0.18796)
		(layer "F.Cu")
		(net "REV_ID<1>")
	)
	(segment
		(start 6.858 -55.245)
		(end 6.36905 -55.245)
		(width 0.18796)
		(layer "F.Cu")
		(net "REV_ID<1>")
	)
	(segment
		(start 7.62 -55.499)
		(end 8.244078 -55.499)
		(width 0.18796)
		(layer "F.Cu")
		(net "REV_ID<1>")
	)
	(segment
		(start 8.244078 -55.499)
		(end 8.382 -55.636922)
		(width 0.18796)
		(layer "F.Cu")
		(net "REV_ID<1>")
	)
	(via
		(at 7.62 -55.499)
		(size 0.762)
		(drill 0.381)
		(layers "F.Cu" "B.Cu")
		(net "REV_ID<1>")
	)
	(segment
		(start 8.102092 -56.286908)
		(end 9.266936 -56.286908)
		(width 0.18796)
		(layer "F.Cu")
		(net "REV_ID<2>")
	)
	(segment
		(start 6.36905 -57.277)
		(end 6.36905 -58.293)
		(width 0.18796)
		(layer "F.Cu")
		(net "REV_ID<2>")
	)
	(segment
		(start 7.112 -57.277)
		(end 7.62 -56.769)
		(width 0.18796)
		(layer "F.Cu")
		(net "REV_ID<2>")
	)
	(segment
		(start 7.62 -56.769)
		(end 8.102092 -56.286908)
		(width 0.18796)
		(layer "F.Cu")
		(net "REV_ID<2>")
	)
	(segment
		(start 6.36905 -57.277)
		(end 7.112 -57.277)
		(width 0.18796)
		(layer "F.Cu")
		(net "REV_ID<2>")
	)
	(via
		(at 7.62 -56.769)
		(size 0.762)
		(drill 0.381)
		(layers "F.Cu" "B.Cu")
		(net "REV_ID<2>")
	)
	(segment
		(start 16.51 -13.588746)
		(end 16.51 -15.494)
		(width 0.18796)
		(layer "F.Cu")
		(net "PRSNT_DBV2_USB")
	)
	(segment
		(start 21.086318 -11.118342)
		(end 21.086318 -12.441428)
		(width 0.18796)
		(layer "F.Cu")
		(net "PRSNT_DBV2_USB")
	)
	(segment
		(start 27.479498 -15.825978)
		(end 27.479498 -14.802866)
		(width 0.18796)
		(layer "F.Cu")
		(net "PRSNT_DBV2_USB")
	)
	(segment
		(start 16.51 -15.494)
		(end 16.891 -15.875)
		(width 0.18796)
		(layer "F.Cu")
		(net "PRSNT_DBV2_USB")
	)
	(segment
		(start 27.258772 -16.046704)
		(end 27.479498 -15.825978)
		(width 0.18796)
		(layer "F.Cu")
		(net "PRSNT_DBV2_USB")
	)
	(segment
		(start 13.86205 -18.64995)
		(end 13.86205 -21.209)
		(width 0.18796)
		(layer "F.Cu")
		(net "PRSNT_DBV2_USB")
	)
	(segment
		(start 20.573746 -12.954)
		(end 17.144746 -12.954)
		(width 0.18796)
		(layer "F.Cu")
		(net "PRSNT_DBV2_USB")
	)
	(segment
		(start 26.475182 -12.378182)
		(end 24.477218 -10.380218)
		(width 0.18796)
		(layer "F.Cu")
		(net "PRSNT_DBV2_USB")
	)
	(segment
		(start 24.477218 -10.380218)
		(end 21.824442 -10.380218)
		(width 0.18796)
		(layer "F.Cu")
		(net "PRSNT_DBV2_USB")
	)
	(segment
		(start 27.479498 -14.802866)
		(end 26.475182 -12.378182)
		(width 0.18796)
		(layer "F.Cu")
		(net "PRSNT_DBV2_USB")
	)
	(segment
		(start 16.002 -17.399)
		(end 15.113 -17.399)
		(width 0.18796)
		(layer "F.Cu")
		(net "PRSNT_DBV2_USB")
	)
	(segment
		(start 21.086318 -12.441428)
		(end 20.573746 -12.954)
		(width 0.18796)
		(layer "F.Cu")
		(net "PRSNT_DBV2_USB")
	)
	(segment
		(start 13.081 -22.987)
		(end 13.081 -23.43404)
		(width 0.18796)
		(layer "F.Cu")
		(net "PRSNT_DBV2_USB")
	)
	(segment
		(start 21.824442 -10.380218)
		(end 21.086318 -11.118342)
		(width 0.18796)
		(layer "F.Cu")
		(net "PRSNT_DBV2_USB")
	)
	(segment
		(start 13.86205 -22.225)
		(end 13.10005 -22.987)
		(width 0.18796)
		(layer "F.Cu")
		(net "PRSNT_DBV2_USB")
	)
	(segment
		(start 13.86205 -21.209)
		(end 13.86205 -22.225)
		(width 0.18796)
		(layer "F.Cu")
		(net "PRSNT_DBV2_USB")
	)
	(segment
		(start 17.144746 -12.954)
		(end 16.51 -13.588746)
		(width 0.18796)
		(layer "F.Cu")
		(net "PRSNT_DBV2_USB")
	)
	(segment
		(start 13.10005 -22.987)
		(end 13.081 -22.987)
		(width 0.18796)
		(layer "F.Cu")
		(net "PRSNT_DBV2_USB")
	)
	(segment
		(start 16.891 -15.875)
		(end 16.891 -16.51)
		(width 0.18796)
		(layer "F.Cu")
		(net "PRSNT_DBV2_USB")
	)
	(segment
		(start 16.891 -16.51)
		(end 16.002 -17.399)
		(width 0.18796)
		(layer "F.Cu")
		(net "PRSNT_DBV2_USB")
	)
	(segment
		(start 15.113 -17.399)
		(end 13.86205 -18.64995)
		(width 0.18796)
		(layer "F.Cu")
		(net "PRSNT_DBV2_USB")
	)
	(via
		(at 27.258772 -16.046704)
		(size 0.508)
		(drill 0.254)
		(layers "F.Cu" "B.Cu")
		(net "PRSNT_DBV2_USB")
	)
	(segment
		(start 25.900126 -16.45539)
		(end 26.308812 -16.046704)
		(width 0.18796)
		(layer "B.Cu")
		(net "PRSNT_DBV2_USB")
	)
	(segment
		(start 25.900126 -17.329912)
		(end 25.900126 -16.45539)
		(width 0.18796)
		(layer "B.Cu")
		(net "PRSNT_DBV2_USB")
	)
	(segment
		(start 26.308812 -16.046704)
		(end 27.258772 -16.046704)
		(width 0.18796)
		(layer "B.Cu")
		(net "PRSNT_DBV2_USB")
	)
	(segment
		(start 16.4592 -58.928)
		(end 15.850108 -59.537092)
		(width 0.18796)
		(layer "F.Cu")
		(net "PCA9539_A0")
	)
	(segment
		(start 15.850108 -59.537092)
		(end 15.117064 -59.537092)
		(width 0.18796)
		(layer "F.Cu")
		(net "PCA9539_A0")
	)
	(segment
		(start 17.399 -58.801)
		(end 17.092422 -58.928)
		(width 0.18796)
		(layer "F.Cu")
		(net "PCA9539_A0")
	)
	(segment
		(start 18.01495 -58.801)
		(end 17.399 -58.801)
		(width 0.18796)
		(layer "F.Cu")
		(net "PCA9539_A0")
	)
	(segment
		(start 18.01495 -57.785)
		(end 18.01495 -58.801)
		(width 0.18796)
		(layer "F.Cu")
		(net "PCA9539_A0")
	)
	(segment
		(start 17.092422 -58.928)
		(end 16.4592 -58.928)
		(width 0.18796)
		(layer "F.Cu")
		(net "PCA9539_A0")
	)
	(via
		(at 17.399 -58.801)
		(size 0.508)
		(drill 0.254)
		(layers "F.Cu" "B.Cu")
		(net "PCA9539_A0")
	)
	(segment
		(start 6.36905 -62.357)
		(end 6.36905 -61.341)
		(width 0.18796)
		(layer "F.Cu")
		(net "PCA9539_A1")
	)
	(segment
		(start 8.123936 -60.837064)
		(end 7.62 -61.341)
		(width 0.18796)
		(layer "F.Cu")
		(net "PCA9539_A1")
	)
	(segment
		(start 9.266936 -60.837064)
		(end 8.123936 -60.837064)
		(width 0.18796)
		(layer "F.Cu")
		(net "PCA9539_A1")
	)
	(segment
		(start 7.62 -61.341)
		(end 6.36905 -61.341)
		(width 0.18796)
		(layer "F.Cu")
		(net "PCA9539_A1")
	)
	(via
		(at 7.62 -61.341)
		(size 0.762)
		(drill 0.381)
		(layers "F.Cu" "B.Cu")
		(net "PCA9539_A1")
	)
	(segment
		(start 10.403078 -60.187078)
		(end 9.266936 -60.187078)
		(width 0.18796)
		(layer "F.Cu")
		(net "RST_SMB_R_N")
	)
	(segment
		(start 10.77595 -60.55995)
		(end 10.403078 -60.187078)
		(width 0.18796)
		(layer "F.Cu")
		(net "RST_SMB_R_N")
	)
	(segment
		(start 10.77595 -62.738)
		(end 10.77595 -60.55995)
		(width 0.18796)
		(layer "F.Cu")
		(net "RST_SMB_R_N")
	)
	(segment
		(start 7.62 -60.071)
		(end 8.265922 -60.071)
		(width 0.18796)
		(layer "F.Cu")
		(net "RST_SMB_R_N")
	)
	(segment
		(start 6.858 -60.325)
		(end 6.36905 -60.325)
		(width 0.18796)
		(layer "F.Cu")
		(net "RST_SMB_R_N")
	)
	(segment
		(start 7.112 -60.071)
		(end 6.858 -60.325)
		(width 0.18796)
		(layer "F.Cu")
		(net "RST_SMB_R_N")
	)
	(segment
		(start 8.265922 -60.071)
		(end 8.382 -60.187078)
		(width 0.18796)
		(layer "F.Cu")
		(net "RST_SMB_R_N")
	)
	(segment
		(start 8.382 -60.187078)
		(end 9.266936 -60.187078)
		(width 0.18796)
		(layer "F.Cu")
		(net "RST_SMB_R_N")
	)
	(segment
		(start 7.62 -60.071)
		(end 7.112 -60.071)
		(width 0.18796)
		(layer "F.Cu")
		(net "RST_SMB_R_N")
	)
	(segment
		(start 6.36905 -59.309)
		(end 6.36905 -60.325)
		(width 0.18796)
		(layer "F.Cu")
		(net "RST_SMB_R_N")
	)
	(via
		(at 7.62 -60.071)
		(size 0.762)
		(drill 0.381)
		(layers "F.Cu" "B.Cu")
		(net "RST_SMB_R_N")
	)
	(segment
		(start 20.066 -50.207418)
		(end 21.844 -48.429418)
		(width 0.18796)
		(layer "F.Cu")
		(net "PWR_LED_R1")
	)
	(segment
		(start 15.113 -29.96184)
		(end 6.46684 -29.96184)
		(width 0.18796)
		(layer "F.Cu")
		(net "PWR_LED_R1")
	)
	(segment
		(start 5.602986 -29.097986)
		(end 4.9149 -29.097986)
		(width 0.18796)
		(layer "F.Cu")
		(net "PWR_LED_R1")
	)
	(segment
		(start 3.44805 -29.083)
		(end 4.272534 -29.083)
		(width 0.18796)
		(layer "F.Cu")
		(net "PWR_LED_R1")
	)
	(segment
		(start 6.46684 -29.96184)
		(end 5.602986 -29.097986)
		(width 0.18796)
		(layer "F.Cu")
		(net "PWR_LED_R1")
	)
	(segment
		(start 4.272534 -29.083)
		(end 4.28752 -29.097986)
		(width 0.18796)
		(layer "F.Cu")
		(net "PWR_LED_R1")
	)
	(segment
		(start 4.28752 -29.097986)
		(end 4.9149 -29.097986)
		(width 0.18796)
		(layer "F.Cu")
		(net "PWR_LED_R1")
	)
	(segment
		(start 3.44805 -28.067)
		(end 3.44805 -29.083)
		(width 0.18796)
		(layer "F.Cu")
		(net "PWR_LED_R1")
	)
	(segment
		(start 20.066 -56.769)
		(end 18.81505 -56.769)
		(width 0.18796)
		(layer "F.Cu")
		(net "PWR_LED_R1")
	)
	(segment
		(start 21.844 -48.429418)
		(end 21.844 -34.417)
		(width 0.18796)
		(layer "F.Cu")
		(net "PWR_LED_R1")
	)
	(segment
		(start 20.066 -56.769)
		(end 20.066 -50.207418)
		(width 0.18796)
		(layer "F.Cu")
		(net "PWR_LED_R1")
	)
	(segment
		(start 21.844 -34.417)
		(end 21.209 -33.782)
		(width 0.18796)
		(layer "F.Cu")
		(net "PWR_LED_R1")
	)
	(via
		(at 20.066 -56.769)
		(size 0.762)
		(drill 0.381)
		(layers "F.Cu" "B.Cu")
		(net "PWR_LED_R1")
	)
	(via
		(at 15.113 -29.96184)
		(size 0.508)
		(drill 0.254)
		(layers "F.Cu" "B.Cu")
		(net "PWR_LED_R1")
	)
	(via
		(at 21.209 -33.782)
		(size 0.508)
		(drill 0.254)
		(layers "F.Cu" "B.Cu")
		(net "PWR_LED_R1")
	)
	(segment
		(start 18.93316 -33.782)
		(end 21.209 -33.782)
		(width 0.18796)
		(layer "B.Cu")
		(net "PWR_LED_R1")
	)
	(segment
		(start 15.113 -29.96184)
		(end 18.93316 -33.782)
		(width 0.18796)
		(layer "B.Cu")
		(net "PWR_LED_R1")
	)
	(segment
		(start 17.648428 -30.230826)
		(end 17.237202 -30.642052)
		(width 0.18796)
		(layer "F.Cu")
		(net "SYSTEM_FAULT_ID_LED_R1")
	)
	(segment
		(start 3.897884 -26.289)
		(end 3.91287 -26.303986)
		(width 0.18796)
		(layer "F.Cu")
		(net "SYSTEM_FAULT_ID_LED_R1")
	)
	(segment
		(start 3.44805 -26.90495)
		(end 3.44805 -26.289)
		(width 0.18796)
		(layer "F.Cu")
		(net "SYSTEM_FAULT_ID_LED_R1")
	)
	(segment
		(start 4.064 -30.353)
		(end 2.286 -30.353)
		(width 0.18796)
		(layer "F.Cu")
		(net "SYSTEM_FAULT_ID_LED_R1")
	)
	(segment
		(start 3.44805 -25.273)
		(end 3.44805 -26.289)
		(width 0.18796)
		(layer "F.Cu")
		(net "SYSTEM_FAULT_ID_LED_R1")
	)
	(segment
		(start 1.397 -27.432)
		(end 1.778 -27.051)
		(width 0.18796)
		(layer "F.Cu")
		(net "SYSTEM_FAULT_ID_LED_R1")
	)
	(segment
		(start 18.81505 -55.753)
		(end 18.81505 -50.905156)
		(width 0.18796)
		(layer "F.Cu")
		(net "SYSTEM_FAULT_ID_LED_R1")
	)
	(segment
		(start 21.336 -34.670746)
		(end 19.939 -33.273746)
		(width 0.18796)
		(layer "F.Cu")
		(net "SYSTEM_FAULT_ID_LED_R1")
	)
	(segment
		(start 1.778 -27.051)
		(end 3.302 -27.051)
		(width 0.18796)
		(layer "F.Cu")
		(net "SYSTEM_FAULT_ID_LED_R1")
	)
	(segment
		(start 19.75104 -30.230826)
		(end 17.648428 -30.230826)
		(width 0.18796)
		(layer "F.Cu")
		(net "SYSTEM_FAULT_ID_LED_R1")
	)
	(segment
		(start 21.336 -48.384206)
		(end 21.336 -34.670746)
		(width 0.18796)
		(layer "F.Cu")
		(net "SYSTEM_FAULT_ID_LED_R1")
	)
	(segment
		(start 19.939 -33.273746)
		(end 19.939 -30.418786)
		(width 0.18796)
		(layer "F.Cu")
		(net "SYSTEM_FAULT_ID_LED_R1")
	)
	(segment
		(start 1.397 -29.464)
		(end 1.397 -27.432)
		(width 0.18796)
		(layer "F.Cu")
		(net "SYSTEM_FAULT_ID_LED_R1")
	)
	(segment
		(start 3.44805 -26.289)
		(end 3.897884 -26.289)
		(width 0.18796)
		(layer "F.Cu")
		(net "SYSTEM_FAULT_ID_LED_R1")
	)
	(segment
		(start 14.766798 -30.642052)
		(end 14.477746 -30.353)
		(width 0.18796)
		(layer "F.Cu")
		(net "SYSTEM_FAULT_ID_LED_R1")
	)
	(segment
		(start 3.91287 -26.303986)
		(end 4.9149 -26.303986)
		(width 0.18796)
		(layer "F.Cu")
		(net "SYSTEM_FAULT_ID_LED_R1")
	)
	(segment
		(start 18.81505 -50.905156)
		(end 21.336 -48.384206)
		(width 0.18796)
		(layer "F.Cu")
		(net "SYSTEM_FAULT_ID_LED_R1")
	)
	(segment
		(start 14.477746 -30.353)
		(end 4.064 -30.353)
		(width 0.18796)
		(layer "F.Cu")
		(net "SYSTEM_FAULT_ID_LED_R1")
	)
	(segment
		(start 2.286 -30.353)
		(end 1.397 -29.464)
		(width 0.18796)
		(layer "F.Cu")
		(net "SYSTEM_FAULT_ID_LED_R1")
	)
	(segment
		(start 19.939 -30.418786)
		(end 19.75104 -30.230826)
		(width 0.18796)
		(layer "F.Cu")
		(net "SYSTEM_FAULT_ID_LED_R1")
	)
	(segment
		(start 17.237202 -30.642052)
		(end 14.766798 -30.642052)
		(width 0.18796)
		(layer "F.Cu")
		(net "SYSTEM_FAULT_ID_LED_R1")
	)
	(segment
		(start 3.302 -27.051)
		(end 3.44805 -26.90495)
		(width 0.18796)
		(layer "F.Cu")
		(net "SYSTEM_FAULT_ID_LED_R1")
	)
	(via
		(at 4.064 -30.353)
		(size 0.762)
		(drill 0.381)
		(layers "F.Cu" "B.Cu")
		(net "SYSTEM_FAULT_ID_LED_R1")
	)
	(segment
		(start 26.317448 -29.562298)
		(end 28.311094 -27.568652)
		(width 0.14732)
		(layer "F.Cu")
		(net "USB2_DP")
	)
	(segment
		(start 26.477214 -67.945762)
		(end 25.64511 -66.700908)
		(width 0.14732)
		(layer "F.Cu")
		(net "USB2_DP")
	)
	(segment
		(start 26.477214 -69.057774)
		(end 26.477214 -67.945762)
		(width 0.14732)
		(layer "F.Cu")
		(net "USB2_DP")
	)
	(segment
		(start 31.129986 -26.400506)
		(end 31.736792 -25.7937)
		(width 0.14732)
		(layer "F.Cu")
		(net "USB2_DP")
	)
	(segment
		(start 25.64511 -66.700908)
		(end 24.648668 -64.294766)
		(width 0.14732)
		(layer "F.Cu")
		(net "USB2_DP")
	)
	(segment
		(start 26.650188 -69.230748)
		(end 26.477214 -69.057774)
		(width 0.14732)
		(layer "F.Cu")
		(net "USB2_DP")
	)
	(segment
		(start 31.736792 -25.7937)
		(end 31.736792 -25.28062)
		(width 0.14732)
		(layer "F.Cu")
		(net "USB2_DP")
	)
	(segment
		(start 32.034734 -24.197818)
		(end 32.034734 -24.705818)
		(width 0.14732)
		(layer "F.Cu")
		(net "USB2_DP")
	)
	(segment
		(start 28.311094 -27.568652)
		(end 31.129986 -26.400506)
		(width 0.14732)
		(layer "F.Cu")
		(net "USB2_DP")
	)
	(segment
		(start 24.648668 -64.294766)
		(end 26.317448 -29.562298)
		(width 0.14732)
		(layer "F.Cu")
		(net "USB2_DP")
	)
	(segment
		(start 26.650188 -69.799962)
		(end 26.650188 -69.230748)
		(width 0.14732)
		(layer "F.Cu")
		(net "USB2_DP")
	)
	(segment
		(start 31.736792 -25.28062)
		(end 32.034734 -24.982678)
		(width 0.14732)
		(layer "F.Cu")
		(net "USB2_DP")
	)
	(segment
		(start 32.034734 -24.982678)
		(end 32.034734 -24.705818)
		(width 0.14732)
		(layer "F.Cu")
		(net "USB2_DP")
	)
	(segment
		(start 30.985968 -26.185114)
		(end 31.482792 -25.68829)
		(width 0.14732)
		(layer "F.Cu")
		(net "USB2_DN")
	)
	(segment
		(start 25.419812 -66.821304)
		(end 24.392128 -64.33947)
		(width 0.14732)
		(layer "F.Cu")
		(net "USB2_DN")
	)
	(segment
		(start 26.049986 -69.799962)
		(end 26.049986 -69.231002)
		(width 0.14732)
		(layer "F.Cu")
		(net "USB2_DN")
	)
	(segment
		(start 28.167076 -27.35326)
		(end 30.985968 -26.185114)
		(width 0.14732)
		(layer "F.Cu")
		(net "USB2_DN")
	)
	(segment
		(start 31.18485 -24.982678)
		(end 31.18485 -24.705818)
		(width 0.14732)
		(layer "F.Cu")
		(net "USB2_DN")
	)
	(segment
		(start 31.482792 -25.28062)
		(end 31.18485 -24.982678)
		(width 0.14732)
		(layer "F.Cu")
		(net "USB2_DN")
	)
	(segment
		(start 26.068274 -29.452062)
		(end 28.167076 -27.35326)
		(width 0.14732)
		(layer "F.Cu")
		(net "USB2_DN")
	)
	(segment
		(start 26.223214 -69.057774)
		(end 26.223214 -68.022978)
		(width 0.14732)
		(layer "F.Cu")
		(net "USB2_DN")
	)
	(segment
		(start 31.482792 -25.68829)
		(end 31.482792 -25.28062)
		(width 0.14732)
		(layer "F.Cu")
		(net "USB2_DN")
	)
	(segment
		(start 31.18485 -24.197818)
		(end 31.18485 -24.705818)
		(width 0.14732)
		(layer "F.Cu")
		(net "USB2_DN")
	)
	(segment
		(start 25.821386 -67.422014)
		(end 25.821132 -67.421506)
		(width 0.14732)
		(layer "F.Cu")
		(net "USB2_DN")
	)
	(segment
		(start 25.821132 -67.421506)
		(end 25.419812 -66.821304)
		(width 0.14732)
		(layer "F.Cu")
		(net "USB2_DN")
	)
	(segment
		(start 24.392128 -64.33947)
		(end 26.068274 -29.452062)
		(width 0.14732)
		(layer "F.Cu")
		(net "USB2_DN")
	)
	(segment
		(start 26.049986 -69.231002)
		(end 26.223214 -69.057774)
		(width 0.14732)
		(layer "F.Cu")
		(net "USB2_DN")
	)
	(segment
		(start 26.223214 -68.022978)
		(end 25.821386 -67.422014)
		(width 0.14732)
		(layer "F.Cu")
		(net "USB2_DN")
	)
	(segment
		(start 22.450044 -72.904096)
		(end 22.750018 -73.20407)
		(width 0.381)
		(layer "F.Cu")
		(net "P5V_STBY")
	)
	(segment
		(start 9.92505 -26.289)
		(end 10.541 -26.289)
		(width 0.4572)
		(layer "F.Cu")
		(net "P5V_STBY")
	)
	(segment
		(start 9.92505 -29.083)
		(end 10.423652 -28.584398)
		(width 0.4572)
		(layer "F.Cu")
		(net "P5V_STBY")
	)
	(segment
		(start 16.1544 -9.4234)
		(end 16.1544 -8.684768)
		(width 0.4572)
		(layer "F.Cu")
		(net "P5V_STBY")
	)
	(segment
		(start 17.650206 -72.904096)
		(end 17.650206 -72.14997)
		(width 0.381)
		(layer "F.Cu")
		(net "P5V_STBY")
	)
	(segment
		(start 17.050004 -72.903842)
		(end 17.350232 -73.20407)
		(width 0.381)
		(layer "F.Cu")
		(net "P5V_STBY")
	)
	(segment
		(start 24.85009 -72.904096)
		(end 24.85009 -72.14997)
		(width 0.381)
		(layer "F.Cu")
		(net "P5V_STBY")
	)
	(segment
		(start 19.45005 -72.904096)
		(end 19.150076 -73.20407)
		(width 0.381)
		(layer "F.Cu")
		(net "P5V_STBY")
	)
	(segment
		(start 24.250142 -72.14997)
		(end 24.250142 -72.904096)
		(width 0.381)
		(layer "F.Cu")
		(net "P5V_STBY")
	)
	(segment
		(start 17.350232 -73.20407)
		(end 17.650206 -72.904096)
		(width 0.381)
		(layer "F.Cu")
		(net "P5V_STBY")
	)
	(segment
		(start 13.06195 -20.72005)
		(end 13.06195 -21.209)
		(width 0.4572)
		(layer "F.Cu")
		(net "P5V_STBY")
	)
	(segment
		(start 24.250142 -72.904096)
		(end 24.550116 -73.20407)
		(width 0.381)
		(layer "F.Cu")
		(net "P5V_STBY")
	)
	(segment
		(start 18.850102 -72.904096)
		(end 18.850102 -72.14997)
		(width 0.381)
		(layer "F.Cu")
		(net "P5V_STBY")
	)
	(segment
		(start 23.049992 -72.904096)
		(end 23.049992 -72.14997)
		(width 0.381)
		(layer "F.Cu")
		(net "P5V_STBY")
	)
	(segment
		(start 17.050004 -72.14997)
		(end 17.050004 -72.903842)
		(width 0.381)
		(layer "F.Cu")
		(net "P5V_STBY")
	)
	(segment
		(start 19.49577 -11.917934)
		(end 18.42897 -11.917934)
		(width 0.4572)
		(layer "F.Cu")
		(net "P5V_STBY")
	)
	(segment
		(start 19.150076 -73.20407)
		(end 18.850102 -72.904096)
		(width 0.381)
		(layer "F.Cu")
		(net "P5V_STBY")
	)
	(segment
		(start 13.208 -20.574)
		(end 13.06195 -20.72005)
		(width 0.4572)
		(layer "F.Cu")
		(net "P5V_STBY")
	)
	(segment
		(start 24.550116 -73.20407)
		(end 24.85009 -72.904096)
		(width 0.381)
		(layer "F.Cu")
		(net "P5V_STBY")
	)
	(segment
		(start 19.45005 -72.14997)
		(end 19.45005 -72.904096)
		(width 0.381)
		(layer "F.Cu")
		(net "P5V_STBY")
	)
	(segment
		(start 22.750018 -73.20407)
		(end 23.049992 -72.904096)
		(width 0.381)
		(layer "F.Cu")
		(net "P5V_STBY")
	)
	(segment
		(start 2.62001 -5.100066)
		(end 2.62001 -3.302)
		(width 0.4572)
		(layer "F.Cu")
		(net "P5V_STBY")
	)
	(segment
		(start 22.450044 -72.14997)
		(end 22.450044 -72.904096)
		(width 0.381)
		(layer "F.Cu")
		(net "P5V_STBY")
	)
	(via
		(at 17.350232 -73.20407)
		(size 0.508)
		(drill 0.254)
		(layers "F.Cu" "B.Cu")
		(net "P5V_STBY")
	)
	(via
		(at 29.21 -37.338)
		(size 0.508)
		(drill 0.254)
		(layers "F.Cu" "B.Cu")
		(net "P5V_STBY")
	)
	(via
		(at 28.448 -37.338)
		(size 0.508)
		(drill 0.254)
		(layers "F.Cu" "B.Cu")
		(net "P5V_STBY")
	)
	(via
		(at 16.891 -65.532)
		(size 0.508)
		(drill 0.254)
		(layers "F.Cu" "B.Cu")
		(net "P5V_STBY")
	)
	(via
		(at 13.208 -20.574)
		(size 0.508)
		(drill 0.254)
		(layers "F.Cu" "B.Cu")
		(net "P5V_STBY")
	)
	(via
		(at 24.550116 -73.20407)
		(size 0.508)
		(drill 0.254)
		(layers "F.Cu" "B.Cu")
		(net "P5V_STBY")
	)
	(via
		(at 2.62001 -3.302)
		(size 0.508)
		(drill 0.254)
		(layers "F.Cu" "B.Cu")
		(net "P5V_STBY")
	)
	(via
		(at 10.541 -26.289)
		(size 0.508)
		(drill 0.254)
		(layers "F.Cu" "B.Cu")
		(net "P5V_STBY")
	)
	(via
		(at 22.750018 -73.20407)
		(size 0.508)
		(drill 0.254)
		(layers "F.Cu" "B.Cu")
		(net "P5V_STBY")
	)
	(via
		(at 16.256 -65.532)
		(size 0.508)
		(drill 0.254)
		(layers "F.Cu" "B.Cu")
		(net "P5V_STBY")
	)
	(via
		(at 28.448 -38.227)
		(size 0.508)
		(drill 0.254)
		(layers "F.Cu" "B.Cu")
		(net "P5V_STBY")
	)
	(via
		(at 18.42897 -11.917934)
		(size 0.508)
		(drill 0.254)
		(layers "F.Cu" "B.Cu")
		(net "P5V_STBY")
	)
	(via
		(at 16.1544 -8.684768)
		(size 0.508)
		(drill 0.254)
		(layers "F.Cu" "B.Cu")
		(net "P5V_STBY")
	)
	(via
		(at 10.423652 -28.584398)
		(size 0.508)
		(drill 0.254)
		(layers "F.Cu" "B.Cu")
		(net "P5V_STBY")
	)
	(via
		(at 29.21 -38.227)
		(size 0.508)
		(drill 0.254)
		(layers "F.Cu" "B.Cu")
		(net "P5V_STBY")
	)
	(via
		(at 19.150076 -73.20407)
		(size 0.508)
		(drill 0.254)
		(layers "F.Cu" "B.Cu")
		(net "P5V_STBY")
	)
	(segment
		(start 20.049998 -69.799962)
		(end 20.049998 -68.745862)
		(width 0.381)
		(layer "F.Cu")
		(net "GND")
	)
	(segment
		(start 3.53695 -50.8)
		(end 2.921 -50.8)
		(width 0.4572)
		(layer "F.Cu")
		(net "GND")
	)
	(segment
		(start 15.134844 -11.076432)
		(end 15.134844 -10.16)
		(width 0.4572)
		(layer "F.Cu")
		(net "GND")
	)
	(segment
		(start 19.4056 -66.294)
		(end 19.4056 -65.532)
		(width 0.4572)
		(layer "F.Cu")
		(net "GND")
	)
	(segment
		(start 20.049998 -72.903842)
		(end 20.350226 -73.20407)
		(width 0.381)
		(layer "F.Cu")
		(net "GND")
	)
	(segment
		(start 30.099 -1.705864)
		(end 31.237682 -1.705864)
		(width 0.4572)
		(layer "F.Cu")
		(net "GND")
	)
	(segment
		(start 23.650194 -69.799962)
		(end 23.650194 -68.745862)
		(width 0.381)
		(layer "F.Cu")
		(net "GND")
	)
	(segment
		(start 18.250154 -72.14997)
		(end 18.250154 -73.20407)
		(width 0.381)
		(layer "F.Cu")
		(net "GND")
	)
	(segment
		(start 15.1384 -66.294)
		(end 14.351 -66.294)
		(width 0.4572)
		(layer "F.Cu")
		(net "GND")
	)
	(segment
		(start 20.049998 -72.14997)
		(end 20.049998 -72.903842)
		(width 0.381)
		(layer "F.Cu")
		(net "GND")
	)
	(segment
		(start 12.431014 -23.43404)
		(end 12.431014 -22.733)
		(width 0.4572)
		(layer "F.Cu")
		(net "GND")
	)
	(segment
		(start 18.704052 -67.453002)
		(end 18.704052 -67.853306)
		(width 0.381)
		(layer "F.Cu")
		(net "GND")
	)
	(segment
		(start 16.27505 -50.165)
		(end 16.27505 -50.8)
		(width 0.4572)
		(layer "F.Cu")
		(net "GND")
	)
	(segment
		(start 26.950162 -73.20407)
		(end 27.250136 -72.904096)
		(width 0.381)
		(layer "F.Cu")
		(net "GND")
	)
	(segment
		(start 27.250136 -72.904096)
		(end 27.250136 -72.14997)
		(width 0.381)
		(layer "F.Cu")
		(net "GND")
	)
	(segment
		(start 27.71013 -22.69998)
		(end 27.71013 -24.609806)
		(width 0.4572)
		(layer "F.Cu")
		(net "GND")
	)
	(segment
		(start 15.00505 -51.181)
		(end 15.00505 -51.816)
		(width 0.4572)
		(layer "F.Cu")
		(net "GND")
	)
	(segment
		(start 3.53695 -48.768)
		(end 2.921 -48.768)
		(width 0.4572)
		(layer "F.Cu")
		(net "GND")
	)
	(segment
		(start 26.049986 -72.904096)
		(end 26.049986 -72.14997)
		(width 0.381)
		(layer "F.Cu")
		(net "GND")
	)
	(segment
		(start 21.250148 -72.904096)
		(end 21.250148 -72.14997)
		(width 0.381)
		(layer "F.Cu")
		(net "GND")
	)
	(segment
		(start 4.064 -25.004014)
		(end 4.9149 -25.004014)
		(width 0.4572)
		(layer "F.Cu")
		(net "GND")
	)
	(segment
		(start 27.71013 -24.609806)
		(end 25.002998 -27.316938)
		(width 0.4572)
		(layer "F.Cu")
		(net "GND")
	)
	(segment
		(start 37.719 -22.352)
		(end 37.10305 -22.352)
		(width 0.4572)
		(layer "F.Cu")
		(net "GND")
	)
	(segment
		(start 26.650188 -72.14997)
		(end 26.650188 -72.904096)
		(width 0.381)
		(layer "F.Cu")
		(net "GND")
	)
	(segment
		(start 37.10305 -26.416)
		(end 37.719 -26.416)
		(width 0.4572)
		(layer "F.Cu")
		(net "GND")
	)
	(segment
		(start 20.6502 -72.904096)
		(end 20.6502 -72.14997)
		(width 0.381)
		(layer "F.Cu")
		(net "GND")
	)
	(segment
		(start 5.56895 -60.325)
		(end 4.953 -60.325)
		(width 0.4572)
		(layer "F.Cu")
		(net "GND")
	)
	(segment
		(start 29.888434 -6.911594)
		(end 28.747974 -8.052054)
		(width 0.4572)
		(layer "F.Cu")
		(net "GND")
	)
	(segment
		(start 2.64795 -28.067)
		(end 2.032 -28.067)
		(width 0.4572)
		(layer "F.Cu")
		(net "GND")
	)
	(segment
		(start 10.414 -54.237128)
		(end 9.266936 -54.237128)
		(width 0.4572)
		(layer "F.Cu")
		(net "GND")
	)
	(segment
		(start 21.550122 -73.20407)
		(end 21.250148 -72.904096)
		(width 0.381)
		(layer "F.Cu")
		(net "GND")
	)
	(segment
		(start 5.56895 -58.293)
		(end 4.953 -58.293)
		(width 0.4572)
		(layer "F.Cu")
		(net "GND")
	)
	(segment
		(start 15.22095 -67.672204)
		(end 15.22095 -67.437)
		(width 0.381)
		(layer "F.Cu")
		(net "GND")
	)
	(segment
		(start 19.655028 -15.673578)
		(end 19.655028 -14.732)
		(width 0.4572)
		(layer "F.Cu")
		(net "GND")
	)
	(segment
		(start 15.22095 -67.672204)
		(end 16.450056 -68.90131)
		(width 0.381)
		(layer "F.Cu")
		(net "GND")
	)
	(segment
		(start 26.650188 -72.904096)
		(end 26.950162 -73.20407)
		(width 0.381)
		(layer "F.Cu")
		(net "GND")
	)
	(segment
		(start 18.81505 -57.785)
		(end 19.431 -57.785)
		(width 0.4572)
		(layer "F.Cu")
		(net "GND")
	)
	(segment
		(start 18.704052 -67.453002)
		(end 18.68805 -67.437)
		(width 0.381)
		(layer "F.Cu")
		(net "GND")
	)
	(segment
		(start 18.704052 -67.853306)
		(end 18.250154 -68.307204)
		(width 0.381)
		(layer "F.Cu")
		(net "GND")
	)
	(segment
		(start 32.60979 -19.413474)
		(end 32.60979 -20.32)
		(width 0.4572)
		(layer "F.Cu")
		(net "GND")
	)
	(segment
		(start 25.750012 -73.20407)
		(end 26.049986 -72.904096)
		(width 0.381)
		(layer "F.Cu")
		(net "GND")
	)
	(segment
		(start 12.431014 -22.733)
		(end 12.939014 -22.225)
		(width 0.4572)
		(layer "F.Cu")
		(net "GND")
	)
	(segment
		(start 21.850096 -72.14997)
		(end 21.850096 -72.904096)
		(width 0.381)
		(layer "F.Cu")
		(net "GND")
	)
	(segment
		(start 25.450038 -69.799962)
		(end 25.450038 -68.745862)
		(width 0.381)
		(layer "F.Cu")
		(net "GND")
	)
	(segment
		(start 37.719 -20.32)
		(end 37.10305 -20.32)
		(width 0.4572)
		(layer "F.Cu")
		(net "GND")
	)
	(segment
		(start 30.879034 -29.591)
		(end 29.972 -29.591)
		(width 0.4572)
		(layer "F.Cu")
		(net "GND")
	)
	(segment
		(start 30.673802 -6.911594)
		(end 29.888434 -6.911594)
		(width 0.4572)
		(layer "F.Cu")
		(net "GND")
	)
	(segment
		(start 12.939014 -22.225)
		(end 13.06195 -22.225)
		(width 0.4572)
		(layer "F.Cu")
		(net "GND")
	)
	(segment
		(start 5.56895 -56.261)
		(end 4.953 -56.261)
		(width 0.4572)
		(layer "F.Cu")
		(net "GND")
	)
	(segment
		(start 21.850096 -72.904096)
		(end 21.550122 -73.20407)
		(width 0.381)
		(layer "F.Cu")
		(net "GND")
	)
	(segment
		(start 17.54505 -62.103)
		(end 17.54505 -62.738)
		(width 0.4572)
		(layer "F.Cu")
		(net "GND")
	)
	(segment
		(start 4.064 -27.798014)
		(end 4.9149 -27.798014)
		(width 0.4572)
		(layer "F.Cu")
		(net "GND")
	)
	(segment
		(start 18.250154 -68.307204)
		(end 18.250154 -69.799962)
		(width 0.381)
		(layer "F.Cu")
		(net "GND")
	)
	(segment
		(start 20.350226 -73.20407)
		(end 20.6502 -72.904096)
		(width 0.381)
		(layer "F.Cu")
		(net "GND")
	)
	(segment
		(start 25.450038 -72.14997)
		(end 25.450038 -72.904096)
		(width 0.381)
		(layer "F.Cu")
		(net "GND")
	)
	(segment
		(start 7.256018 -47.244)
		(end 8.382 -47.244)
		(width 0.508)
		(layer "F.Cu")
		(net "GND")
	)
	(segment
		(start 13.730986 -26.035)
		(end 13.730986 -25.33396)
		(width 0.4572)
		(layer "F.Cu")
		(net "GND")
	)
	(segment
		(start 19.673062 -19.685)
		(end 19.673062 -20.430998)
		(width 0.4572)
		(layer "F.Cu")
		(net "GND")
	)
	(segment
		(start 25.450038 -72.904096)
		(end 25.750012 -73.20407)
		(width 0.381)
		(layer "F.Cu")
		(net "GND")
	)
	(segment
		(start 5.56895 -54.229)
		(end 4.953 -54.229)
		(width 0.4572)
		(layer "F.Cu")
		(net "GND")
	)
	(segment
		(start 16.450056 -72.14997)
		(end 16.450056 -73.20407)
		(width 0.381)
		(layer "F.Cu")
		(net "GND")
	)
	(segment
		(start 21.850096 -69.799962)
		(end 21.850096 -68.745862)
		(width 0.381)
		(layer "F.Cu")
		(net "GND")
	)
	(segment
		(start 27.250136 -69.799962)
		(end 27.250136 -68.745862)
		(width 0.381)
		(layer "F.Cu")
		(net "GND")
	)
	(segment
		(start 2.64795 -25.273)
		(end 2.032 -25.273)
		(width 0.4572)
		(layer "F.Cu")
		(net "GND")
	)
	(segment
		(start 3.53695 -46.736)
		(end 2.921 -46.736)
		(width 0.4572)
		(layer "F.Cu")
		(net "GND")
	)
	(segment
		(start 16.450056 -68.90131)
		(end 16.450056 -69.799962)
		(width 0.381)
		(layer "F.Cu")
		(net "GND")
	)
	(segment
		(start 5.56895 -62.357)
		(end 4.953 -62.357)
		(width 0.4572)
		(layer "F.Cu")
		(net "GND")
	)
	(segment
		(start 23.650194 -72.14997)
		(end 23.650194 -73.20407)
		(width 0.381)
		(layer "F.Cu")
		(net "GND")
	)
	(segment
		(start 37.10305 -24.384)
		(end 37.719 -24.384)
		(width 0.4572)
		(layer "F.Cu")
		(net "GND")
	)
	(via
		(at 26.181304 -85.381084)
		(size 0.508)
		(drill 0.254)
		(layers "F.Cu" "B.Cu")
		(net "GND")
	)
	(via
		(at 0.763016 -27.042872)
		(size 0.508)
		(drill 0.254)
		(layers "F.Cu" "B.Cu")
		(net "GND")
	)
	(via
		(at 0.763016 -62.602872)
		(size 0.508)
		(drill 0.254)
		(layers "F.Cu" "B.Cu")
		(net "GND")
	)
	(via
		(at 25.750012 -73.20407)
		(size 0.508)
		(drill 0.254)
		(layers "F.Cu" "B.Cu")
		(net "GND")
	)
	(via
		(at 33.655 -52.705)
		(size 0.6604)
		(drill 0.3302)
		(layers "F.Cu" "B.Cu")
		(net "GND")
	)
	(via
		(at 34.781744 -0.77089)
		(size 0.508)
		(drill 0.254)
		(layers "F.Cu" "B.Cu")
		(net "GND")
	)
	(via
		(at 4.064 -25.004014)
		(size 0.508)
		(drill 0.254)
		(layers "F.Cu" "B.Cu")
		(net "GND")
	)
	(via
		(at 16.450056 -73.20407)
		(size 0.508)
		(drill 0.254)
		(layers "F.Cu" "B.Cu")
		(net "GND")
	)
	(via
		(at 21.850096 -68.745862)
		(size 0.508)
		(drill 0.254)
		(layers "F.Cu" "B.Cu")
		(net "GND")
	)
	(via
		(at 33.655 -50.8)
		(size 0.6604)
		(drill 0.3302)
		(layers "F.Cu" "B.Cu")
		(net "GND")
	)
	(via
		(at 37.465 -48.895)
		(size 0.6604)
		(drill 0.3302)
		(layers "F.Cu" "B.Cu")
		(net "GND")
	)
	(via
		(at 14.6812 -67.0306)
		(size 0.508)
		(drill 0.254)
		(layers "F.Cu" "B.Cu")
		(net "GND")
	)
	(via
		(at 35.56 -48.895)
		(size 0.6604)
		(drill 0.3302)
		(layers "F.Cu" "B.Cu")
		(net "GND")
	)
	(via
		(at 35.56 -54.61)
		(size 0.6604)
		(drill 0.3302)
		(layers "F.Cu" "B.Cu")
		(net "GND")
	)
	(via
		(at 0.763016 -47.362872)
		(size 0.508)
		(drill 0.254)
		(layers "F.Cu" "B.Cu")
		(net "GND")
	)
	(via
		(at 32.60979 -20.32)
		(size 0.508)
		(drill 0.254)
		(layers "F.Cu" "B.Cu")
		(net "GND")
	)
	(via
		(at 20.049998 -68.745862)
		(size 0.508)
		(drill 0.254)
		(layers "F.Cu" "B.Cu")
		(net "GND")
	)
	(via
		(at 34.600134 -7.98195)
		(size 0.508)
		(drill 0.254)
		(layers "F.Cu" "B.Cu")
		(net "GND")
	)
	(via
		(at 2.032 -25.273)
		(size 0.508)
		(drill 0.254)
		(layers "F.Cu" "B.Cu")
		(net "GND")
	)
	(via
		(at 0.763016 -32.122872)
		(size 0.508)
		(drill 0.254)
		(layers "F.Cu" "B.Cu")
		(net "GND")
	)
	(via
		(at 37.719 -20.32)
		(size 0.508)
		(drill 0.254)
		(layers "F.Cu" "B.Cu")
		(net "GND")
	)
	(via
		(at 37.648134 -11.02995)
		(size 0.508)
		(drill 0.254)
		(layers "F.Cu" "B.Cu")
		(net "GND")
	)
	(via
		(at 13.730986 -26.035)
		(size 0.508)
		(drill 0.254)
		(layers "F.Cu" "B.Cu")
		(net "GND")
	)
	(via
		(at 37.719 -26.416)
		(size 0.508)
		(drill 0.254)
		(layers "F.Cu" "B.Cu")
		(net "GND")
	)
	(via
		(at 25.146 -16.637)
		(size 0.508)
		(drill 0.254)
		(layers "F.Cu" "B.Cu")
		(net "GND")
	)
	(via
		(at 33.655 -48.895)
		(size 0.6604)
		(drill 0.3302)
		(layers "F.Cu" "B.Cu")
		(net "GND")
	)
	(via
		(at 29.68498 -85.055202)
		(size 0.508)
		(drill 0.254)
		(layers "F.Cu" "B.Cu")
		(net "GND")
	)
	(via
		(at 37.719 -22.352)
		(size 0.508)
		(drill 0.254)
		(layers "F.Cu" "B.Cu")
		(net "GND")
	)
	(via
		(at 25.019508 -0.766064)
		(size 0.508)
		(drill 0.254)
		(layers "F.Cu" "B.Cu")
		(net "GND")
	)
	(via
		(at 29.765244 -0.765556)
		(size 0.508)
		(drill 0.254)
		(layers "F.Cu" "B.Cu")
		(net "GND")
	)
	(via
		(at 35.56 -46.99)
		(size 0.6604)
		(drill 0.3302)
		(layers "F.Cu" "B.Cu")
		(net "GND")
	)
	(via
		(at 25.273 -2.286)
		(size 0.508)
		(drill 0.254)
		(layers "F.Cu" "B.Cu")
		(net "GND")
	)
	(via
		(at 36.718494 -79.116682)
		(size 0.508)
		(drill 0.254)
		(layers "F.Cu" "B.Cu")
		(net "GND")
	)
	(via
		(at 30.607 -34.671)
		(size 0.508)
		(drill 0.254)
		(layers "F.Cu" "B.Cu")
		(net "GND")
	)
	(via
		(at 37.719 -29.337)
		(size 0.508)
		(drill 0.254)
		(layers "F.Cu" "B.Cu")
		(net "GND")
	)
	(via
		(at 13.61313 -84.133436)
		(size 0.508)
		(drill 0.254)
		(layers "F.Cu" "B.Cu")
		(net "GND")
	)
	(via
		(at 0.763016 -42.282872)
		(size 0.508)
		(drill 0.254)
		(layers "F.Cu" "B.Cu")
		(net "GND")
	)
	(via
		(at 2.921 -50.8)
		(size 0.508)
		(drill 0.254)
		(layers "F.Cu" "B.Cu")
		(net "GND")
	)
	(via
		(at 38.522148 -54.00421)
		(size 0.508)
		(drill 0.254)
		(layers "F.Cu" "B.Cu")
		(net "GND")
	)
	(via
		(at 38.527482 -38.476428)
		(size 0.508)
		(drill 0.254)
		(layers "F.Cu" "B.Cu")
		(net "GND")
	)
	(via
		(at 27.250136 -68.745862)
		(size 0.508)
		(drill 0.254)
		(layers "F.Cu" "B.Cu")
		(net "GND")
	)
	(via
		(at 1.866392 -76.857352)
		(size 0.508)
		(drill 0.254)
		(layers "F.Cu" "B.Cu")
		(net "GND")
	)
	(via
		(at 9.068054 -79.231998)
		(size 0.508)
		(drill 0.254)
		(layers "F.Cu" "B.Cu")
		(net "GND")
	)
	(via
		(at 35.56 -52.705)
		(size 0.6604)
		(drill 0.3302)
		(layers "F.Cu" "B.Cu")
		(net "GND")
	)
	(via
		(at 19.4056 -65.532)
		(size 0.508)
		(drill 0.254)
		(layers "F.Cu" "B.Cu")
		(net "GND")
	)
	(via
		(at 16.27505 -50.8)
		(size 0.508)
		(drill 0.254)
		(layers "F.Cu" "B.Cu")
		(net "GND")
	)
	(via
		(at 21.101304 -85.381084)
		(size 0.508)
		(drill 0.254)
		(layers "F.Cu" "B.Cu")
		(net "GND")
	)
	(via
		(at 37.465 -54.61)
		(size 0.6604)
		(drill 0.3302)
		(layers "F.Cu" "B.Cu")
		(net "GND")
	)
	(via
		(at 18.250154 -73.20407)
		(size 0.508)
		(drill 0.254)
		(layers "F.Cu" "B.Cu")
		(net "GND")
	)
	(via
		(at 3.551936 -70.980046)
		(size 0.508)
		(drill 0.254)
		(layers "F.Cu" "B.Cu")
		(net "GND")
	)
	(via
		(at 0.763016 -57.522872)
		(size 0.508)
		(drill 0.254)
		(layers "F.Cu" "B.Cu")
		(net "GND")
	)
	(via
		(at 19.673062 -19.685)
		(size 0.508)
		(drill 0.254)
		(layers "F.Cu" "B.Cu")
		(net "GND")
	)
	(via
		(at 26.950162 -73.20407)
		(size 0.508)
		(drill 0.254)
		(layers "F.Cu" "B.Cu")
		(net "GND")
	)
	(via
		(at 38.532816 -59.09183)
		(size 0.508)
		(drill 0.254)
		(layers "F.Cu" "B.Cu")
		(net "GND")
	)
	(via
		(at 31.552134 -11.02995)
		(size 0.508)
		(drill 0.254)
		(layers "F.Cu" "B.Cu")
		(net "GND")
	)
	(via
		(at 38.18382 -1.168654)
		(size 0.508)
		(drill 0.254)
		(layers "F.Cu" "B.Cu")
		(net "GND")
	)
	(via
		(at 4.064 -27.798014)
		(size 0.508)
		(drill 0.254)
		(layers "F.Cu" "B.Cu")
		(net "GND")
	)
	(via
		(at 4.953 -54.229)
		(size 0.508)
		(drill 0.254)
		(layers "F.Cu" "B.Cu")
		(net "GND")
	)
	(via
		(at 13.056616 -80.32623)
		(size 0.508)
		(drill 0.254)
		(layers "F.Cu" "B.Cu")
		(net "GND")
	)
	(via
		(at 38.528752 -3.499104)
		(size 0.508)
		(drill 0.254)
		(layers "F.Cu" "B.Cu")
		(net "GND")
	)
	(via
		(at 23.114 -4.699)
		(size 0.508)
		(drill 0.254)
		(layers "F.Cu" "B.Cu")
		(net "GND")
	)
	(via
		(at 21.463 -24.13)
		(size 0.508)
		(drill 0.254)
		(layers "F.Cu" "B.Cu")
		(net "GND")
	)
	(via
		(at 16.764 -29.972)
		(size 0.508)
		(drill 0.254)
		(layers "F.Cu" "B.Cu")
		(net "GND")
	)
	(via
		(at 37.465 -52.705)
		(size 0.6604)
		(drill 0.3302)
		(layers "F.Cu" "B.Cu")
		(net "GND")
	)
	(via
		(at 6.865112 -0.766826)
		(size 0.508)
		(drill 0.254)
		(layers "F.Cu" "B.Cu")
		(net "GND")
	)
	(via
		(at 10.414 -54.237128)
		(size 0.508)
		(drill 0.254)
		(layers "F.Cu" "B.Cu")
		(net "GND")
	)
	(via
		(at 30.607 -33.782)
		(size 0.508)
		(drill 0.254)
		(layers "F.Cu" "B.Cu")
		(net "GND")
	)
	(via
		(at 33.655 -54.61)
		(size 0.6604)
		(drill 0.3302)
		(layers "F.Cu" "B.Cu")
		(net "GND")
	)
	(via
		(at 21.550122 -73.20407)
		(size 0.508)
		(drill 0.254)
		(layers "F.Cu" "B.Cu")
		(net "GND")
	)
	(via
		(at 23.650194 -68.745862)
		(size 0.508)
		(drill 0.254)
		(layers "F.Cu" "B.Cu")
		(net "GND")
	)
	(via
		(at 11.730736 -0.765556)
		(size 0.508)
		(drill 0.254)
		(layers "F.Cu" "B.Cu")
		(net "GND")
	)
	(via
		(at 19.431 -57.785)
		(size 0.508)
		(drill 0.254)
		(layers "F.Cu" "B.Cu")
		(net "GND")
	)
	(via
		(at 15.00505 -51.816)
		(size 0.508)
		(drill 0.254)
		(layers "F.Cu" "B.Cu")
		(net "GND")
	)
	(via
		(at 0.763016 -23.07844)
		(size 0.508)
		(drill 0.254)
		(layers "F.Cu" "B.Cu")
		(net "GND")
	)
	(via
		(at 37.719 -33.782)
		(size 0.508)
		(drill 0.254)
		(layers "F.Cu" "B.Cu")
		(net "GND")
	)
	(via
		(at 30.099 -1.705864)
		(size 0.508)
		(drill 0.254)
		(layers "F.Cu" "B.Cu")
		(net "GND")
	)
	(via
		(at 2.921 -48.768)
		(size 0.508)
		(drill 0.254)
		(layers "F.Cu" "B.Cu")
		(net "GND")
	)
	(via
		(at 30.08757 -82.260948)
		(size 0.508)
		(drill 0.254)
		(layers "F.Cu" "B.Cu")
		(net "GND")
	)
	(via
		(at 4.953 -62.357)
		(size 0.508)
		(drill 0.254)
		(layers "F.Cu" "B.Cu")
		(net "GND")
	)
	(via
		(at 36.755324 -8.87476)
		(size 0.508)
		(drill 0.254)
		(layers "F.Cu" "B.Cu")
		(net "GND")
	)
	(via
		(at 1.318768 -0.975614)
		(size 0.508)
		(drill 0.254)
		(layers "F.Cu" "B.Cu")
		(net "GND")
	)
	(via
		(at 20.574 -2.032)
		(size 0.508)
		(drill 0.254)
		(layers "F.Cu" "B.Cu")
		(net "GND")
	)
	(via
		(at 30.607 -32.004)
		(size 0.508)
		(drill 0.254)
		(layers "F.Cu" "B.Cu")
		(net "GND")
	)
	(via
		(at 4.444746 -68.824856)
		(size 0.508)
		(drill 0.254)
		(layers "F.Cu" "B.Cu")
		(net "GND")
	)
	(via
		(at 37.465 -50.8)
		(size 0.6604)
		(drill 0.3302)
		(layers "F.Cu" "B.Cu")
		(net "GND")
	)
	(via
		(at 4.953 -56.261)
		(size 0.508)
		(drill 0.254)
		(layers "F.Cu" "B.Cu")
		(net "GND")
	)
	(via
		(at 37.719 -32.893)
		(size 0.508)
		(drill 0.254)
		(layers "F.Cu" "B.Cu")
		(net "GND")
	)
	(via
		(at 24.003 -32.766)
		(size 0.508)
		(drill 0.254)
		(layers "F.Cu" "B.Cu")
		(net "GND")
	)
	(via
		(at 38.53307 -43.919902)
		(size 0.508)
		(drill 0.254)
		(layers "F.Cu" "B.Cu")
		(net "GND")
	)
	(via
		(at 1.863598 -74.409808)
		(size 0.508)
		(drill 0.254)
		(layers "F.Cu" "B.Cu")
		(net "GND")
	)
	(via
		(at 37.465 -46.99)
		(size 0.6604)
		(drill 0.3302)
		(layers "F.Cu" "B.Cu")
		(net "GND")
	)
	(via
		(at 4.953 -58.293)
		(size 0.508)
		(drill 0.254)
		(layers "F.Cu" "B.Cu")
		(net "GND")
	)
	(via
		(at 38.527736 -28.650692)
		(size 0.508)
		(drill 0.254)
		(layers "F.Cu" "B.Cu")
		(net "GND")
	)
	(via
		(at 37.719 -32.004)
		(size 0.508)
		(drill 0.254)
		(layers "F.Cu" "B.Cu")
		(net "GND")
	)
	(via
		(at 19.655028 -14.732)
		(size 0.508)
		(drill 0.254)
		(layers "F.Cu" "B.Cu")
		(net "GND")
	)
	(via
		(at 19.2278 -67.0306)
		(size 0.508)
		(drill 0.254)
		(layers "F.Cu" "B.Cu")
		(net "GND")
	)
	(via
		(at 37.719 -24.384)
		(size 0.508)
		(drill 0.254)
		(layers "F.Cu" "B.Cu")
		(net "GND")
	)
	(via
		(at 23.650194 -73.20407)
		(size 0.508)
		(drill 0.254)
		(layers "F.Cu" "B.Cu")
		(net "GND")
	)
	(via
		(at 29.972 -29.591)
		(size 0.508)
		(drill 0.254)
		(layers "F.Cu" "B.Cu")
		(net "GND")
	)
	(via
		(at 33.909 -40.64)
		(size 0.508)
		(drill 0.254)
		(layers "F.Cu" "B.Cu")
		(net "GND")
	)
	(via
		(at 2.032 -28.067)
		(size 0.508)
		(drill 0.254)
		(layers "F.Cu" "B.Cu")
		(net "GND")
	)
	(via
		(at 37.719 -28.448)
		(size 0.508)
		(drill 0.254)
		(layers "F.Cu" "B.Cu")
		(net "GND")
	)
	(via
		(at 37.465 -56.515)
		(size 0.6604)
		(drill 0.3302)
		(layers "F.Cu" "B.Cu")
		(net "GND")
	)
	(via
		(at 38.522402 -48.937926)
		(size 0.508)
		(drill 0.254)
		(layers "F.Cu" "B.Cu")
		(net "GND")
	)
	(via
		(at 20.350226 -73.20407)
		(size 0.508)
		(drill 0.254)
		(layers "F.Cu" "B.Cu")
		(net "GND")
	)
	(via
		(at 25.450038 -68.745862)
		(size 0.508)
		(drill 0.254)
		(layers "F.Cu" "B.Cu")
		(net "GND")
	)
	(via
		(at 33.655 -46.99)
		(size 0.508)
		(drill 0.254)
		(layers "F.Cu" "B.Cu")
		(net "GND")
	)
	(via
		(at 9.647936 -70.980046)
		(size 0.508)
		(drill 0.254)
		(layers "F.Cu" "B.Cu")
		(net "GND")
	)
	(via
		(at 17.517872 -85.38083)
		(size 0.508)
		(drill 0.254)
		(layers "F.Cu" "B.Cu")
		(net "GND")
	)
	(via
		(at 20.701 -32.131)
		(size 0.508)
		(drill 0.254)
		(layers "F.Cu" "B.Cu")
		(net "GND")
	)
	(via
		(at 38.533324 -18.469864)
		(size 0.508)
		(drill 0.254)
		(layers "F.Cu" "B.Cu")
		(net "GND")
	)
	(via
		(at 17.907 -45.085)
		(size 0.508)
		(drill 0.254)
		(layers "F.Cu" "B.Cu")
		(net "GND")
	)
	(via
		(at 6.599936 -67.932046)
		(size 0.508)
		(drill 0.254)
		(layers "F.Cu" "B.Cu")
		(net "GND")
	)
	(via
		(at 12.431014 -22.733)
		(size 0.508)
		(drill 0.254)
		(layers "F.Cu" "B.Cu")
		(net "GND")
	)
	(via
		(at 17.78 -35.179)
		(size 0.508)
		(drill 0.254)
		(layers "F.Cu" "B.Cu")
		(net "GND")
	)
	(via
		(at 35.56 -50.8)
		(size 0.6604)
		(drill 0.3302)
		(layers "F.Cu" "B.Cu")
		(net "GND")
	)
	(via
		(at 15.875 -13.97)
		(size 0.508)
		(drill 0.254)
		(layers "F.Cu" "B.Cu")
		(net "GND")
	)
	(via
		(at 0.763016 -37.202872)
		(size 0.508)
		(drill 0.254)
		(layers "F.Cu" "B.Cu")
		(net "GND")
	)
	(via
		(at 37.719 -30.226)
		(size 0.508)
		(drill 0.254)
		(layers "F.Cu" "B.Cu")
		(net "GND")
	)
	(via
		(at 38.53307 -64.17437)
		(size 0.508)
		(drill 0.254)
		(layers "F.Cu" "B.Cu")
		(net "GND")
	)
	(via
		(at 37.465 -45.085)
		(size 0.6604)
		(drill 0.3302)
		(layers "F.Cu" "B.Cu")
		(net "GND")
	)
	(via
		(at 38.527736 -33.701228)
		(size 0.508)
		(drill 0.254)
		(layers "F.Cu" "B.Cu")
		(net "GND")
	)
	(via
		(at 38.527482 -23.099268)
		(size 0.508)
		(drill 0.254)
		(layers "F.Cu" "B.Cu")
		(net "GND")
	)
	(via
		(at 2.921 -46.736)
		(size 0.508)
		(drill 0.254)
		(layers "F.Cu" "B.Cu")
		(net "GND")
	)
	(via
		(at 0.763016 -52.442872)
		(size 0.508)
		(drill 0.254)
		(layers "F.Cu" "B.Cu")
		(net "GND")
	)
	(via
		(at 32.444944 -8.87476)
		(size 0.508)
		(drill 0.254)
		(layers "F.Cu" "B.Cu")
		(net "GND")
	)
	(via
		(at 35.56 -45.085)
		(size 0.6604)
		(drill 0.3302)
		(layers "F.Cu" "B.Cu")
		(net "GND")
	)
	(via
		(at 14.351 -66.294)
		(size 0.508)
		(drill 0.254)
		(layers "F.Cu" "B.Cu")
		(net "GND")
	)
	(via
		(at 4.267454 -79.234284)
		(size 0.508)
		(drill 0.254)
		(layers "F.Cu" "B.Cu")
		(net "GND")
	)
	(via
		(at 20.497038 -0.766064)
		(size 0.508)
		(drill 0.254)
		(layers "F.Cu" "B.Cu")
		(net "GND")
	)
	(via
		(at 15.134844 -10.16)
		(size 0.508)
		(drill 0.254)
		(layers "F.Cu" "B.Cu")
		(net "GND")
	)
	(via
		(at 4.953 -60.325)
		(size 0.508)
		(drill 0.254)
		(layers "F.Cu" "B.Cu")
		(net "GND")
	)
	(via
		(at 37.719 -31.115)
		(size 0.508)
		(drill 0.254)
		(layers "F.Cu" "B.Cu")
		(net "GND")
	)
	(via
		(at 15.460218 -0.765556)
		(size 0.508)
		(drill 0.254)
		(layers "F.Cu" "B.Cu")
		(net "GND")
	)
	(via
		(at 28.747974 -8.052054)
		(size 0.508)
		(drill 0.254)
		(layers "F.Cu" "B.Cu")
		(net "GND")
	)
	(via
		(at 32.94761 -79.23784)
		(size 0.508)
		(drill 0.254)
		(layers "F.Cu" "B.Cu")
		(net "GND")
	)
	(via
		(at 8.755126 -68.824856)
		(size 0.508)
		(drill 0.254)
		(layers "F.Cu" "B.Cu")
		(net "GND")
	)
	(via
		(at 37.719 -34.671)
		(size 0.508)
		(drill 0.254)
		(layers "F.Cu" "B.Cu")
		(net "GND")
	)
	(via
		(at 17.54505 -62.738)
		(size 0.508)
		(drill 0.254)
		(layers "F.Cu" "B.Cu")
		(net "GND")
	)
	(via
		(at 8.382 -47.244)
		(size 0.508)
		(drill 0.254)
		(layers "F.Cu" "B.Cu")
		(net "GND")
	)
	(via
		(at 30.607 -32.893)
		(size 0.508)
		(drill 0.254)
		(layers "F.Cu" "B.Cu")
		(net "GND")
	)
	(segment
		(start 24.247348 -17.456912)
		(end 24.574754 -17.456912)
		(width 0.14732)
		(layer "F.Cu")
		(net "USB2_DEBUG_DN")
	)
	(segment
		(start 26.381456 -18.45818)
		(end 26.93416 -19.010884)
		(width 0.14732)
		(layer "F.Cu")
		(net "USB2_DEBUG_DN")
	)
	(segment
		(start 31.251144 -20.253198)
		(end 31.492444 -20.494244)
		(width 0.14732)
		(layer "F.Cu")
		(net "USB2_DEBUG_DN")
	)
	(segment
		(start 25.576022 -18.45818)
		(end 26.381456 -18.45818)
		(width 0.14732)
		(layer "F.Cu")
		(net "USB2_DEBUG_DN")
	)
	(segment
		(start 29.260038 -20.19427)
		(end 29.525468 -20.084288)
		(width 0.14732)
		(layer "F.Cu")
		(net "USB2_DEBUG_DN")
	)
	(segment
		(start 28.74137 -19.759422)
		(end 28.851352 -20.025106)
		(width 0.14732)
		(layer "F.Cu")
		(net "USB2_DEBUG_DN")
	)
	(segment
		(start 31.492698 -20.652994)
		(end 31.492952 -20.653502)
		(width 0.14732)
		(layer "F.Cu")
		(net "USB2_DEBUG_DN")
	)
	(segment
		(start 31.336742 -20.849844)
		(end 30.873446 -20.849844)
		(width 0.14732)
		(layer "F.Cu")
		(net "USB2_DEBUG_DN")
	)
	(segment
		(start 28.333192 -19.590512)
		(end 28.74137 -19.759422)
		(width 0.14732)
		(layer "F.Cu")
		(net "USB2_DEBUG_DN")
	)
	(segment
		(start 30.984952 -21.488654)
		(end 31.32963 -21.488654)
		(width 0.14732)
		(layer "F.Cu")
		(net "USB2_DEBUG_DN")
	)
	(segment
		(start 31.482792 -22.431248)
		(end 31.18485 -22.72919)
		(width 0.14732)
		(layer "F.Cu")
		(net "USB2_DEBUG_DN")
	)
	(segment
		(start 24.100028 -18.32991)
		(end 24.100028 -17.604232)
		(width 0.14732)
		(layer "F.Cu")
		(net "USB2_DEBUG_DN")
	)
	(segment
		(start 31.492952 -20.692872)
		(end 31.336742 -20.849844)
		(width 0.14732)
		(layer "F.Cu")
		(net "USB2_DEBUG_DN")
	)
	(segment
		(start 29.525468 -20.084288)
		(end 29.933646 -20.253198)
		(width 0.14732)
		(layer "F.Cu")
		(net "USB2_DEBUG_DN")
	)
	(segment
		(start 26.93416 -19.010884)
		(end 27.549094 -19.265646)
		(width 0.14732)
		(layer "F.Cu")
		(net "USB2_DEBUG_DN")
	)
	(segment
		(start 24.100028 -17.604232)
		(end 24.247348 -17.456912)
		(width 0.14732)
		(layer "F.Cu")
		(net "USB2_DEBUG_DN")
	)
	(segment
		(start 28.851352 -20.025106)
		(end 29.260038 -20.19427)
		(width 0.14732)
		(layer "F.Cu")
		(net "USB2_DEBUG_DN")
	)
	(segment
		(start 30.873446 -20.849844)
		(end 30.609794 -21.113496)
		(width 0.14732)
		(layer "F.Cu")
		(net "USB2_DEBUG_DN")
	)
	(segment
		(start 30.609794 -21.113496)
		(end 30.984952 -21.488654)
		(width 0.14732)
		(layer "F.Cu")
		(net "USB2_DEBUG_DN")
	)
	(segment
		(start 31.492444 -20.494244)
		(end 31.492698 -20.652994)
		(width 0.14732)
		(layer "F.Cu")
		(net "USB2_DEBUG_DN")
	)
	(segment
		(start 27.659076 -19.53133)
		(end 28.067762 -19.700494)
		(width 0.14732)
		(layer "F.Cu")
		(net "USB2_DEBUG_DN")
	)
	(segment
		(start 31.482792 -21.641816)
		(end 31.482792 -22.431248)
		(width 0.14732)
		(layer "F.Cu")
		(net "USB2_DEBUG_DN")
	)
	(segment
		(start 27.549094 -19.265646)
		(end 27.659076 -19.53133)
		(width 0.14732)
		(layer "F.Cu")
		(net "USB2_DEBUG_DN")
	)
	(segment
		(start 29.933646 -20.253198)
		(end 31.251144 -20.253198)
		(width 0.14732)
		(layer "F.Cu")
		(net "USB2_DEBUG_DN")
	)
	(segment
		(start 31.18485 -23.397718)
		(end 31.18485 -23.00605)
		(width 0.14732)
		(layer "F.Cu")
		(net "USB2_DEBUG_DN")
	)
	(segment
		(start 31.492952 -20.653502)
		(end 31.492952 -20.692872)
		(width 0.14732)
		(layer "F.Cu")
		(net "USB2_DEBUG_DN")
	)
	(segment
		(start 28.067762 -19.700494)
		(end 28.333192 -19.590512)
		(width 0.14732)
		(layer "F.Cu")
		(net "USB2_DEBUG_DN")
	)
	(segment
		(start 31.18485 -22.72919)
		(end 31.18485 -23.00605)
		(width 0.14732)
		(layer "F.Cu")
		(net "USB2_DEBUG_DN")
	)
	(segment
		(start 24.574754 -17.456912)
		(end 25.576022 -18.45818)
		(width 0.14732)
		(layer "F.Cu")
		(net "USB2_DEBUG_DN")
	)
	(segment
		(start 31.32963 -21.488654)
		(end 31.482792 -21.641816)
		(width 0.14732)
		(layer "F.Cu")
		(net "USB2_DEBUG_DN")
	)
	(segment
		(start 32.034734 -23.00605)
		(end 32.034734 -22.72919)
		(width 0.14732)
		(layer "F.Cu")
		(net "USB2_DEBUG_DP")
	)
	(segment
		(start 31.746444 -20.388834)
		(end 31.746698 -20.592796)
		(width 0.14732)
		(layer "F.Cu")
		(net "USB2_DEBUG_DP")
	)
	(segment
		(start 24.680164 -17.202912)
		(end 25.681432 -18.20418)
		(width 0.14732)
		(layer "F.Cu")
		(net "USB2_DEBUG_DP")
	)
	(segment
		(start 31.736792 -22.431248)
		(end 31.736792 -21.641816)
		(width 0.14732)
		(layer "F.Cu")
		(net "USB2_DEBUG_DP")
	)
	(segment
		(start 24.100028 -16.329914)
		(end 24.100028 -17.055592)
		(width 0.14732)
		(layer "F.Cu")
		(net "USB2_DEBUG_DP")
	)
	(segment
		(start 31.746952 -20.660868)
		(end 31.747206 -20.692364)
		(width 0.14732)
		(layer "F.Cu")
		(net "USB2_DEBUG_DP")
	)
	(segment
		(start 31.889954 -21.488654)
		(end 32.234632 -21.488654)
		(width 0.14732)
		(layer "F.Cu")
		(net "USB2_DEBUG_DP")
	)
	(segment
		(start 29.984192 -19.999198)
		(end 31.3563 -19.999198)
		(width 0.14732)
		(layer "F.Cu")
		(net "USB2_DEBUG_DP")
	)
	(segment
		(start 25.681432 -18.20418)
		(end 26.486866 -18.20418)
		(width 0.14732)
		(layer "F.Cu")
		(net "USB2_DEBUG_DP")
	)
	(segment
		(start 31.746698 -20.592796)
		(end 31.746952 -20.593304)
		(width 0.14732)
		(layer "F.Cu")
		(net "USB2_DEBUG_DP")
	)
	(segment
		(start 24.100028 -17.055592)
		(end 24.247348 -17.202912)
		(width 0.14732)
		(layer "F.Cu")
		(net "USB2_DEBUG_DP")
	)
	(segment
		(start 32.234632 -21.488654)
		(end 32.60979 -21.113496)
		(width 0.14732)
		(layer "F.Cu")
		(net "USB2_DEBUG_DP")
	)
	(segment
		(start 31.747206 -20.692364)
		(end 31.903924 -20.848828)
		(width 0.14732)
		(layer "F.Cu")
		(net "USB2_DEBUG_DP")
	)
	(segment
		(start 27.078178 -18.795238)
		(end 29.984192 -19.999198)
		(width 0.14732)
		(layer "F.Cu")
		(net "USB2_DEBUG_DP")
	)
	(segment
		(start 31.3563 -19.999198)
		(end 31.746444 -20.388834)
		(width 0.14732)
		(layer "F.Cu")
		(net "USB2_DEBUG_DP")
	)
	(segment
		(start 31.903924 -20.848828)
		(end 32.345122 -20.848828)
		(width 0.14732)
		(layer "F.Cu")
		(net "USB2_DEBUG_DP")
	)
	(segment
		(start 32.345122 -20.848828)
		(end 32.60979 -21.113496)
		(width 0.14732)
		(layer "F.Cu")
		(net "USB2_DEBUG_DP")
	)
	(segment
		(start 31.746952 -20.593304)
		(end 31.746952 -20.660868)
		(width 0.14732)
		(layer "F.Cu")
		(net "USB2_DEBUG_DP")
	)
	(segment
		(start 31.736792 -21.641816)
		(end 31.889954 -21.488654)
		(width 0.14732)
		(layer "F.Cu")
		(net "USB2_DEBUG_DP")
	)
	(segment
		(start 32.034734 -23.00605)
		(end 32.034734 -23.397718)
		(width 0.14732)
		(layer "F.Cu")
		(net "USB2_DEBUG_DP")
	)
	(segment
		(start 32.034734 -22.72919)
		(end 31.736792 -22.431248)
		(width 0.14732)
		(layer "F.Cu")
		(net "USB2_DEBUG_DP")
	)
	(segment
		(start 26.486866 -18.20418)
		(end 27.078178 -18.795238)
		(width 0.14732)
		(layer "F.Cu")
		(net "USB2_DEBUG_DP")
	)
	(segment
		(start 24.247348 -17.202912)
		(end 24.680164 -17.202912)
		(width 0.14732)
		(layer "F.Cu")
		(net "USB2_DEBUG_DP")
	)
	(segment
		(start 19.49577 -9.238234)
		(end 19.49577 -10.018014)
		(width 0.18796)
		(layer "F.Cu")
		(net "FM_PFR_LED_BLUE_R")
	)
	(segment
		(start 19.67992 -9.054084)
		(end 19.49577 -9.238234)
		(width 0.18796)
		(layer "F.Cu")
		(net "FM_PFR_LED_BLUE_R")
	)
	(segment
		(start 17.45488 -13.716)
		(end 17.45488 -14.723618)
		(width 0.18796)
		(layer "F.Cu")
		(net "FM_PFR_LED_BLUE_R")
	)
	(segment
		(start 19.67992 -6.679946)
		(end 19.67992 -9.054084)
		(width 0.18796)
		(layer "F.Cu")
		(net "FM_PFR_LED_BLUE_R")
	)
	(via
		(at 17.45488 -13.716)
		(size 0.508)
		(drill 0.254)
		(layers "F.Cu" "B.Cu")
		(net "FM_PFR_LED_BLUE_R")
	)
	(segment
		(start 19.67992 -13.040868)
		(end 19.004788 -13.716)
		(width 0.18796)
		(layer "B.Cu")
		(net "FM_PFR_LED_BLUE_R")
	)
	(segment
		(start 19.004788 -13.716)
		(end 17.45488 -13.716)
		(width 0.18796)
		(layer "B.Cu")
		(net "FM_PFR_LED_BLUE_R")
	)
	(segment
		(start 19.67992 -6.679946)
		(end 19.67992 -13.040868)
		(width 0.18796)
		(layer "B.Cu")
		(net "FM_PFR_LED_BLUE_R")
	)
	(segment
		(start 19.655028 -13.773658)
		(end 18.72996 -13.773658)
		(width 0.18796)
		(layer "F.Cu")
		(net "FM_PFR_LED_BLUE_R_N")
	)
	(segment
		(start 18.72996 -13.773658)
		(end 18.542 -13.961618)
		(width 0.18796)
		(layer "F.Cu")
		(net "FM_PFR_LED_BLUE_R_N")
	)
	(segment
		(start 18.542 -13.961618)
		(end 18.542 -15.64005)
		(width 0.18796)
		(layer "F.Cu")
		(net "FM_PFR_LED_BLUE_R_N")
	)
	(segment
		(start 17.79905 -16.383)
		(end 17.79905 -17.145)
		(width 0.18796)
		(layer "F.Cu")
		(net "FM_PFR_LED_BLUE_R_N")
	)
	(segment
		(start 18.542 -15.64005)
		(end 17.79905 -16.383)
		(width 0.18796)
		(layer "F.Cu")
		(net "FM_PFR_LED_BLUE_R_N")
	)
	(via
		(at 17.79905 -16.383)
		(size 0.508)
		(drill 0.254)
		(layers "F.Cu" "B.Cu")
		(net "FM_PFR_LED_BLUE_R_N")
	)
	(segment
		(start 15.569946 -6.679946)
		(end 17.6276 -8.7376)
		(width 0.18796)
		(layer "F.Cu")
		(net "FM_PFR_LED_AMBER_R")
	)
	(segment
		(start 17.6276 -10.5664)
		(end 17.6276 -9.4234)
		(width 0.18796)
		(layer "F.Cu")
		(net "FM_PFR_LED_AMBER_R")
	)
	(segment
		(start 17.334992 -10.859008)
		(end 17.6276 -10.5664)
		(width 0.18796)
		(layer "F.Cu")
		(net "FM_PFR_LED_AMBER_R")
	)
	(segment
		(start 14.59992 -6.679946)
		(end 15.569946 -6.679946)
		(width 0.18796)
		(layer "F.Cu")
		(net "FM_PFR_LED_AMBER_R")
	)
	(segment
		(start 17.334992 -12.026392)
		(end 17.334992 -10.859008)
		(width 0.18796)
		(layer "F.Cu")
		(net "FM_PFR_LED_AMBER_R")
	)
	(segment
		(start 17.6276 -8.7376)
		(end 17.6276 -9.4234)
		(width 0.18796)
		(layer "F.Cu")
		(net "FM_PFR_LED_AMBER_R")
	)
	(segment
		(start 15.134844 -13.948156)
		(end 15.113 -13.97)
		(width 0.18796)
		(layer "F.Cu")
		(net "FM_PFR_LED_AMBER_R_N")
	)
	(segment
		(start 15.134844 -12.976352)
		(end 15.134844 -13.948156)
		(width 0.18796)
		(layer "F.Cu")
		(net "FM_PFR_LED_AMBER_R_N")
	)
	(segment
		(start 15.113 -13.97)
		(end 15.113 -14.58595)
		(width 0.18796)
		(layer "F.Cu")
		(net "FM_PFR_LED_AMBER_R_N")
	)
	(via
		(at 15.113 -13.97)
		(size 0.508)
		(drill 0.254)
		(layers "F.Cu" "B.Cu")
		(net "FM_PFR_LED_AMBER_R_N")
	)
	(segment
		(start 23.171404 -22.028404)
		(end 23.171404 -24.326596)
		(width 0.18796)
		(layer "F.Cu")
		(net "FM_PFR_LED_BLUE_N")
	)
	(segment
		(start 20.759166 -19.754088)
		(end 21.071078 -20.066)
		(width 0.18796)
		(layer "F.Cu")
		(net "FM_PFR_LED_BLUE_N")
	)
	(segment
		(start 21.463 -26.035)
		(end 21.463 -32.439102)
		(width 0.18796)
		(layer "F.Cu")
		(net "FM_PFR_LED_BLUE_N")
	)
	(segment
		(start 21.071078 -20.066)
		(end 21.209 -20.066)
		(width 0.18796)
		(layer "F.Cu")
		(net "FM_PFR_LED_BLUE_N")
	)
	(segment
		(start 22.70252 -33.678622)
		(end 22.70252 -64.11087)
		(width 0.18796)
		(layer "F.Cu")
		(net "FM_PFR_LED_BLUE_N")
	)
	(segment
		(start 16.99895 -17.78)
		(end 16.99895 -17.145)
		(width 0.18796)
		(layer "F.Cu")
		(net "FM_PFR_LED_BLUE_N")
	)
	(segment
		(start 23.171404 -24.326596)
		(end 21.463 -26.035)
		(width 0.18796)
		(layer "F.Cu")
		(net "FM_PFR_LED_BLUE_N")
	)
	(segment
		(start 22.70252 -64.11087)
		(end 24.250142 -67.847464)
		(width 0.18796)
		(layer "F.Cu")
		(net "FM_PFR_LED_BLUE_N")
	)
	(segment
		(start 21.463 -32.439102)
		(end 22.70252 -33.678622)
		(width 0.18796)
		(layer "F.Cu")
		(net "FM_PFR_LED_BLUE_N")
	)
	(segment
		(start 24.250142 -67.847464)
		(end 24.250142 -69.799962)
		(width 0.18796)
		(layer "F.Cu")
		(net "FM_PFR_LED_BLUE_N")
	)
	(segment
		(start 21.209 -20.066)
		(end 23.171404 -22.028404)
		(width 0.18796)
		(layer "F.Cu")
		(net "FM_PFR_LED_BLUE_N")
	)
	(via
		(at 16.99895 -17.78)
		(size 0.508)
		(drill 0.254)
		(layers "F.Cu" "B.Cu")
		(net "FM_PFR_LED_BLUE_N")
	)
	(via
		(at 20.759166 -19.754088)
		(size 0.508)
		(drill 0.254)
		(layers "F.Cu" "B.Cu")
		(net "FM_PFR_LED_BLUE_N")
	)
	(segment
		(start 20.759166 -18.980912)
		(end 20.759166 -19.754088)
		(width 0.18796)
		(layer "B.Cu")
		(net "FM_PFR_LED_BLUE_N")
	)
	(segment
		(start 19.558254 -17.78)
		(end 20.759166 -18.980912)
		(width 0.18796)
		(layer "B.Cu")
		(net "FM_PFR_LED_BLUE_N")
	)
	(segment
		(start 16.99895 -17.78)
		(end 19.558254 -17.78)
		(width 0.18796)
		(layer "B.Cu")
		(net "FM_PFR_LED_BLUE_N")
	)
	(segment
		(start 23.562564 -21.866352)
		(end 23.562564 -24.488648)
		(width 0.18796)
		(layer "F.Cu")
		(net "FM_PFR_LED_AMBER_N")
	)
	(segment
		(start 15.301214 -16.129)
		(end 15.113 -15.940786)
		(width 0.18796)
		(layer "F.Cu")
		(net "FM_PFR_LED_AMBER_N")
	)
	(segment
		(start 23.09368 -64.032638)
		(end 23.09368 -32.99968)
		(width 0.18796)
		(layer "F.Cu")
		(net "FM_PFR_LED_AMBER_N")
	)
	(segment
		(start 21.85416 -26.197052)
		(end 21.85416 -31.76016)
		(width 0.18796)
		(layer "F.Cu")
		(net "FM_PFR_LED_AMBER_N")
	)
	(segment
		(start 21.463 -19.766788)
		(end 23.562564 -21.866352)
		(width 0.18796)
		(layer "F.Cu")
		(net "FM_PFR_LED_AMBER_N")
	)
	(segment
		(start 23.09368 -32.99968)
		(end 22.606 -32.512)
		(width 0.18796)
		(layer "F.Cu")
		(net "FM_PFR_LED_AMBER_N")
	)
	(segment
		(start 23.562564 -24.488648)
		(end 21.85416 -26.197052)
		(width 0.18796)
		(layer "F.Cu")
		(net "FM_PFR_LED_AMBER_N")
	)
	(segment
		(start 15.113 -15.940786)
		(end 15.113 -15.38605)
		(width 0.18796)
		(layer "F.Cu")
		(net "FM_PFR_LED_AMBER_N")
	)
	(segment
		(start 21.463 -19.431)
		(end 21.463 -19.766788)
		(width 0.18796)
		(layer "F.Cu")
		(net "FM_PFR_LED_AMBER_N")
	)
	(segment
		(start 24.85009 -68.273676)
		(end 23.09368 -64.032638)
		(width 0.18796)
		(layer "F.Cu")
		(net "FM_PFR_LED_AMBER_N")
	)
	(segment
		(start 16.383 -16.129)
		(end 15.301214 -16.129)
		(width 0.18796)
		(layer "F.Cu")
		(net "FM_PFR_LED_AMBER_N")
	)
	(segment
		(start 21.85416 -31.76016)
		(end 22.606 -32.512)
		(width 0.18796)
		(layer "F.Cu")
		(net "FM_PFR_LED_AMBER_N")
	)
	(segment
		(start 24.85009 -69.799962)
		(end 24.85009 -68.273676)
		(width 0.18796)
		(layer "F.Cu")
		(net "FM_PFR_LED_AMBER_N")
	)
	(via
		(at 22.606 -32.512)
		(size 0.762)
		(drill 0.381)
		(layers "F.Cu" "B.Cu")
		(net "FM_PFR_LED_AMBER_N")
	)
	(via
		(at 21.463 -19.431)
		(size 0.508)
		(drill 0.254)
		(layers "F.Cu" "B.Cu")
		(net "FM_PFR_LED_AMBER_N")
	)
	(via
		(at 16.383 -16.129)
		(size 0.508)
		(drill 0.254)
		(layers "F.Cu" "B.Cu")
		(net "FM_PFR_LED_AMBER_N")
	)
	(segment
		(start 21.463 -18.796)
		(end 19.685 -17.018)
		(width 0.18796)
		(layer "B.Cu")
		(net "FM_PFR_LED_AMBER_N")
	)
	(segment
		(start 21.463 -19.431)
		(end 21.463 -18.796)
		(width 0.18796)
		(layer "B.Cu")
		(net "FM_PFR_LED_AMBER_N")
	)
	(segment
		(start 17.272 -17.018)
		(end 16.383 -16.129)
		(width 0.18796)
		(layer "B.Cu")
		(net "FM_PFR_LED_AMBER_N")
	)
	(segment
		(start 19.685 -17.018)
		(end 17.272 -17.018)
		(width 0.18796)
		(layer "B.Cu")
		(net "FM_PFR_LED_AMBER_N")
	)
	(zone
		(layer "F.Cu")
		(hatch none 0.5)
		(connect_pads
			(clearance 0)
		)
		(min_thickness 0.25)
		(keepout
			(tracks not_allowed)
			(vias allowed)
			(pads allowed)
			(copperpour not_allowed)
			(footprints allowed)
		)
		(placement
			(enabled no)
			(sheetname "")
		)
		(fill
			(thermal_gap 0.5)
			(thermal_bridge_width 0.5)
			(island_removal_mode 0)
		)
		(polygon
			(pts
				(arc
					(start 33.10001 -11.701526)
					(mid 32.985626 -12.368197)
					(end 32.65551 -12.958572)
				)
				(arc
					(start 32.65551 -12.958572)
					(mid 34.600214 -17.030304)
					(end 36.544504 -12.958572)
				)
				(arc
					(start 36.544504 -12.958572)
					(mid 36.214447 -12.368176)
					(end 36.100004 -11.701526)
				)
				(arc
					(start 36.100004 -11.02995)
					(mid 34.600134 -9.53008)
					(end 33.10001 -11.02995)
				)
			)
		)
	)
	(zone
		(layer "F.Cu")
		(hatch none 0.5)
		(connect_pads
			(clearance 0)
		)
		(min_thickness 0.25)
		(keepout
			(tracks allowed)
			(vias allowed)
			(pads allowed)
			(copperpour allowed)
			(footprints not_allowed)
		)
		(placement
			(enabled no)
			(sheetname "")
		)
		(fill
			(thermal_gap 0.5)
			(thermal_bridge_width 0.5)
			(island_removal_mode 0)
		)
		(polygon
			(pts
				(arc
					(start 32.800036 -54.875938)
					(mid 40.80002 -62.875922)
					(end 32.800036 -70.875906)
				)
				(arc
					(start 32.800036 -70.875906)
					(mid 24.800052 -62.875922)
					(end 32.800036 -54.875938)
				)
			)
		)
	)
	(zone
		(layer "F.Cu")
		(hatch none 0.5)
		(connect_pads
			(clearance 0)
		)
		(min_thickness 0.25)
		(keepout
			(tracks allowed)
			(vias allowed)
			(pads allowed)
			(copperpour allowed)
			(footprints not_allowed)
		)
		(placement
			(enabled no)
			(sheetname "")
		)
		(fill
			(thermal_gap 0.5)
			(thermal_bridge_width 0.5)
			(island_removal_mode 0)
		)
		(polygon
			(pts
				(xy 20.439888 -8.949944) (xy 20.439888 -25.550114) (xy 29.560012 -25.550114) (xy 29.560012 -0.999998)
				(arc
					(start 1.999996 -0.999998)
					(mid 1.292891 -1.292891)
					(end 0.999998 -1.999996)
				)
				(arc
					(start 0.999998 -8.73633)
					(mid 1.690824 -8.224716)
					(end 2.432558 -7.79018)
				)
				(arc
					(start 9.767316 -7.79018)
					(mid 10.644704 -8.316224)
					(end 11.44778 -8.949944)
				)
			)
		)
	)
	(zone
		(layer "F.Cu")
		(hatch none 0.5)
		(connect_pads
			(clearance 0)
		)
		(min_thickness 0.25)
		(keepout
			(tracks allowed)
			(vias allowed)
			(pads allowed)
			(copperpour allowed)
			(footprints not_allowed)
		)
		(placement
			(enabled no)
			(sheetname "")
		)
		(fill
			(thermal_gap 0.5)
			(thermal_bridge_width 0.5)
			(island_removal_mode 0)
		)
		(polygon
			(pts
				(xy 20.439888 -8.949944) (xy 20.439888 -25.550876) (xy 29.560266 -25.550876) (xy 29.560266 -0.999998)
				(arc
					(start 1.999996 -0.999998)
					(mid 1.292891 -1.292891)
					(end 0.999998 -1.999996)
				)
				(arc
					(start 0.999998 -8.73633)
					(mid 1.356648 -8.457804)
					(end 1.72847 -8.199882)
				)
				(arc
					(start 10.471404 -8.199882)
					(mid 10.973911 -8.556113)
					(end 11.447526 -8.949944)
				)
			)
		)
	)
	(zone
		(layer "F.Cu")
		(hatch none 0.5)
		(connect_pads
			(clearance 0)
		)
		(min_thickness 0.25)
		(keepout
			(tracks not_allowed)
			(vias allowed)
			(pads allowed)
			(copperpour not_allowed)
			(footprints allowed)
		)
		(placement
			(enabled no)
			(sheetname "")
		)
		(fill
			(thermal_gap 0.5)
			(thermal_bridge_width 0.5)
			(island_removal_mode 0)
		)
		(polygon
			(pts
				(arc
					(start 30.80004 -62.875922)
					(mid 32.800036 -60.875926)
					(end 34.800032 -62.875922)
				)
				(arc
					(start 34.800032 -62.875922)
					(mid 32.800036 -64.875918)
					(end 30.80004 -62.875922)
				)
			)
		)
	)
	(zone
		(layer "F.Cu")
		(hatch none 0.5)
		(connect_pads
			(clearance 0)
		)
		(min_thickness 0.25)
		(keepout
			(tracks allowed)
			(vias allowed)
			(pads allowed)
			(copperpour allowed)
			(footprints not_allowed)
		)
		(placement
			(enabled no)
			(sheetname "")
		)
		(fill
			(thermal_gap 0.5)
			(thermal_bridge_width 0.5)
			(island_removal_mode 0)
		)
		(polygon
			(pts
				(arc
					(start 6.100064 -6.89991)
					(mid 14.100048 -14.899894)
					(end 6.100064 -22.899878)
				)
				(arc
					(start 6.100064 -22.899878)
					(mid -1.89992 -14.899894)
					(end 6.100064 -6.89991)
				)
			)
		)
	)
	(zone
		(layer "F.Cu")
		(hatch none 0.5)
		(connect_pads
			(clearance 0)
		)
		(min_thickness 0.25)
		(keepout
			(tracks allowed)
			(vias allowed)
			(pads allowed)
			(copperpour allowed)
			(footprints not_allowed)
		)
		(placement
			(enabled no)
			(sheetname "")
		)
		(fill
			(thermal_gap 0.5)
			(thermal_bridge_width 0.5)
			(island_removal_mode 0)
		)
		(polygon
			(pts
				(arc
					(start 38.600126 -11.02995)
					(mid 34.600134 -7.029958)
					(end 30.599888 -11.02995)
				)
				(arc
					(start 30.599888 -14.53007)
					(mid 34.600134 -18.530316)
					(end 38.600126 -14.53007)
				)
			)
		)
	)
	(zone
		(layer "F.Cu")
		(hatch none 0.5)
		(connect_pads
			(clearance 0)
		)
		(min_thickness 0.25)
		(keepout
			(tracks allowed)
			(vias allowed)
			(pads allowed)
			(copperpour allowed)
			(footprints not_allowed)
		)
		(placement
			(enabled no)
			(sheetname "")
		)
		(fill
			(thermal_gap 0.5)
			(thermal_bridge_width 0.5)
			(island_removal_mode 0)
		)
		(polygon
			(pts
				(xy 14.500098 -68.349876) (xy 14.500098 -82.06994) (xy 13.850112 -82.06994)
				(arc
					(start 13.850112 -84.149946)
					(mid 14.143005 -84.857051)
					(end 14.85011 -85.149944)
				)
				(arc
					(start 28.850082 -85.149944)
					(mid 29.557187 -84.857051)
					(end 29.85008 -84.149946)
				)
				(xy 29.85008 -82.06994) (xy 29.200094 -82.06994) (xy 29.200094 -68.349876)
			)
		)
	)
	(zone
		(layer "F.Cu")
		(hatch none 0.5)
		(connect_pads
			(clearance 0)
		)
		(min_thickness 0.25)
		(keepout
			(tracks allowed)
			(vias allowed)
			(pads allowed)
			(copperpour allowed)
			(footprints not_allowed)
		)
		(placement
			(enabled no)
			(sheetname "")
		)
		(fill
			(thermal_gap 0.5)
			(thermal_bridge_width 0.5)
			(island_removal_mode 0)
		)
		(polygon
			(pts
				(xy 29.560012 -24.079962) (xy 29.560012 -30.589982) (xy 14.69009 -30.589982) (xy 14.69009 -50.259996)
				(xy 38.299898 -50.259996) (xy 38.299898 -24.079962)
			)
		)
	)
	(zone
		(layer "F.Cu")
		(hatch none 0.5)
		(connect_pads
			(clearance 0)
		)
		(min_thickness 0.25)
		(keepout
			(tracks not_allowed)
			(vias allowed)
			(pads allowed)
			(copperpour not_allowed)
			(footprints allowed)
		)
		(placement
			(enabled no)
			(sheetname "")
		)
		(fill
			(thermal_gap 0.5)
			(thermal_bridge_width 0.5)
			(island_removal_mode 0)
		)
		(polygon
			(pts
				(arc
					(start 11.100054 -14.899894)
					(mid 6.100064 -19.899884)
					(end 1.100074 -14.899894)
				)
				(arc
					(start 1.100074 -14.899894)
					(mid 6.100064 -9.899904)
					(end 11.100054 -14.899894)
				)
			)
		)
		(polygon
			(pts
				(arc
					(start 8.10006 -14.899894)
					(mid 6.100064 -16.89989)
					(end 4.100068 -14.899894)
				)
				(arc
					(start 4.100068 -14.899894)
					(mid 6.100064 -12.899898)
					(end 8.10006 -14.899894)
				)
			)
		)
	)
	(zone
		(layer "F.Cu")
		(hatch none 0.5)
		(connect_pads
			(clearance 0)
		)
		(min_thickness 0.25)
		(keepout
			(tracks not_allowed)
			(vias allowed)
			(pads allowed)
			(copperpour not_allowed)
			(footprints allowed)
		)
		(placement
			(enabled no)
			(sheetname "")
		)
		(fill
			(thermal_gap 0.5)
			(thermal_bridge_width 0.5)
			(island_removal_mode 0)
		)
		(polygon
			(pts
				(arc
					(start 1.100074 -14.899894)
					(mid 6.100064 -9.899904)
					(end 11.100054 -14.899894)
				)
				(arc
					(start 11.100054 -14.899894)
					(mid 6.100064 -19.899884)
					(end 1.100074 -14.899894)
				)
			)
		)
	)
	(zone
		(layer "F.Cu")
		(hatch none 0.5)
		(connect_pads
			(clearance 0)
		)
		(min_thickness 0.25)
		(keepout
			(tracks allowed)
			(vias allowed)
			(pads allowed)
			(copperpour allowed)
			(footprints not_allowed)
		)
		(placement
			(enabled no)
			(sheetname "")
		)
		(fill
			(thermal_gap 0.5)
			(thermal_bridge_width 0.5)
			(island_removal_mode 0)
		)
		(polygon
			(pts
				(arc
					(start 38.299898 -68.68541)
					(mid 35.760051 -70.308134)
					(end 32.800036 -70.875906)
				)
				(arc
					(start 32.800036 -70.875906)
					(mid 30.949916 -70.659025)
					(end 29.200094 -70.02018)
				)
				(xy 29.200094 -82.06994) (xy 29.85008 -82.06994)
				(arc
					(start 29.85008 -82.00009)
					(mid 30.728758 -79.878774)
					(end 32.850074 -79.000096)
				)
				(arc
					(start 36.20008 -79.000096)
					(mid 36.907185 -78.707203)
					(end 37.200078 -78.000098)
				)
				(arc
					(start 37.200078 -71.949056)
					(mid 37.413957 -70.836614)
					(end 38.02507 -69.882766)
				)
				(arc
					(start 38.02507 -69.882766)
					(mid 38.228714 -69.564764)
					(end 38.299898 -69.193918)
				)
			)
		)
	)
	(zone
		(layer "F.Cu")
		(hatch none 0.5)
		(connect_pads
			(clearance 0)
		)
		(min_thickness 0.25)
		(keepout
			(tracks not_allowed)
			(vias allowed)
			(pads allowed)
			(copperpour not_allowed)
			(footprints allowed)
		)
		(placement
			(enabled no)
			(sheetname "")
		)
		(fill
			(thermal_gap 0.5)
			(thermal_bridge_width 0.5)
			(island_removal_mode 0)
		)
		(polygon
			(pts
				(arc
					(start 4.100068 -14.899894)
					(mid 6.100064 -12.899898)
					(end 8.10006 -14.899894)
				)
				(arc
					(start 8.10006 -14.899894)
					(mid 6.100064 -16.89989)
					(end 4.100068 -14.899894)
				)
			)
		)
	)
	(zone
		(layer "F.Cu")
		(hatch none 0.5)
		(connect_pads
			(clearance 0)
		)
		(min_thickness 0.25)
		(keepout
			(tracks allowed)
			(vias allowed)
			(pads allowed)
			(copperpour allowed)
			(footprints not_allowed)
		)
		(placement
			(enabled no)
			(sheetname "")
		)
		(fill
			(thermal_gap 0.5)
			(thermal_bridge_width 0.5)
			(island_removal_mode 0)
		)
		(polygon
			(pts
				(xy 14.500098 -82.06994) (xy 14.500098 -68.349876)
				(arc
					(start 26.96591 -68.349876)
					(mid 25.458604 -59.697152)
					(end 32.800036 -54.875938)
				)
				(arc
					(start 32.800036 -54.875938)
					(mid 35.760051 -55.443711)
					(end 38.299898 -57.066434)
				)
				(xy 38.299898 -50.259996) (xy 14.69009 -50.259996) (xy 14.69009 -30.589982) (xy 29.560012 -30.589982)
				(xy 29.560012 -25.550114) (xy 20.439888 -25.550114) (xy 20.439888 -8.949944)
				(arc
					(start 11.44778 -8.949944)
					(mid 13.569989 -17.763492)
					(end 6.100064 -22.899878)
				)
				(arc
					(start 6.100064 -22.899878)
					(mid 3.389793 -22.426882)
					(end 0.999998 -21.063712)
				)
				(arc
					(start 0.999998 -69.193918)
					(mid 1.071299 -69.5648)
					(end 1.27508 -69.882766)
				)
				(arc
					(start 1.27508 -69.882766)
					(mid 1.886228 -70.836601)
					(end 2.100072 -71.949056)
				)
				(arc
					(start 2.100072 -78.000098)
					(mid 2.392965 -78.707203)
					(end 3.10007 -79.000096)
				)
				(arc
					(start 10.850118 -79.000096)
					(mid 12.971434 -79.878774)
					(end 13.850112 -82.00009)
				)
				(xy 13.850112 -82.06994)
			)
		)
	)
	(zone
		(layer "F.Cu")
		(hatch none 0.5)
		(connect_pads
			(clearance 0)
		)
		(min_thickness 0.25)
		(keepout
			(tracks allowed)
			(vias allowed)
			(pads allowed)
			(copperpour allowed)
			(footprints not_allowed)
		)
		(placement
			(enabled no)
			(sheetname "")
		)
		(fill
			(thermal_gap 0.5)
			(thermal_bridge_width 0.5)
			(island_removal_mode 0)
		)
		(polygon
			(pts
				(xy 29.560012 -24.079962) (xy 38.299898 -24.079962)
				(arc
					(start 38.299898 -16.049752)
					(mid 33.825382 -18.454318)
					(end 30.599888 -14.53007)
				)
				(arc
					(start 30.599888 -11.02995)
					(mid 33.825258 -7.10568)
					(end 38.299898 -9.510014)
				)
				(arc
					(start 38.299898 -1.999996)
					(mid 38.007005 -1.292891)
					(end 37.2999 -0.999998)
				)
				(xy 29.560012 -0.999998)
			)
		)
	)
	(zone
		(layer "F.Cu")
		(hatch none 0.5)
		(connect_pads
			(clearance 0)
		)
		(min_thickness 0.25)
		(keepout
			(tracks not_allowed)
			(vias allowed)
			(pads allowed)
			(copperpour not_allowed)
			(footprints allowed)
		)
		(placement
			(enabled no)
			(sheetname "")
		)
		(fill
			(thermal_gap 0.5)
			(thermal_bridge_width 0.5)
			(island_removal_mode 0)
		)
		(polygon
			(pts
				(arc
					(start 37.800026 -62.875922)
					(mid 32.800036 -67.875912)
					(end 27.800046 -62.875922)
				)
				(arc
					(start 27.800046 -62.875922)
					(mid 32.800036 -57.875932)
					(end 37.800026 -62.875922)
				)
			)
		)
	)
	(zone
		(layer "F.Cu")
		(hatch none 0.5)
		(connect_pads
			(clearance 0)
		)
		(min_thickness 0.25)
		(keepout
			(tracks not_allowed)
			(vias allowed)
			(pads allowed)
			(copperpour not_allowed)
			(footprints allowed)
		)
		(placement
			(enabled no)
			(sheetname "")
		)
		(fill
			(thermal_gap 0.5)
			(thermal_bridge_width 0.5)
			(island_removal_mode 0)
		)
		(polygon
			(pts
				(arc
					(start 5.100066 -71.651622)
					(mid 4.985682 -72.318293)
					(end 4.655566 -72.908668)
				)
				(arc
					(start 4.655566 -72.908668)
					(mid 6.60027 -76.9804)
					(end 8.54456 -72.908668)
				)
				(arc
					(start 8.54456 -72.908668)
					(mid 8.214503 -72.318272)
					(end 8.10006 -71.651622)
				)
				(arc
					(start 8.10006 -70.980046)
					(mid 6.60019 -69.480176)
					(end 5.100066 -70.980046)
				)
			)
		)
	)
	(zone
		(layer "F.Cu")
		(hatch none 0.5)
		(connect_pads
			(clearance 0)
		)
		(min_thickness 0.25)
		(keepout
			(tracks allowed)
			(vias allowed)
			(pads allowed)
			(copperpour allowed)
			(footprints allowed)
		)
		(placement
			(enabled no)
			(sheetname "")
		)
		(fill
			(thermal_gap 0.5)
			(thermal_bridge_width 0.5)
			(island_removal_mode 0)
		)
		(polygon
			(pts
				(xy 19.7866 -70.5104) (xy 19.7866 -68.58) (xy 23.8506 -68.58) (xy 23.8506 -70.5104)
			)
		)
	)
	(zone
		(layers "F.Cu" "B.Cu")
		(hatch none 0.5)
		(connect_pads
			(clearance 0)
		)
		(min_thickness 0.25)
		(keepout
			(tracks not_allowed)
			(vias allowed)
			(pads allowed)
			(copperpour not_allowed)
			(footprints allowed)
		)
		(placement
			(enabled no)
			(sheetname "")
		)
		(fill yes
			(thermal_gap 0.5)
			(thermal_bridge_width 0.5)
			(island_removal_mode 0)
		)
		(polygon
			(pts
				(arc
					(start 10.599928 -70.980046)
					(mid 6.599936 -66.980054)
					(end 2.599944 -70.980046)
				)
				(arc
					(start 2.599944 -74.479912)
					(mid 6.599936 -78.479904)
					(end 10.599928 -74.479912)
				)
			)
		)
	)
	(zone
		(layers "F.Cu" "B.Cu")
		(hatch none 0.5)
		(connect_pads
			(clearance 0)
		)
		(min_thickness 0.25)
		(keepout
			(tracks not_allowed)
			(vias allowed)
			(pads allowed)
			(copperpour not_allowed)
			(footprints allowed)
		)
		(placement
			(enabled no)
			(sheetname "")
		)
		(fill yes
			(thermal_gap 0.5)
			(thermal_bridge_width 0.5)
			(island_removal_mode 0)
		)
		(polygon
			(pts
				(arc
					(start 38.600126 -11.02995)
					(mid 34.600134 -7.029958)
					(end 30.599888 -11.02995)
				)
				(arc
					(start 30.599888 -14.53007)
					(mid 34.600134 -18.530316)
					(end 38.600126 -14.53007)
				)
			)
		)
	)
	(zone
		(layers "F.Cu" "B.Cu")
		(hatch none 0.5)
		(connect_pads
			(clearance 0)
		)
		(min_thickness 0.25)
		(keepout
			(tracks allowed)
			(vias allowed)
			(pads allowed)
			(copperpour allowed)
			(footprints not_allowed)
		)
		(placement
			(enabled no)
			(sheetname "")
		)
		(fill yes
			(thermal_gap 0.5)
			(thermal_bridge_width 0.5)
			(island_removal_mode 0)
		)
		(polygon
			(pts
				(arc
					(start 10.599928 -70.980046)
					(mid 6.599936 -66.980054)
					(end 2.599944 -70.980046)
				)
				(arc
					(start 2.599944 -74.479912)
					(mid 6.599936 -78.479904)
					(end 10.599928 -74.479912)
				)
			)
		)
	)
	(zone
		(layers "F.Cu" "B.Cu" "In1.Cu" "In2.Cu")
		(hatch none 0.5)
		(connect_pads
			(clearance 0)
		)
		(min_thickness 0.25)
		(keepout
			(tracks not_allowed)
			(vias allowed)
			(pads allowed)
			(copperpour not_allowed)
			(footprints allowed)
		)
		(placement
			(enabled no)
			(sheetname "")
		)
		(fill
			(thermal_gap 0.5)
			(thermal_bridge_width 0.5)
			(island_removal_mode 0)
		)
		(polygon
			(pts
				(arc
					(start 23.490428 -18.32991)
					(mid 24.100028 -18.93951)
					(end 24.709628 -18.32991)
				)
				(xy 24.709374 -18.312384) (xy 24.709374 -16.34744) (xy 24.709628 -16.329914) (xy 24.709374 -16.312388)
				(xy 24.709374 -16.303244)
				(arc
					(start 24.70912 -16.303244)
					(mid 24.521599 -15.88948)
					(end 24.100028 -15.720314)
				)
				(arc
					(start 24.100028 -15.720314)
					(mid 23.678784 -15.889271)
					(end 23.490936 -16.302482)
				)
				(xy 23.490682 -16.302482) (xy 23.490682 -16.312388) (xy 23.490428 -16.329914) (xy 23.490682 -16.34744)
				(xy 23.490682 -18.312384)
			)
		)
	)
	(zone
		(layers "F.Cu" "B.Cu" "In1.Cu" "In2.Cu")
		(name "Route Keepin")
		(hatch none 0.5)
		(connect_pads
			(clearance 0)
		)
		(min_thickness 0.25)
		(keepout
			(tracks allowed)
			(vias allowed)
			(pads allowed)
			(copperpour allowed)
			(footprints allowed)
		)
		(placement
			(enabled no)
			(sheetname "")
		)
		(fill
			(thermal_gap 0.5)
			(thermal_bridge_width 0.5)
			(island_removal_mode 0)
		)
		(polygon
			(pts
				(arc
					(start 1.999996 -0.508)
					(mid 0.944996 -0.944996)
					(end 0.508 -1.999996)
				)
				(arc
					(start 0.508 -69.194426)
					(mid 0.614397 -69.747546)
					(end 0.91821 -70.221856)
				)
				(arc
					(start 0.91821 -70.221856)
					(mid 1.429134 -71.01915)
					(end 1.608074 -71.949056)
				)
				(arc
					(start 1.608074 -78.000098)
					(mid 2.04507 -79.055098)
					(end 3.10007 -79.492094)
				)
				(arc
					(start 10.849864 -79.492094)
					(mid 12.623285 -80.226669)
					(end 13.35786 -82.00009)
				)
				(arc
					(start 13.35786 -84.149946)
					(mid 13.794856 -85.204946)
					(end 14.849856 -85.641942)
				)
				(arc
					(start 28.850082 -85.641942)
					(mid 29.905082 -85.204946)
					(end 30.342078 -84.149946)
				)
				(arc
					(start 30.342078 -82.00009)
					(mid 31.076653 -80.226669)
					(end 32.850074 -79.492094)
				)
				(arc
					(start 36.20008 -79.492094)
					(mid 37.25508 -79.055098)
					(end 37.692076 -78.000098)
				)
				(arc
					(start 37.692076 -71.948802)
					(mid 37.8709 -71.01905)
					(end 38.381686 -70.221856)
				)
				(arc
					(start 38.381686 -70.221856)
					(mid 38.68554 -69.747563)
					(end 38.791896 -69.194426)
				)
				(xy 38.791896 -48.90516) (xy 38.791896 -48.382428) (xy 38.83787 -48.336454) (xy 38.84168 -48.332644)
				(xy 82.53984 -48.332644) (xy 82.54365 -48.336454) (xy 83.107784 -48.900588) (xy 83.107784 -49.529238)
				(xy 83.107784 -166.402258)
				(arc
					(start 83.107784 -172.404024)
					(mid 83.59601 -173.393211)
					(end 84.624164 -173.792896)
				)
				(arc
					(start 97.59188 -173.792896)
					(mid 98.652448 -173.353594)
					(end 99.09175 -172.293026)
				)
				(arc
					(start 99.09175 -2.008378)
					(mid 98.652448 -0.94781)
					(end 97.59188 -0.508508)
				)
				(xy 84.637118 -0.508508)
				(arc
					(start 84.620608 -0.508508)
					(mid 83.55088 -0.951604)
					(end 83.107784 -2.021332)
				)
				(xy 83.107784 -2.037842) (xy 83.107784 -47.759112) (xy 82.542888 -48.324008) (xy 82.537808 -48.329088)
				(xy 82.535522 -48.331374) (xy 38.825424 -48.331374) (xy 38.823138 -48.329088) (xy 38.791896 -48.297846)
				(xy 38.791896 -48.278796) (xy 38.791896 -47.759112)
				(arc
					(start 38.791896 -1.999996)
					(mid 38.3549 -0.944996)
					(end 37.2999 -0.508)
				)
			)
		)
	)
	(zone
		(layers "F.Cu" "B.Cu" "In1.Cu" "In2.Cu")
		(name "Package Keepin")
		(hatch none 0.5)
		(connect_pads
			(clearance 0)
		)
		(min_thickness 0.25)
		(keepout
			(tracks allowed)
			(vias allowed)
			(pads allowed)
			(copperpour allowed)
			(footprints allowed)
		)
		(placement
			(enabled no)
			(sheetname "")
		)
		(fill
			(thermal_gap 0.5)
			(thermal_bridge_width 0.5)
			(island_removal_mode 0)
		)
		(polygon
			(pts
				(arc
					(start 83.615784 -172.379386)
					(mid 83.946525 -173.025295)
					(end 84.624164 -173.284896)
				)
				(arc
					(start 97.583752 -173.284896)
					(mid 98.290857 -172.992003)
					(end 98.58375 -172.284898)
				)
				(xy 98.58375 -67.691) (xy 98.806 -67.46875) (xy 98.806 -61.341) (xy 98.58375 -61.11875) (xy 98.58375 -25.4)
				(xy 98.806 -25.17775) (xy 98.806 -19.812) (xy 98.58375 -19.58975)
				(arc
					(start 98.58375 -2.016506)
					(mid 98.290857 -1.309401)
					(end 97.583752 -1.016508)
				)
				(xy 84.634324 -1.016508) (xy 84.621878 -1.016508)
				(arc
					(start 84.620608 -1.016508)
					(mid 83.91009 -1.310814)
					(end 83.615784 -2.021332)
				)
				(xy 83.615784 -2.022602) (xy 83.615784 -2.035048) (xy 83.615784 -2.036572) (xy 83.615784 -48.267112)
				(xy 83.553554 -48.329342) (xy 83.551268 -48.331628) (xy 38.288214 -48.331628) (xy 38.283896 -48.32731)
				(xy 38.283896 -48.322738) (xy 38.283896 -48.267112)
				(arc
					(start 38.283896 -1.999996)
					(mid 37.99569 -1.304206)
					(end 37.2999 -1.016)
				)
				(arc
					(start 1.999996 -1.016)
					(mid 1.304206 -1.304206)
					(end 1.016 -1.999996)
				)
				(arc
					(start 1.016 -69.194426)
					(mid 1.086117 -69.559268)
					(end 1.28651 -69.872098)
				)
				(arc
					(start 1.28651 -69.872098)
					(mid 1.900936 -70.830839)
					(end 2.116074 -71.949056)
				)
				(arc
					(start 2.116074 -78.000098)
					(mid 2.40428 -78.695888)
					(end 3.10007 -78.984094)
				)
				(arc
					(start 10.849864 -78.984094)
					(mid 12.982495 -79.867459)
					(end 13.86586 -82.00009)
				)
				(arc
					(start 13.86586 -84.149946)
					(mid 14.154066 -84.845736)
					(end 14.849856 -85.133942)
				)
				(arc
					(start 28.850082 -85.133942)
					(mid 29.545872 -84.845736)
					(end 29.834078 -84.149946)
				)
				(arc
					(start 29.834078 -82.00009)
					(mid 30.717443 -79.867459)
					(end 32.850074 -78.984094)
				)
				(arc
					(start 36.20008 -78.984094)
					(mid 36.89587 -78.695888)
					(end 37.184076 -78.000098)
				)
				(arc
					(start 37.184076 -71.948802)
					(mid 37.39918 -70.830772)
					(end 38.013386 -69.872098)
				)
				(arc
					(start 38.013386 -69.872098)
					(mid 38.213739 -69.559252)
					(end 38.283896 -69.194426)
				)
				(xy 38.283896 -48.39716) (xy 38.283896 -48.338994) (xy 38.2905 -48.33239) (xy 83.551522 -48.33239)
				(xy 83.615784 -48.396652) (xy 83.615784 -49.318926)
			)
		)
	)
	(zone
		(layer "B.Cu")
		(hatch none 0.5)
		(connect_pads
			(clearance 0)
		)
		(min_thickness 0.25)
		(keepout
			(tracks allowed)
			(vias allowed)
			(pads allowed)
			(copperpour allowed)
			(footprints not_allowed)
		)
		(placement
			(enabled no)
			(sheetname "")
		)
		(fill
			(thermal_gap 0.5)
			(thermal_bridge_width 0.5)
			(island_removal_mode 0)
		)
		(polygon
			(pts
				(xy 1.895094 -4.400042) (xy 1.895094 -5.80009) (xy 11.884914 -5.80009) (xy 11.884914 -4.400042)
			)
		)
	)
	(zone
		(layer "B.Cu")
		(hatch none 0.5)
		(connect_pads
			(clearance 0)
		)
		(min_thickness 0.25)
		(keepout
			(tracks allowed)
			(vias allowed)
			(pads allowed)
			(copperpour allowed)
			(footprints not_allowed)
		)
		(placement
			(enabled no)
			(sheetname "")
		)
		(fill
			(thermal_gap 0.5)
			(thermal_bridge_width 0.5)
			(island_removal_mode 0)
		)
		(polygon
			(pts
				(arc
					(start 27.800046 -66.376042)
					(mid 32.800036 -71.376032)
					(end 37.800026 -66.376042)
				)
				(arc
					(start 37.800026 -62.875922)
					(mid 32.800036 -57.875932)
					(end 27.800046 -62.875922)
				)
			)
		)
	)
	(zone
		(layer "B.Cu")
		(hatch none 0.5)
		(connect_pads
			(clearance 0)
		)
		(min_thickness 0.25)
		(keepout
			(tracks allowed)
			(vias allowed)
			(pads allowed)
			(copperpour allowed)
			(footprints not_allowed)
		)
		(placement
			(enabled no)
			(sheetname "")
		)
		(fill
			(thermal_gap 0.5)
			(thermal_bridge_width 0.5)
			(island_removal_mode 0)
		)
		(polygon
			(pts
				(xy 28.360116 -24.299926) (xy 28.360116 -10.40003) (xy 21.640038 -10.40003) (xy 21.640038 -24.299926)
			)
		)
	)
	(zone
		(layer "B.Cu")
		(hatch none 0.5)
		(connect_pads
			(clearance 0)
		)
		(min_thickness 0.25)
		(keepout
			(tracks allowed)
			(vias allowed)
			(pads allowed)
			(copperpour allowed)
			(footprints not_allowed)
		)
		(placement
			(enabled no)
			(sheetname "")
		)
		(fill
			(thermal_gap 0.5)
			(thermal_bridge_width 0.5)
			(island_removal_mode 0)
		)
		(polygon
			(pts
				(xy 1.895094 -3.990086) (xy 1.895094 -5.38988) (xy 11.884914 -5.38988) (xy 11.884914 -3.990086)
			)
		)
	)
	(zone
		(layer "B.Cu")
		(hatch none 0.5)
		(connect_pads
			(clearance 0)
		)
		(min_thickness 0.25)
		(keepout
			(tracks allowed)
			(vias allowed)
			(pads allowed)
			(copperpour allowed)
			(footprints not_allowed)
		)
		(placement
			(enabled no)
			(sheetname "")
		)
		(fill
			(thermal_gap 0.5)
			(thermal_bridge_width 0.5)
			(island_removal_mode 0)
		)
		(polygon
			(pts
				(xy 13.850112 -5.929884) (xy 13.850112 -7.430008) (xy 20.429982 -7.430008) (xy 20.429982 -5.929884)
			)
		)
	)
	(zone
		(layer "B.Cu")
		(hatch none 0.5)
		(connect_pads
			(clearance 0)
		)
		(min_thickness 0.25)
		(keepout
			(tracks allowed)
			(vias allowed)
			(pads allowed)
			(copperpour allowed)
			(footprints not_allowed)
		)
		(placement
			(enabled no)
			(sheetname "")
		)
		(fill
			(thermal_gap 0.5)
			(thermal_bridge_width 0.5)
			(island_removal_mode 0)
		)
		(polygon
			(pts
				(xy 15.055088 -79.43596) (xy 15.055088 -83.637882) (xy 28.645104 -83.637882) (xy 28.645104 -79.43596)
			)
		)
	)
	(zone
		(layer "B.Cu")
		(hatch none 0.5)
		(connect_pads
			(clearance 0)
		)
		(min_thickness 0.25)
		(keepout
			(tracks allowed)
			(vias allowed)
			(pads allowed)
			(copperpour allowed)
			(footprints not_allowed)
		)
		(placement
			(enabled no)
			(sheetname "")
		)
		(fill
			(thermal_gap 0.5)
			(thermal_bridge_width 0.5)
			(island_removal_mode 0)
		)
		(polygon
			(pts
				(xy 11.884914 -5.80009) (xy 11.884914 -4.400042) (xy 1.895094 -4.400042) (xy 1.895094 -5.80009)
			)
		)
	)
	(zone
		(layer "B.Cu")
		(hatch none 0.5)
		(connect_pads
			(clearance 0)
		)
		(min_thickness 0.25)
		(keepout
			(tracks not_allowed)
			(vias allowed)
			(pads allowed)
			(copperpour not_allowed)
			(footprints allowed)
		)
		(placement
			(enabled no)
			(sheetname "")
		)
		(fill
			(thermal_gap 0.5)
			(thermal_bridge_width 0.5)
			(island_removal_mode 0)
		)
		(polygon
			(pts
				(arc
					(start 11.582654 -14.900148)
					(mid 9.969401 -11.005411)
					(end 6.074664 -9.392158)
				)
				(arc
					(start 6.074664 -9.874758)
					(mid 9.628151 -11.346661)
					(end 11.100054 -14.900148)
				)
				(arc
					(start 11.100054 -18.400268)
					(mid 9.628151 -21.953755)
					(end 6.074664 -23.425658)
				)
				(arc
					(start 6.074664 -23.908258)
					(mid 9.969401 -22.295005)
					(end 11.582654 -18.400268)
				)
			)
		)
	)
	(zone
		(layer "B.Cu")
		(hatch none 0.5)
		(connect_pads
			(clearance 0)
		)
		(min_thickness 0.25)
		(keepout
			(tracks allowed)
			(vias allowed)
			(pads allowed)
			(copperpour allowed)
			(footprints not_allowed)
		)
		(placement
			(enabled no)
			(sheetname "")
		)
		(fill
			(thermal_gap 0.5)
			(thermal_bridge_width 0.5)
			(island_removal_mode 0)
		)
		(polygon
			(pts
				(arc
					(start 38.299898 -1.999996)
					(mid 38.007005 -1.292891)
					(end 37.2999 -0.999998)
				)
				(arc
					(start 1.999996 -0.999998)
					(mid 1.292891 -1.292891)
					(end 0.999998 -1.999996)
				)
				(arc
					(start 0.999998 -69.193918)
					(mid 1.071299 -69.5648)
					(end 1.27508 -69.882766)
				)
				(arc
					(start 1.27508 -69.882766)
					(mid 1.886228 -70.836601)
					(end 2.100072 -71.949056)
				)
				(arc
					(start 2.100072 -78.000098)
					(mid 2.392965 -78.707203)
					(end 3.10007 -79.000096)
				)
				(arc
					(start 10.850118 -79.000096)
					(mid 12.971434 -79.878774)
					(end 13.850112 -82.00009)
				)
				(arc
					(start 13.850112 -84.149946)
					(mid 14.143005 -84.857051)
					(end 14.85011 -85.149944)
				)
				(arc
					(start 28.850082 -85.149944)
					(mid 29.557187 -84.857051)
					(end 29.85008 -84.149946)
				)
				(arc
					(start 29.85008 -82.00009)
					(mid 30.728758 -79.878774)
					(end 32.850074 -79.000096)
				)
				(arc
					(start 36.20008 -79.000096)
					(mid 36.907185 -78.707203)
					(end 37.200078 -78.000098)
				)
				(arc
					(start 37.200078 -71.949056)
					(mid 37.413957 -70.836614)
					(end 38.02507 -69.882766)
				)
				(arc
					(start 38.02507 -69.882766)
					(mid 38.228714 -69.564764)
					(end 38.299898 -69.193918)
				)
				(arc
					(start 38.299898 -16.049752)
					(mid 33.825382 -18.454318)
					(end 30.599888 -14.53007)
				)
				(arc
					(start 30.599888 -11.02995)
					(mid 33.825258 -7.10568)
					(end 38.299898 -9.510014)
				)
			)
		)
	)
	(zone
		(layer "B.Cu")
		(hatch none 0.5)
		(connect_pads
			(clearance 0)
		)
		(min_thickness 0.25)
		(keepout
			(tracks allowed)
			(vias allowed)
			(pads allowed)
			(copperpour allowed)
			(footprints not_allowed)
		)
		(placement
			(enabled no)
			(sheetname "")
		)
		(fill
			(thermal_gap 0.5)
			(thermal_bridge_width 0.5)
			(island_removal_mode 0)
		)
		(polygon
			(pts
				(arc
					(start 1.100074 -18.400014)
					(mid 6.100064 -23.400004)
					(end 11.100054 -18.400014)
				)
				(arc
					(start 11.100054 -14.899894)
					(mid 6.100064 -9.899904)
					(end 1.100074 -14.899894)
				)
			)
		)
	)
	(zone
		(layer "B.Cu")
		(hatch none 0.5)
		(connect_pads
			(clearance 0)
		)
		(min_thickness 0.25)
		(keepout
			(tracks not_allowed)
			(vias allowed)
			(pads allowed)
			(copperpour not_allowed)
			(footprints allowed)
		)
		(placement
			(enabled no)
			(sheetname "")
		)
		(fill
			(thermal_gap 0.5)
			(thermal_bridge_width 0.5)
			(island_removal_mode 0)
		)
		(polygon
			(pts
				(arc
					(start 34.800032 -62.875922)
					(mid 32.800036 -60.875926)
					(end 30.80004 -62.875922)
				)
				(arc
					(start 30.80004 -62.875922)
					(mid 32.800036 -64.875918)
					(end 34.800032 -62.875922)
				)
			)
		)
	)
	(zone
		(layer "B.Cu")
		(hatch none 0.5)
		(connect_pads
			(clearance 0)
		)
		(min_thickness 0.25)
		(keepout
			(tracks not_allowed)
			(vias allowed)
			(pads allowed)
			(copperpour not_allowed)
			(footprints allowed)
		)
		(placement
			(enabled no)
			(sheetname "")
		)
		(fill
			(thermal_gap 0.5)
			(thermal_bridge_width 0.5)
			(island_removal_mode 0)
		)
		(polygon
			(pts
				(arc
					(start 27.800046 -66.376042)
					(mid 32.800036 -71.376032)
					(end 37.800026 -66.376042)
				)
				(arc
					(start 37.800026 -62.875922)
					(mid 32.800036 -57.875932)
					(end 27.800046 -62.875922)
				)
			)
		)
	)
	(zone
		(layer "B.Cu")
		(hatch none 0.5)
		(connect_pads
			(clearance 0)
		)
		(min_thickness 0.25)
		(keepout
			(tracks not_allowed)
			(vias allowed)
			(pads allowed)
			(copperpour not_allowed)
			(footprints allowed)
		)
		(placement
			(enabled no)
			(sheetname "")
		)
		(fill
			(thermal_gap 0.5)
			(thermal_bridge_width 0.5)
			(island_removal_mode 0)
		)
		(polygon
			(pts
				(arc
					(start 11.599926 -70.980046)
					(mid 6.599936 -65.980056)
					(end 1.599946 -70.980046)
				)
				(arc
					(start 1.599946 -74.479912)
					(mid 6.599936 -79.479902)
					(end 11.599926 -74.479912)
				)
			)
		)
		(polygon
			(pts
				(arc
					(start 8.599932 -70.980046)
					(mid 6.599936 -68.98005)
					(end 4.59994 -70.980046)
				)
				(arc
					(start 4.59994 -70.980046)
					(mid 6.599936 -72.980042)
					(end 8.599932 -70.980046)
				)
			)
		)
	)
	(zone
		(layer "B.Cu")
		(hatch none 0.5)
		(connect_pads
			(clearance 0)
		)
		(min_thickness 0.25)
		(keepout
			(tracks not_allowed)
			(vias allowed)
			(pads allowed)
			(copperpour not_allowed)
			(footprints allowed)
		)
		(placement
			(enabled no)
			(sheetname "")
		)
		(fill
			(thermal_gap 0.5)
			(thermal_bridge_width 0.5)
			(island_removal_mode 0)
		)
		(polygon
			(pts
				(arc
					(start 0.566674 -14.900148)
					(mid 2.179927 -11.005411)
					(end 6.074664 -9.392158)
				)
				(arc
					(start 6.074664 -9.874758)
					(mid 2.521177 -11.346661)
					(end 1.049274 -14.900148)
				)
				(arc
					(start 1.049274 -18.400268)
					(mid 2.521177 -21.953755)
					(end 6.074664 -23.425658)
				)
				(arc
					(start 6.074664 -23.908258)
					(mid 2.179927 -22.295005)
					(end 0.566674 -18.400268)
				)
			)
		)
	)
	(zone
		(layer "B.Cu")
		(hatch none 0.5)
		(connect_pads
			(clearance 0)
		)
		(min_thickness 0.25)
		(keepout
			(tracks not_allowed)
			(vias allowed)
			(pads allowed)
			(copperpour not_allowed)
			(footprints allowed)
		)
		(placement
			(enabled no)
			(sheetname "")
		)
		(fill
			(thermal_gap 0.5)
			(thermal_bridge_width 0.5)
			(island_removal_mode 0)
		)
		(polygon
			(pts
				(arc
					(start 11.100054 -14.900148)
					(mid 6.100064 -9.900158)
					(end 1.100074 -14.900148)
				)
				(arc
					(start 1.100074 -18.400014)
					(mid 6.100064 -23.400004)
					(end 11.100054 -18.400014)
				)
			)
		)
		(polygon
			(pts
				(arc
					(start 8.10006 -14.900148)
					(mid 6.100064 -12.900152)
					(end 4.100068 -14.900148)
				)
				(arc
					(start 4.100068 -14.900148)
					(mid 6.100064 -16.900144)
					(end 8.10006 -14.900148)
				)
			)
		)
	)
	(zone
		(layer "B.Cu")
		(hatch none 0.5)
		(connect_pads
			(clearance 0)
		)
		(min_thickness 0.25)
		(keepout
			(tracks not_allowed)
			(vias allowed)
			(pads allowed)
			(copperpour not_allowed)
			(footprints allowed)
		)
		(placement
			(enabled no)
			(sheetname "")
		)
		(fill
			(thermal_gap 0.5)
			(thermal_bridge_width 0.5)
			(island_removal_mode 0)
		)
		(polygon
			(pts
				(arc
					(start 8.54456 -72.908668)
					(mid 8.214503 -72.318272)
					(end 8.10006 -71.651622)
				)
				(arc
					(start 8.10006 -70.980046)
					(mid 6.60019 -69.480176)
					(end 5.100066 -70.980046)
				)
				(arc
					(start 5.100066 -71.651622)
					(mid 4.985682 -72.318293)
					(end 4.655566 -72.908668)
				)
				(arc
					(start 4.655566 -72.908668)
					(mid 6.60027 -76.9804)
					(end 8.54456 -72.908668)
				)
			)
		)
	)
	(zone
		(layer "B.Cu")
		(hatch none 0.5)
		(connect_pads
			(clearance 0)
		)
		(min_thickness 0.25)
		(keepout
			(tracks not_allowed)
			(vias allowed)
			(pads allowed)
			(copperpour not_allowed)
			(footprints allowed)
		)
		(placement
			(enabled no)
			(sheetname "")
		)
		(fill
			(thermal_gap 0.5)
			(thermal_bridge_width 0.5)
			(island_removal_mode 0)
		)
		(polygon
			(pts
				(arc
					(start 8.10006 -14.899894)
					(mid 6.100064 -12.899898)
					(end 4.100068 -14.899894)
				)
				(arc
					(start 4.100068 -14.899894)
					(mid 6.100064 -16.89989)
					(end 8.10006 -14.899894)
				)
			)
		)
	)
	(zone
		(layer "B.Cu")
		(hatch none 0.5)
		(connect_pads
			(clearance 0)
		)
		(min_thickness 0.25)
		(keepout
			(tracks allowed)
			(vias allowed)
			(pads allowed)
			(copperpour allowed)
			(footprints not_allowed)
		)
		(placement
			(enabled no)
			(sheetname "")
		)
		(fill
			(thermal_gap 0.5)
			(thermal_bridge_width 0.5)
			(island_removal_mode 0)
		)
		(polygon
			(pts
				(xy 28.645104 -79.43596) (xy 15.055088 -79.43596) (xy 15.055088 -83.637882) (xy 28.645104 -83.637882)
			)
		)
	)
	(zone
		(layer "B.Cu")
		(hatch none 0.5)
		(connect_pads
			(clearance 0)
		)
		(min_thickness 0.25)
		(keepout
			(tracks allowed)
			(vias allowed)
			(pads allowed)
			(copperpour allowed)
			(footprints not_allowed)
		)
		(placement
			(enabled no)
			(sheetname "")
		)
		(fill
			(thermal_gap 0.5)
			(thermal_bridge_width 0.5)
			(island_removal_mode 0)
		)
		(polygon
			(pts
				(xy 21.640038 -10.40003) (xy 21.640038 -24.299926) (xy 28.360116 -24.299926) (xy 28.360116 -10.40003)
			)
		)
	)
	(zone
		(layer "B.Cu")
		(hatch none 0.5)
		(connect_pads
			(clearance 0)
		)
		(min_thickness 0.25)
		(keepout
			(tracks allowed)
			(vias allowed)
			(pads allowed)
			(copperpour allowed)
			(footprints not_allowed)
		)
		(placement
			(enabled no)
			(sheetname "")
		)
		(fill
			(thermal_gap 0.5)
			(thermal_bridge_width 0.5)
			(island_removal_mode 0)
		)
		(polygon
			(pts
				(xy 11.884914 -5.38988) (xy 11.884914 -3.990086) (xy 1.895094 -3.990086) (xy 1.895094 -5.38988)
			)
		)
	)
	(zone
		(layer "B.Cu")
		(hatch none 0.5)
		(connect_pads
			(clearance 0)
		)
		(min_thickness 0.25)
		(keepout
			(tracks not_allowed)
			(vias allowed)
			(pads allowed)
			(copperpour not_allowed)
			(footprints allowed)
		)
		(placement
			(enabled no)
			(sheetname "")
		)
		(fill
			(thermal_gap 0.5)
			(thermal_bridge_width 0.5)
			(island_removal_mode 0)
		)
		(polygon
			(pts
				(arc
					(start 36.544504 -12.958572)
					(mid 36.214447 -12.368176)
					(end 36.100004 -11.701526)
				)
				(arc
					(start 36.100004 -11.02995)
					(mid 34.600134 -9.53008)
					(end 33.10001 -11.02995)
				)
				(arc
					(start 33.10001 -11.701526)
					(mid 32.985626 -12.368197)
					(end 32.65551 -12.958572)
				)
				(arc
					(start 32.65551 -12.958572)
					(mid 34.600214 -17.030304)
					(end 36.544504 -12.958572)
				)
			)
		)
	)
	(zone
		(layer "B.Cu")
		(hatch none 0.5)
		(connect_pads
			(clearance 0)
		)
		(min_thickness 0.25)
		(keepout
			(tracks not_allowed)
			(vias allowed)
			(pads allowed)
			(copperpour not_allowed)
			(footprints allowed)
		)
		(placement
			(enabled no)
			(sheetname "")
		)
		(fill
			(thermal_gap 0.5)
			(thermal_bridge_width 0.5)
			(island_removal_mode 0)
		)
		(polygon
			(pts
				(arc
					(start 1.100074 -18.400014)
					(mid 6.100064 -23.400004)
					(end 11.100054 -18.400014)
				)
				(arc
					(start 11.100054 -14.899894)
					(mid 6.100064 -9.899904)
					(end 1.100074 -14.899894)
				)
			)
		)
	)
	(zone
		(layer "In1.Cu")
		(hatch none 0.5)
		(connect_pads
			(clearance 0)
		)
		(min_thickness 0.25)
		(keepout
			(tracks not_allowed)
			(vias allowed)
			(pads allowed)
			(copperpour not_allowed)
			(footprints allowed)
		)
		(placement
			(enabled no)
			(sheetname "")
		)
		(fill
			(thermal_gap 0.5)
			(thermal_bridge_width 0.5)
			(island_removal_mode 0)
		)
		(polygon
			(pts
				(arc
					(start 30.243526 -20.823936)
					(mid 30.250965 -20.805975)
					(end 30.268926 -20.798536)
				)
				(arc
					(start 30.959806 -20.798536)
					(mid 30.977767 -20.805975)
					(end 30.985206 -20.823936)
				)
				(arc
					(start 30.985206 -21.404834)
					(mid 30.977767 -21.422795)
					(end 30.959806 -21.430234)
				)
				(arc
					(start 30.268926 -21.430234)
					(mid 30.250965 -21.422795)
					(end 30.243526 -21.404834)
				)
			)
		)
	)
	(zone
		(layer "In1.Cu")
		(hatch none 0.5)
		(connect_pads
			(clearance 0)
		)
		(min_thickness 0.25)
		(keepout
			(tracks not_allowed)
			(vias allowed)
			(pads allowed)
			(copperpour not_allowed)
			(footprints allowed)
		)
		(placement
			(enabled no)
			(sheetname "")
		)
		(fill
			(thermal_gap 0.5)
			(thermal_bridge_width 0.5)
			(island_removal_mode 0)
		)
		(polygon
			(pts
				(arc
					(start 30.90164 -23.988522)
					(mid 30.909079 -23.970561)
					(end 30.92704 -23.963122)
				)
				(arc
					(start 31.42869 -23.963122)
					(mid 31.446651 -23.970561)
					(end 31.45409 -23.988522)
				)
				(arc
					(start 31.45409 -25.163272)
					(mid 31.446651 -25.181233)
					(end 31.42869 -25.188672)
				)
				(arc
					(start 30.92704 -25.188672)
					(mid 30.909079 -25.181233)
					(end 30.90164 -25.163272)
				)
			)
		)
	)
	(zone
		(layer "In1.Cu")
		(hatch none 0.5)
		(connect_pads
			(clearance 0)
		)
		(min_thickness 0.25)
		(keepout
			(tracks not_allowed)
			(vias allowed)
			(pads allowed)
			(copperpour not_allowed)
			(footprints allowed)
		)
		(placement
			(enabled no)
			(sheetname "")
		)
		(fill
			(thermal_gap 0.5)
			(thermal_bridge_width 0.5)
			(island_removal_mode 0)
		)
		(polygon
			(pts
				(arc
					(start 25.85085 -69.139562)
					(mid 25.858289 -69.121601)
					(end 25.87625 -69.114162)
				)
				(arc
					(start 26.834592 -69.114162)
					(mid 26.852553 -69.121601)
					(end 26.859992 -69.139562)
				)
				(arc
					(start 26.859992 -70.45833)
					(mid 26.852553 -70.476291)
					(end 26.834592 -70.48373)
				)
				(arc
					(start 25.87625 -70.48373)
					(mid 25.858289 -70.476291)
					(end 25.85085 -70.45833)
				)
			)
		)
	)
	(zone
		(layer "In1.Cu")
		(hatch none 0.5)
		(connect_pads
			(clearance 0)
		)
		(min_thickness 0.25)
		(keepout
			(tracks not_allowed)
			(vias allowed)
			(pads allowed)
			(copperpour not_allowed)
			(footprints allowed)
		)
		(placement
			(enabled no)
			(sheetname "")
		)
		(fill
			(thermal_gap 0.5)
			(thermal_bridge_width 0.5)
			(island_removal_mode 0)
		)
		(polygon
			(pts
				(arc
					(start 31.751524 -23.988522)
					(mid 31.758963 -23.970561)
					(end 31.776924 -23.963122)
				)
				(arc
					(start 32.278574 -23.963122)
					(mid 32.296535 -23.970561)
					(end 32.303974 -23.988522)
				)
				(arc
					(start 32.303974 -25.163272)
					(mid 32.296535 -25.181233)
					(end 32.278574 -25.188672)
				)
				(arc
					(start 31.776924 -25.188672)
					(mid 31.758963 -25.181233)
					(end 31.751524 -25.163272)
				)
			)
		)
	)
	(zone
		(layer "In1.Cu")
		(hatch none 0.5)
		(connect_pads
			(clearance 0)
		)
		(min_thickness 0.25)
		(keepout
			(tracks not_allowed)
			(vias allowed)
			(pads allowed)
			(copperpour not_allowed)
			(footprints allowed)
		)
		(placement
			(enabled no)
			(sheetname "")
		)
		(fill
			(thermal_gap 0.5)
			(thermal_bridge_width 0.5)
			(island_removal_mode 0)
		)
		(polygon
			(pts
				(arc
					(start 95.7961 -154.080464)
					(mid 95.849982 -154.102782)
					(end 95.8723 -154.156664)
				)
				(arc
					(start 95.8723 -154.768804)
					(mid 95.849982 -154.822686)
					(end 95.7961 -154.845004)
				)
				(arc
					(start 94.69882 -154.845004)
					(mid 94.644938 -154.822686)
					(end 94.62262 -154.768804)
				)
				(arc
					(start 94.62262 -154.156664)
					(mid 94.644938 -154.102782)
					(end 94.69882 -154.080464)
				)
			)
		)
	)
	(zone
		(layer "In1.Cu")
		(hatch none 0.5)
		(connect_pads
			(clearance 0)
		)
		(min_thickness 0.25)
		(keepout
			(tracks not_allowed)
			(vias allowed)
			(pads allowed)
			(copperpour not_allowed)
			(footprints allowed)
		)
		(placement
			(enabled no)
			(sheetname "")
		)
		(fill
			(thermal_gap 0.5)
			(thermal_bridge_width 0.5)
			(island_removal_mode 0)
		)
		(polygon
			(pts
				(arc
					(start 88.3031 -154.080464)
					(mid 88.356982 -154.102782)
					(end 88.3793 -154.156664)
				)
				(arc
					(start 88.3793 -154.768804)
					(mid 88.356982 -154.822686)
					(end 88.3031 -154.845004)
				)
				(arc
					(start 87.20582 -154.845004)
					(mid 87.151938 -154.822686)
					(end 87.12962 -154.768804)
				)
				(arc
					(start 87.12962 -154.156664)
					(mid 87.151938 -154.102782)
					(end 87.20582 -154.080464)
				)
			)
		)
	)
	(zone
		(layer "In1.Cu")
		(hatch none 0.5)
		(connect_pads
			(clearance 0)
		)
		(min_thickness 0.25)
		(keepout
			(tracks not_allowed)
			(vias allowed)
			(pads allowed)
			(copperpour not_allowed)
			(footprints allowed)
		)
		(placement
			(enabled no)
			(sheetname "")
		)
		(fill
			(thermal_gap 0.5)
			(thermal_bridge_width 0.5)
			(island_removal_mode 0)
		)
		(polygon
			(pts
				(arc
					(start 31.77159 -22.526752)
					(mid 31.779029 -22.508791)
					(end 31.79699 -22.501352)
				)
				(arc
					(start 32.271716 -22.501352)
					(mid 32.289677 -22.508791)
					(end 32.297116 -22.526752)
				)
				(arc
					(start 32.297116 -23.616412)
					(mid 32.289677 -23.634373)
					(end 32.271716 -23.641812)
				)
				(arc
					(start 31.79699 -23.641812)
					(mid 31.779029 -23.634373)
					(end 31.77159 -23.616412)
				)
			)
		)
	)
	(zone
		(layer "In1.Cu")
		(hatch none 0.5)
		(connect_pads
			(clearance 0)
		)
		(min_thickness 0.25)
		(keepout
			(tracks not_allowed)
			(vias allowed)
			(pads allowed)
			(copperpour not_allowed)
			(footprints allowed)
		)
		(placement
			(enabled no)
			(sheetname "")
		)
		(fill
			(thermal_gap 0.5)
			(thermal_bridge_width 0.5)
			(island_removal_mode 0)
		)
		(polygon
			(pts
				(arc
					(start 94.7039 -84.34578)
					(mid 94.650018 -84.323462)
					(end 94.6277 -84.26958)
				)
				(arc
					(start 94.6277 -83.65744)
					(mid 94.650018 -83.603558)
					(end 94.7039 -83.58124)
				)
				(arc
					(start 95.80118 -83.58124)
					(mid 95.855062 -83.603558)
					(end 95.87738 -83.65744)
				)
				(arc
					(start 95.87738 -84.26958)
					(mid 95.855062 -84.323462)
					(end 95.80118 -84.34578)
				)
			)
		)
	)
	(zone
		(layer "In1.Cu")
		(hatch none 0.5)
		(connect_pads
			(clearance 0)
		)
		(min_thickness 0.25)
		(keepout
			(tracks not_allowed)
			(vias allowed)
			(pads allowed)
			(copperpour not_allowed)
			(footprints allowed)
		)
		(placement
			(enabled no)
			(sheetname "")
		)
		(fill
			(thermal_gap 0.5)
			(thermal_bridge_width 0.5)
			(island_removal_mode 0)
		)
		(polygon
			(pts
				(arc
					(start 32.243522 -20.823936)
					(mid 32.250961 -20.805975)
					(end 32.268922 -20.798536)
				)
				(arc
					(start 32.959802 -20.798536)
					(mid 32.977763 -20.805975)
					(end 32.985202 -20.823936)
				)
				(arc
					(start 32.985202 -21.404834)
					(mid 32.977763 -21.422795)
					(end 32.959802 -21.430234)
				)
				(arc
					(start 32.268922 -21.430234)
					(mid 32.250961 -21.422795)
					(end 32.243522 -21.404834)
				)
			)
		)
	)
	(zone
		(layer "In1.Cu")
		(hatch none 0.5)
		(connect_pads
			(clearance 0)
		)
		(min_thickness 0.25)
		(keepout
			(tracks not_allowed)
			(vias allowed)
			(pads allowed)
			(copperpour not_allowed)
			(footprints allowed)
		)
		(placement
			(enabled no)
			(sheetname "")
		)
		(fill
			(thermal_gap 0.5)
			(thermal_bridge_width 0.5)
			(island_removal_mode 0)
		)
		(polygon
			(pts
				(arc
					(start 30.921706 -22.526752)
					(mid 30.929145 -22.508791)
					(end 30.947106 -22.501352)
				)
				(arc
					(start 31.421832 -22.501352)
					(mid 31.439793 -22.508791)
					(end 31.447232 -22.526752)
				)
				(arc
					(start 31.447232 -23.616412)
					(mid 31.439793 -23.634373)
					(end 31.421832 -23.641812)
				)
				(arc
					(start 30.947106 -23.641812)
					(mid 30.929145 -23.634373)
					(end 30.921706 -23.616412)
				)
			)
		)
	)
	(zone
		(layer "In1.Cu")
		(hatch none 0.5)
		(connect_pads
			(clearance 0)
		)
		(min_thickness 0.25)
		(keepout
			(tracks not_allowed)
			(vias allowed)
			(pads allowed)
			(copperpour not_allowed)
			(footprints allowed)
		)
		(placement
			(enabled no)
			(sheetname "")
		)
		(fill
			(thermal_gap 0.5)
			(thermal_bridge_width 0.5)
			(island_removal_mode 0)
		)
		(polygon
			(pts
				(arc
					(start 87.2109 -110.714536)
					(mid 87.157018 -110.692218)
					(end 87.1347 -110.638336)
				)
				(arc
					(start 87.1347 -110.026196)
					(mid 87.157018 -109.972314)
					(end 87.2109 -109.949996)
				)
				(arc
					(start 88.30818 -109.949996)
					(mid 88.362062 -109.972314)
					(end 88.38438 -110.026196)
				)
				(arc
					(start 88.38438 -110.638336)
					(mid 88.362062 -110.692218)
					(end 88.30818 -110.714536)
				)
			)
		)
	)
)
